(kicad_pcb
	(version 20260206)
	(generator "pcbnew")
	(generator_version "10.0")
	(general
		(thickness 1.6)
		(legacy_teardrops no)
	)
	(paper "A4")
	(layers
		(0 "F.Cu" signal "TOP")
		(4 "In1.Cu" signal "L2GND")
		(6 "In2.Cu" signal "L3")
		(8 "In3.Cu" signal "L4VCC")
		(10 "In4.Cu" signal "L5VCC")
		(12 "In5.Cu" signal "L6")
		(14 "In6.Cu" signal "L7GND")
		(2 "B.Cu" signal "BOTTOM")
		(9 "F.Adhes" user "F.Adhesive")
		(11 "B.Adhes" user "B.Adhesive")
		(13 "F.Paste" user "Package Geometry/Pastemask Top")
		(15 "B.Paste" user "Package Geometry/Pastemask Bottom")
		(5 "F.SilkS" user "Ref Des/Silkscreen Top")
		(7 "B.SilkS" user "Ref Des/Silkscreen Bottom")
		(1 "F.Mask" user "Board Geometry/Soldermask Top")
		(3 "B.Mask" user "Board Geometry/Soldermask Bottom")
		(17 "Dwgs.User" user "User.Drawings")
		(19 "Cmts.User" user "User.Comments")
		(21 "Eco1.User" user "User.Eco1")
		(23 "Eco2.User" user "User.Eco2")
		(25 "Edge.Cuts" user "Board Geometry/Outline")
		(27 "Margin" user)
		(31 "F.CrtYd" user "Package Geometry/Place Bound Top")
		(29 "B.CrtYd" user "Package Geometry/Place Bound Bottom")
		(35 "F.Fab" user "Ref Des/Assembly Top")
		(33 "B.Fab" user "Ref Des/Assembly Bottom")
	)
	(setup
		(pad_to_mask_clearance 0)
		(allow_soldermask_bridges_in_footprints no)
		(tenting
			(front yes)
			(back yes)
		)
		(covering
			(front no)
			(back no)
		)
		(plugging
			(front no)
			(back no)
		)
		(capping no)
		(filling no)
		(pcbplotparams
			(layerselection 0x00000000_00000000_55555555_5755f5ff)
			(plot_on_all_layers_selection 0x00000000_00000000_00000000_00000000)
			(disableapertmacros no)
			(usegerberextensions no)
			(usegerberattributes yes)
			(usegerberadvancedattributes yes)
			(creategerberjobfile yes)
			(dashed_line_dash_ratio 12)
			(dashed_line_gap_ratio 3)
			(svgprecision 4)
			(plotframeref no)
			(mode 1)
			(useauxorigin no)
			(pdf_front_fp_property_popups yes)
			(pdf_back_fp_property_popups yes)
			(pdf_metadata yes)
			(pdf_single_document no)
			(dxfpolygonmode yes)
			(dxfimperialunits yes)
			(dxfusepcbnewfont yes)
			(psnegative no)
			(psa4output no)
			(plot_black_and_white yes)
			(sketchpadsonfab no)
			(plotpadnumbers no)
			(hidednponfab no)
			(sketchdnponfab yes)
			(crossoutdnponfab yes)
			(subtractmaskfromsilk no)
			(outputformat 1)
			(mirror no)
			(drillshape 1)
			(scaleselection 1)
			(outputdirectory "")
		)
	)
	(footprint ""
		(layer "F.Cu")
		(at 459.149704 -375.93524)
		(property "Reference" "R188"
			(at 0 0 0)
			(layer "F.SilkS")
			(hide yes)
			(effects
				(font
					(size 1.27 1.27)
				)
			)
		)
		(property "Value" "4K7R2F-GP"
			(at 0.064008 -3.993896 0)
			(unlocked yes)
			(layer "F.Fab")
			(hide yes)
			(effects
				(font
					(size 1.016 1.016)
					(thickness 0.1524)
				)
			)
		)
		(property "Device Type" "R402H16"
			(at 0.064008 -5.517896 0)
			(unlocked yes)
			(layer "F.Fab")
			(hide yes)
			(effects
				(font
					(size 1.016 1.016)
					(thickness 0.1524)
				)
			)
		)
		(duplicate_pad_numbers_are_jumpers no)
		(fp_line
			(start -0.508 -0.9398)
			(end -0.508 0.9398)
			(stroke
				(width 0.1524)
				(type default)
			)
			(layer "F.SilkS")
		)
		(fp_line
			(start 0.508 -0.9398)
			(end -0.508 -0.9398)
			(stroke
				(width 0.1524)
				(type default)
			)
			(layer "F.SilkS")
		)
		(fp_rect
			(start -0.508 0.9398)
			(end 0.508 -0.9398)
			(stroke
				(width 0)
				(type default)
			)
			(fill no)
			(layer "F.CrtYd")
		)
		(fp_rect
			(start -0.508 0.9398)
			(end 0.508 -0.9398)
			(stroke
				(width 0)
				(type default)
			)
			(fill no)
			(layer "F.Fab")
		)
		(pad "1" smd custom
			(at 0 -0.4445)
			(size 0.1397 0.1397)
			(layers "F.Cu" "F.Mask" "F.Paste")
			(net "FAN_BLUE_LED3")
			(options
				(clearance outline)
				(anchor circle)
			)
			(primitives
				(gr_poly
					(pts
						(arc
							(start -0.1778 -0.2794)
							(mid -0.249642 -0.249642)
							(end -0.2794 -0.1778)
						)
						(arc
							(start -0.2794 0.1778)
							(mid -0.249642 0.249642)
							(end -0.1778 0.2794)
						)
						(arc
							(start 0.1778 0.2794)
							(mid 0.249642 0.249642)
							(end 0.2794 0.1778)
						)
						(arc
							(start 0.2794 -0.1778)
							(mid 0.249642 -0.249642)
							(end 0.1778 -0.2794)
						)
					)
					(width 0)
					(fill yes)
				)
			)
		)
		(pad "2" smd custom
			(at 0 0.4445)
			(size 0.1397 0.1397)
			(layers "F.Cu" "F.Mask" "F.Paste")
			(net "P12V_IN")
			(options
				(clearance outline)
				(anchor circle)
			)
			(primitives
				(gr_poly
					(pts
						(arc
							(start -0.1778 -0.2794)
							(mid -0.249642 -0.249642)
							(end -0.2794 -0.1778)
						)
						(arc
							(start -0.2794 0.1778)
							(mid -0.249642 0.249642)
							(end -0.1778 0.2794)
						)
						(arc
							(start 0.1778 0.2794)
							(mid 0.249642 0.249642)
							(end 0.2794 0.1778)
						)
						(arc
							(start 0.2794 -0.1778)
							(mid 0.249642 -0.249642)
							(end 0.1778 -0.2794)
						)
					)
					(width 0)
					(fill yes)
				)
			)
		)
	)
	(footprint ""
		(layer "F.Cu")
		(at 246.898668 -223.393)
		(property "Reference" "R113"
			(at 0 0 0)
			(layer "F.SilkS")
			(hide yes)
			(effects
				(font
					(size 1.27 1.27)
				)
			)
		)
		(property "Value" "4K7R2F-GP"
			(at 0.064008 -3.993896 0)
			(unlocked yes)
			(layer "F.Fab")
			(hide yes)
			(effects
				(font
					(size 1.016 1.016)
					(thickness 0.1524)
				)
			)
		)
		(property "Device Type" "R402H16"
			(at 0.064008 -5.517896 0)
			(unlocked yes)
			(layer "F.Fab")
			(hide yes)
			(effects
				(font
					(size 1.016 1.016)
					(thickness 0.1524)
				)
			)
		)
		(duplicate_pad_numbers_are_jumpers no)
		(fp_line
			(start -0.508 -0.9398)
			(end -0.508 0.9398)
			(stroke
				(width 0.1524)
				(type default)
			)
			(layer "F.SilkS")
		)
		(fp_line
			(start 0.508 -0.9398)
			(end -0.508 -0.9398)
			(stroke
				(width 0.1524)
				(type default)
			)
			(layer "F.SilkS")
		)
		(fp_rect
			(start -0.508 0.9398)
			(end 0.508 -0.9398)
			(stroke
				(width 0)
				(type default)
			)
			(fill no)
			(layer "F.CrtYd")
		)
		(fp_rect
			(start -0.508 0.9398)
			(end 0.508 -0.9398)
			(stroke
				(width 0)
				(type default)
			)
			(fill no)
			(layer "F.Fab")
		)
		(pad "1" smd custom
			(at 0 -0.4445)
			(size 0.1397 0.1397)
			(layers "F.Cu" "F.Mask" "F.Paste")
			(net "P3V3_STBY_B")
			(options
				(clearance outline)
				(anchor circle)
			)
			(primitives
				(gr_poly
					(pts
						(arc
							(start -0.1778 -0.2794)
							(mid -0.249642 -0.249642)
							(end -0.2794 -0.1778)
						)
						(arc
							(start -0.2794 0.1778)
							(mid -0.249642 0.249642)
							(end -0.1778 0.2794)
						)
						(arc
							(start 0.1778 0.2794)
							(mid 0.249642 0.249642)
							(end 0.2794 0.1778)
						)
						(arc
							(start 0.2794 -0.1778)
							(mid 0.249642 -0.249642)
							(end 0.1778 -0.2794)
						)
					)
					(width 0)
					(fill yes)
				)
			)
		)
		(pad "2" smd custom
			(at 0 0.4445)
			(size 0.1397 0.1397)
			(layers "F.Cu" "F.Mask" "F.Paste")
			(net "EEPROM_A2")
			(options
				(clearance outline)
				(anchor circle)
			)
			(primitives
				(gr_poly
					(pts
						(arc
							(start -0.1778 -0.2794)
							(mid -0.249642 -0.249642)
							(end -0.2794 -0.1778)
						)
						(arc
							(start -0.2794 0.1778)
							(mid -0.249642 0.249642)
							(end -0.1778 0.2794)
						)
						(arc
							(start 0.1778 0.2794)
							(mid 0.249642 0.249642)
							(end 0.2794 0.1778)
						)
						(arc
							(start 0.2794 -0.1778)
							(mid 0.249642 -0.249642)
							(end 0.1778 -0.2794)
						)
					)
					(width 0)
					(fill yes)
				)
			)
		)
	)
	(footprint ""
		(layer "F.Cu")
		(at 394.6398 -16.0782 -90)
		(property "Reference" "C454"
			(at 0 0 270)
			(layer "F.SilkS")
			(hide yes)
			(effects
				(font
					(size 1.27 1.27)
				)
			)
		)
		(property "Value" "SCD033U25V2KX-GP"
			(at 1.1811 -2.7051 270)
			(unlocked yes)
			(layer "F.Fab")
			(hide yes)
			(effects
				(font
					(size 1.016 1.016)
					(thickness 0.1524)
				)
			)
		)
		(property "Device Type" "C402H22"
			(at 1.1811 -4.2291 270)
			(unlocked yes)
			(layer "F.Fab")
			(hide yes)
			(effects
				(font
					(size 1.016 1.016)
					(thickness 0.1524)
				)
			)
		)
		(duplicate_pad_numbers_are_jumpers no)
		(fp_rect
			(start -0.4318 0.9525)
			(end 0.4318 -0.9525)
			(stroke
				(width 0)
				(type default)
			)
			(fill no)
			(layer "F.CrtYd")
		)
		(fp_rect
			(start -0.4318 0.9525)
			(end 0.4318 -0.9525)
			(stroke
				(width 0)
				(type default)
			)
			(fill no)
			(layer "F.Fab")
		)
		(pad "1" smd custom
			(at 0 -0.4445 270)
			(size 0.1524 0.1524)
			(layers "F.Cu" "F.Mask" "F.Paste")
			(net "SW_HDD_P32")
			(options
				(clearance outline)
				(anchor circle)
			)
			(primitives
				(gr_poly
					(pts
						(arc
							(start 0.3048 -0.2032)
							(mid 0.275042 -0.275042)
							(end 0.2032 -0.3048)
						)
						(arc
							(start -0.2032 -0.3048)
							(mid -0.275042 -0.275042)
							(end -0.3048 -0.2032)
						)
						(arc
							(start -0.3048 0.2032)
							(mid -0.275042 0.275042)
							(end -0.2032 0.3048)
						)
						(arc
							(start 0.2032 0.3048)
							(mid 0.275042 0.275042)
							(end 0.3048 0.2032)
						)
					)
					(width 0)
					(fill yes)
				)
			)
		)
		(pad "2" smd custom
			(at 0 0.4445 270)
			(size 0.1524 0.1524)
			(layers "F.Cu" "F.Mask" "F.Paste")
			(net "GND")
			(options
				(clearance outline)
				(anchor circle)
			)
			(primitives
				(gr_poly
					(pts
						(arc
							(start 0.3048 -0.2032)
							(mid 0.275042 -0.275042)
							(end 0.2032 -0.3048)
						)
						(arc
							(start -0.2032 -0.3048)
							(mid -0.275042 -0.275042)
							(end -0.3048 -0.2032)
						)
						(arc
							(start -0.3048 0.2032)
							(mid -0.275042 0.275042)
							(end -0.2032 0.3048)
						)
						(arc
							(start 0.2032 0.3048)
							(mid 0.275042 0.275042)
							(end 0.3048 0.2032)
						)
					)
					(width 0)
					(fill yes)
				)
			)
		)
	)
	(footprint ""
		(layer "F.Cu")
		(at 14.859 -16.637 90)
		(property "Reference" "R636"
			(at 0 0 90)
			(layer "F.SilkS")
			(hide yes)
			(effects
				(font
					(size 1.27 1.27)
				)
			)
		)
		(property "Value" "4K7R2J-2-GP"
			(at 0.064008 -3.993896 90)
			(unlocked yes)
			(layer "F.Fab")
			(hide yes)
			(effects
				(font
					(size 1.016 1.016)
					(thickness 0.1524)
				)
			)
		)
		(property "Device Type" "R402H16"
			(at 0.064008 -5.517896 90)
			(unlocked yes)
			(layer "F.Fab")
			(hide yes)
			(effects
				(font
					(size 1.016 1.016)
					(thickness 0.1524)
				)
			)
		)
		(duplicate_pad_numbers_are_jumpers no)
		(fp_line
			(start 0.508 -0.9398)
			(end -0.508 -0.9398)
			(stroke
				(width 0.1524)
				(type default)
			)
			(layer "F.SilkS")
		)
		(fp_line
			(start -0.508 -0.9398)
			(end -0.508 0.9398)
			(stroke
				(width 0.1524)
				(type default)
			)
			(layer "F.SilkS")
		)
		(fp_rect
			(start -0.508 0.9398)
			(end 0.508 -0.9398)
			(stroke
				(width 0)
				(type default)
			)
			(fill no)
			(layer "F.CrtYd")
		)
		(fp_rect
			(start -0.508 0.9398)
			(end 0.508 -0.9398)
			(stroke
				(width 0)
				(type default)
			)
			(fill no)
			(layer "F.Fab")
		)
		(pad "1" smd custom
			(at 0 -0.4445 90)
			(size 0.1397 0.1397)
			(layers "F.Cu" "F.Mask" "F.Paste")
			(net "P12V_B")
			(options
				(clearance outline)
				(anchor circle)
			)
			(primitives
				(gr_poly
					(pts
						(arc
							(start -0.1778 -0.2794)
							(mid -0.249642 -0.249642)
							(end -0.2794 -0.1778)
						)
						(arc
							(start -0.2794 0.1778)
							(mid -0.249642 0.249642)
							(end -0.1778 0.2794)
						)
						(arc
							(start 0.1778 0.2794)
							(mid 0.249642 0.249642)
							(end 0.2794 0.1778)
						)
						(arc
							(start 0.2794 -0.1778)
							(mid 0.249642 -0.249642)
							(end 0.1778 -0.2794)
						)
					)
					(width 0)
					(fill yes)
				)
			)
		)
		(pad "2" smd custom
			(at 0 0.4445 90)
			(size 0.1397 0.1397)
			(layers "F.Cu" "F.Mask" "F.Paste")
			(net "SW_HDD_R24")
			(options
				(clearance outline)
				(anchor circle)
			)
			(primitives
				(gr_poly
					(pts
						(arc
							(start -0.1778 -0.2794)
							(mid -0.249642 -0.249642)
							(end -0.2794 -0.1778)
						)
						(arc
							(start -0.2794 0.1778)
							(mid -0.249642 0.249642)
							(end -0.1778 0.2794)
						)
						(arc
							(start 0.1778 0.2794)
							(mid 0.249642 0.249642)
							(end 0.2794 0.1778)
						)
						(arc
							(start 0.2794 -0.1778)
							(mid 0.249642 -0.249642)
							(end 0.1778 -0.2794)
						)
					)
					(width 0)
					(fill yes)
				)
			)
		)
	)
	(footprint ""
		(layer "F.Cu")
		(at 319.216024 -269.705074)
		(property "Reference" "TP51"
			(at 0 0 0)
			(layer "F.SilkS")
			(hide yes)
			(effects
				(font
					(size 1.27 1.27)
				)
			)
		)
		(property "Value" "*"
			(at -0.0508 -1.6764 0)
			(unlocked yes)
			(layer "F.Fab")
			(hide yes)
			(effects
				(font
					(size 1.016 1.016)
					(thickness 0.1524)
				)
			)
		)
		(property "Device Type" "TPAD32"
			(at -0.0508 -3.2004 0)
			(unlocked yes)
			(layer "F.Fab")
			(hide yes)
			(effects
				(font
					(size 1.016 1.016)
					(thickness 0.1524)
				)
			)
		)
		(duplicate_pad_numbers_are_jumpers no)
		(fp_poly
			(pts
				(arc
					(start 0.4064 0)
					(mid -0.4064 0)
					(end 0.4064 0)
				)
			)
			(stroke
				(width 0)
				(type default)
			)
			(fill no)
			(layer "F.CrtYd")
		)
		(fp_poly
			(pts
				(arc
					(start 0.7112 0)
					(mid -0.7112 0)
					(end 0.7112 0)
				)
			)
			(stroke
				(width 0)
				(type default)
			)
			(fill no)
			(layer "F.Fab")
		)
		(pad "1" smd circle
			(at 0 0)
			(size 0.8128 0.8128)
			(layers "F.Cu" "F.Mask" "F.Paste")
			(net "ACT_HDD_6")
		)
	)
	(footprint ""
		(layer "F.Cu")
		(at 143.002 -138.049 90)
		(property "Reference" "R445"
			(at 0 0 90)
			(layer "F.SilkS")
			(hide yes)
			(effects
				(font
					(size 1.27 1.27)
				)
			)
		)
		(property "Value" "4K7R2J-2-GP"
			(at 0.064008 -3.993896 90)
			(unlocked yes)
			(layer "F.Fab")
			(hide yes)
			(effects
				(font
					(size 1.016 1.016)
					(thickness 0.1524)
				)
			)
		)
		(property "Device Type" "R402H16"
			(at 0.064008 -5.517896 90)
			(unlocked yes)
			(layer "F.Fab")
			(hide yes)
			(effects
				(font
					(size 1.016 1.016)
					(thickness 0.1524)
				)
			)
		)
		(duplicate_pad_numbers_are_jumpers no)
		(fp_line
			(start 0.508 -0.9398)
			(end -0.508 -0.9398)
			(stroke
				(width 0.1524)
				(type default)
			)
			(layer "F.SilkS")
		)
		(fp_line
			(start -0.508 -0.9398)
			(end -0.508 0.9398)
			(stroke
				(width 0.1524)
				(type default)
			)
			(layer "F.SilkS")
		)
		(fp_rect
			(start -0.508 0.9398)
			(end 0.508 -0.9398)
			(stroke
				(width 0)
				(type default)
			)
			(fill no)
			(layer "F.CrtYd")
		)
		(fp_rect
			(start -0.508 0.9398)
			(end 0.508 -0.9398)
			(stroke
				(width 0)
				(type default)
			)
			(fill no)
			(layer "F.Fab")
		)
		(pad "1" smd custom
			(at 0 -0.4445 90)
			(size 0.1397 0.1397)
			(layers "F.Cu" "F.Mask" "F.Paste")
			(net "P12V_B")
			(options
				(clearance outline)
				(anchor circle)
			)
			(primitives
				(gr_poly
					(pts
						(arc
							(start -0.1778 -0.2794)
							(mid -0.249642 -0.249642)
							(end -0.2794 -0.1778)
						)
						(arc
							(start -0.2794 0.1778)
							(mid -0.249642 0.249642)
							(end -0.1778 0.2794)
						)
						(arc
							(start 0.1778 0.2794)
							(mid 0.249642 0.249642)
							(end 0.2794 0.1778)
						)
						(arc
							(start 0.2794 -0.1778)
							(mid 0.249642 -0.249642)
							(end 0.1778 -0.2794)
						)
					)
					(width 0)
					(fill yes)
				)
			)
		)
		(pad "2" smd custom
			(at 0 0.4445 90)
			(size 0.1397 0.1397)
			(layers "F.Cu" "F.Mask" "F.Paste")
			(net "SW_HDD_P16")
			(options
				(clearance outline)
				(anchor circle)
			)
			(primitives
				(gr_poly
					(pts
						(arc
							(start -0.1778 -0.2794)
							(mid -0.249642 -0.249642)
							(end -0.2794 -0.1778)
						)
						(arc
							(start -0.2794 0.1778)
							(mid -0.249642 0.249642)
							(end -0.1778 0.2794)
						)
						(arc
							(start 0.1778 0.2794)
							(mid 0.249642 0.249642)
							(end 0.2794 0.1778)
						)
						(arc
							(start 0.2794 -0.1778)
							(mid 0.249642 -0.249642)
							(end 0.1778 -0.2794)
						)
					)
					(width 0)
					(fill yes)
				)
			)
		)
	)
	(footprint ""
		(layer "F.Cu")
		(at 460.883 -16.3576 -90)
		(property "Reference" "R862"
			(at 0 0 270)
			(layer "F.SilkS")
			(hide yes)
			(effects
				(font
					(size 1.27 1.27)
				)
			)
		)
		(property "Value" "0R2J-2-GP"
			(at 0.064008 -3.993896 270)
			(unlocked yes)
			(layer "F.Fab")
			(hide yes)
			(effects
				(font
					(size 1.016 1.016)
					(thickness 0.1524)
				)
			)
		)
		(property "Device Type" "R402H16"
			(at 0.064008 -5.517896 270)
			(unlocked yes)
			(layer "F.Fab")
			(hide yes)
			(effects
				(font
					(size 1.016 1.016)
					(thickness 0.1524)
				)
			)
		)
		(duplicate_pad_numbers_are_jumpers no)
		(fp_line
			(start -0.508 -0.9398)
			(end -0.508 0.9398)
			(stroke
				(width 0.1524)
				(type default)
			)
			(layer "F.SilkS")
		)
		(fp_line
			(start 0.508 -0.9398)
			(end -0.508 -0.9398)
			(stroke
				(width 0.1524)
				(type default)
			)
			(layer "F.SilkS")
		)
		(fp_rect
			(start -0.508 0.9398)
			(end 0.508 -0.9398)
			(stroke
				(width 0)
				(type default)
			)
			(fill no)
			(layer "F.CrtYd")
		)
		(fp_rect
			(start -0.508 0.9398)
			(end 0.508 -0.9398)
			(stroke
				(width 0)
				(type default)
			)
			(fill no)
			(layer "F.Fab")
		)
		(pad "1" smd custom
			(at 0 -0.4445 270)
			(size 0.1397 0.1397)
			(layers "F.Cu" "F.Mask" "F.Paste")
			(net "DRIVE_B_34_PWR")
			(options
				(clearance outline)
				(anchor circle)
			)
			(primitives
				(gr_poly
					(pts
						(arc
							(start -0.1778 -0.2794)
							(mid -0.249642 -0.249642)
							(end -0.2794 -0.1778)
						)
						(arc
							(start -0.2794 0.1778)
							(mid -0.249642 0.249642)
							(end -0.1778 0.2794)
						)
						(arc
							(start 0.1778 0.2794)
							(mid 0.249642 0.249642)
							(end 0.2794 0.1778)
						)
						(arc
							(start 0.2794 -0.1778)
							(mid 0.249642 -0.249642)
							(end 0.1778 -0.2794)
						)
					)
					(width 0)
					(fill yes)
				)
			)
		)
		(pad "2" smd custom
			(at 0 0.4445 270)
			(size 0.1397 0.1397)
			(layers "F.Cu" "F.Mask" "F.Paste")
			(net "SW_PWR_R_HDD34")
			(options
				(clearance outline)
				(anchor circle)
			)
			(primitives
				(gr_poly
					(pts
						(arc
							(start -0.1778 -0.2794)
							(mid -0.249642 -0.249642)
							(end -0.2794 -0.1778)
						)
						(arc
							(start -0.2794 0.1778)
							(mid -0.249642 0.249642)
							(end -0.1778 0.2794)
						)
						(arc
							(start 0.1778 0.2794)
							(mid 0.249642 0.249642)
							(end 0.2794 0.1778)
						)
						(arc
							(start 0.2794 -0.1778)
							(mid 0.249642 -0.249642)
							(end 0.1778 -0.2794)
						)
					)
					(width 0)
					(fill yes)
				)
			)
		)
	)
	(footprint ""
		(layer "F.Cu")
		(at 462.915 -263.017)
		(property "Reference" "Q40"
			(at 0 0 0)
			(layer "F.SilkS")
			(hide yes)
			(effects
				(font
					(size 1.27 1.27)
				)
			)
		)
		(property "Value" "AO4407AL-GP"
			(at -3.707384 -1.5367 0)
			(unlocked yes)
			(layer "F.Fab")
			(hide yes)
			(effects
				(font
					(size 1.016 1.016)
					(thickness 0.1524)
				)
			)
		)
		(property "Device Type" "SOIC8H69"
			(at -3.707384 -3.0607 0)
			(unlocked yes)
			(layer "F.Fab")
			(hide yes)
			(effects
				(font
					(size 1.016 1.016)
					(thickness 0.1524)
				)
			)
		)
		(duplicate_pad_numbers_are_jumpers no)
		(fp_line
			(start -2.7432 -1.4224)
			(end -2.7432 1.4224)
			(stroke
				(width 0.1524)
				(type default)
			)
			(layer "F.SilkS")
		)
		(fp_line
			(start -2.7432 1.4224)
			(end -2.6416 1.4224)
			(stroke
				(width 0.1524)
				(type default)
			)
			(layer "F.SilkS")
		)
		(fp_line
			(start -2.7432 1.4224)
			(end 2.1336 1.4224)
			(stroke
				(width 0.1524)
				(type default)
			)
			(layer "F.SilkS")
		)
		(fp_line
			(start -2.7178 -0.508)
			(end -2.1844 -0.0508)
			(stroke
				(width 0.1524)
				(type default)
			)
			(layer "F.SilkS")
		)
		(fp_line
			(start -2.6289 3.4417)
			(end -2.6289 1.4732)
			(stroke
				(width 0.381)
				(type default)
			)
			(layer "F.SilkS")
		)
		(fp_line
			(start -2.1844 -0.0508)
			(end -2.7178 0.508)
			(stroke
				(width 0.1524)
				(type default)
			)
			(layer "F.SilkS")
		)
		(fp_line
			(start 2.1336 -1.4224)
			(end -2.7432 -1.4224)
			(stroke
				(width 0.1524)
				(type default)
			)
			(layer "F.SilkS")
		)
		(fp_line
			(start 2.1336 1.4224)
			(end 2.1336 -1.4224)
			(stroke
				(width 0.1524)
				(type default)
			)
			(layer "F.SilkS")
		)
		(fp_poly
			(pts
				(xy -2.2098 -1.4224) (xy -2.2098 1.4224) (xy 2.2098 1.4224) (xy 2.2098 -1.4224)
			)
			(stroke
				(width 0)
				(type default)
			)
			(fill yes)
			(layer "F.SilkS")
		)
		(fp_rect
			(start -2.450084 2.999994)
			(end 2.450084 -2.999994)
			(stroke
				(width 0)
				(type default)
			)
			(fill no)
			(layer "F.CrtYd")
		)
		(fp_poly
			(pts
				(xy -2.8194 3.6322) (xy -2.8194 -3.6322) (xy 2.8194 -3.6322) (xy 2.8194 1.18364) (xy 2.450084 1.18364)
				(xy 2.450084 -2.999994) (xy -2.450084 -2.999994) (xy -2.450084 2.999994) (xy 2.450084 2.999994)
				(xy 2.450084 1.18618) (xy 2.8194 1.18618) (xy 2.8194 3.6322)
			)
			(stroke
				(width 0)
				(type default)
			)
			(fill no)
			(layer "F.CrtYd")
		)
		(fp_rect
			(start -2.8194 3.6322)
			(end 2.8194 -3.6322)
			(stroke
				(width 0)
				(type default)
			)
			(fill no)
			(layer "F.Fab")
		)
		(pad "1" smd rect
			(at -1.905 2.54)
			(size 0.635 1.651)
			(layers "F.Cu" "F.Mask" "F.Paste")
			(net "P12V_B")
		)
		(pad "2" smd rect
			(at -0.635 2.54)
			(size 0.635 1.651)
			(layers "F.Cu" "F.Mask" "F.Paste")
			(net "P12V_B")
		)
		(pad "3" smd rect
			(at 0.635 2.54)
			(size 0.635 1.651)
			(layers "F.Cu" "F.Mask" "F.Paste")
			(net "P12V_B")
		)
		(pad "4" smd rect
			(at 1.905 2.54)
			(size 0.635 1.651)
			(layers "F.Cu" "F.Mask" "F.Paste")
			(net "SW_HDD_N10")
		)
		(pad "5" smd rect
			(at 1.905 -2.54)
			(size 0.635 1.651)
			(layers "F.Cu" "F.Mask" "F.Paste")
			(net "P12V_HDD10")
		)
		(pad "6" smd rect
			(at 0.635 -2.54)
			(size 0.635 1.651)
			(layers "F.Cu" "F.Mask" "F.Paste")
			(net "P12V_HDD10")
		)
		(pad "7" smd rect
			(at -0.635 -2.54)
			(size 0.635 1.651)
			(layers "F.Cu" "F.Mask" "F.Paste")
			(net "P12V_HDD10")
		)
		(pad "8" smd rect
			(at -1.905 -2.54)
			(size 0.635 1.651)
			(layers "F.Cu" "F.Mask" "F.Paste")
			(net "P12V_HDD10")
		)
	)
	(footprint ""
		(layer "F.Cu")
		(at 34.285682 -244.990874 90)
		(property "Reference" "VIA1"
			(at 0 0 90)
			(layer "F.SilkS")
			(hide yes)
			(effects
				(font
					(size 1.27 1.27)
				)
			)
		)
		(property "Value" "100OHM-8L-2D36MM-L18-GP"
			(at 3.8989 0.5715 90)
			(unlocked yes)
			(layer "F.Fab")
			(hide yes)
			(effects
				(font
					(size 1.016 1.016)
					(thickness 0.1524)
				)
			)
		)
		(property "Device Type" "VIA-PCIE-4P-414097"
			(at 3.8989 -0.9525 90)
			(unlocked yes)
			(layer "F.Fab")
			(hide yes)
			(effects
				(font
					(size 1.016 1.016)
					(thickness 0.1524)
				)
			)
		)
		(duplicate_pad_numbers_are_jumpers no)
		(fp_rect
			(start -2.0701 0.4826)
			(end 2.0701 -0.4826)
			(stroke
				(width 0)
				(type default)
			)
			(fill no)
			(layer "F.CrtYd")
		)
		(fp_rect
			(start -2.0701 0.4826)
			(end 2.0701 -0.4826)
			(stroke
				(width 0)
				(type default)
			)
			(fill no)
			(layer "F.Fab")
		)
		(pad "1" thru_hole circle
			(at -1.5875 0 90)
			(size 0.508 0.508)
			(drill 0.254)
			(layers "*.Cu" "*.Mask")
			(remove_unused_layers no)
			(net "GND")
			(clearance 0.2286)
			(thermal_gap 0.2286)
		)
		(pad "2" thru_hole circle
			(at -0.5715 0 90)
			(size 0.508 0.508)
			(drill 0.254)
			(layers "*.Cu" "*.Mask")
			(remove_unused_layers no)
			(net "PHY_SCC_B_TO_DRV_B_0_DP")
			(clearance 0.2286)
			(thermal_gap 0.2286)
		)
		(pad "3" thru_hole circle
			(at 0.5715 0 90)
			(size 0.508 0.508)
			(drill 0.254)
			(layers "*.Cu" "*.Mask")
			(remove_unused_layers no)
			(net "PHY_SCC_B_TO_DRV_B_0_DN")
			(clearance 0.2286)
			(thermal_gap 0.2286)
		)
		(pad "4" thru_hole circle
			(at 1.5875 0 90)
			(size 0.508 0.508)
			(drill 0.254)
			(layers "*.Cu" "*.Mask")
			(remove_unused_layers no)
			(net "GND")
			(clearance 0.2286)
			(thermal_gap 0.2286)
		)
	)
	(footprint ""
		(layer "F.Cu")
		(at 35.426396 -374.1166 -90)
		(property "Reference" "R925"
			(at 0 0 270)
			(layer "F.SilkS")
			(hide yes)
			(effects
				(font
					(size 1.27 1.27)
				)
			)
		)
		(property "Value" "0R2J-2-GP"
			(at 0.064008 -3.993896 270)
			(unlocked yes)
			(layer "F.Fab")
			(hide yes)
			(effects
				(font
					(size 1.016 1.016)
					(thickness 0.1524)
				)
			)
		)
		(property "Device Type" "R402H16"
			(at 0.064008 -5.517896 270)
			(unlocked yes)
			(layer "F.Fab")
			(hide yes)
			(effects
				(font
					(size 1.016 1.016)
					(thickness 0.1524)
				)
			)
		)
		(duplicate_pad_numbers_are_jumpers no)
		(fp_line
			(start -0.508 -0.9398)
			(end -0.508 0.9398)
			(stroke
				(width 0.1524)
				(type default)
			)
			(layer "F.SilkS")
		)
		(fp_line
			(start 0.508 -0.9398)
			(end -0.508 -0.9398)
			(stroke
				(width 0.1524)
				(type default)
			)
			(layer "F.SilkS")
		)
		(fp_rect
			(start -0.508 0.9398)
			(end 0.508 -0.9398)
			(stroke
				(width 0)
				(type default)
			)
			(fill no)
			(layer "F.CrtYd")
		)
		(fp_rect
			(start -0.508 0.9398)
			(end 0.508 -0.9398)
			(stroke
				(width 0)
				(type default)
			)
			(fill no)
			(layer "F.Fab")
		)
		(pad "1" smd custom
			(at 0 -0.4445 270)
			(size 0.1397 0.1397)
			(layers "F.Cu" "F.Mask" "F.Paste")
			(net "FAN_0_PWM")
			(options
				(clearance outline)
				(anchor circle)
			)
			(primitives
				(gr_poly
					(pts
						(arc
							(start -0.1778 -0.2794)
							(mid -0.249642 -0.249642)
							(end -0.2794 -0.1778)
						)
						(arc
							(start -0.2794 0.1778)
							(mid -0.249642 0.249642)
							(end -0.1778 0.2794)
						)
						(arc
							(start 0.1778 0.2794)
							(mid 0.249642 0.249642)
							(end 0.2794 0.1778)
						)
						(arc
							(start 0.2794 -0.1778)
							(mid 0.249642 -0.249642)
							(end 0.1778 -0.2794)
						)
					)
					(width 0)
					(fill yes)
				)
			)
		)
		(pad "2" smd custom
			(at 0 0.4445 270)
			(size 0.1397 0.1397)
			(layers "F.Cu" "F.Mask" "F.Paste")
			(net "PWM_OUT_FAN0")
			(options
				(clearance outline)
				(anchor circle)
			)
			(primitives
				(gr_poly
					(pts
						(arc
							(start -0.1778 -0.2794)
							(mid -0.249642 -0.249642)
							(end -0.2794 -0.1778)
						)
						(arc
							(start -0.2794 0.1778)
							(mid -0.249642 0.249642)
							(end -0.1778 0.2794)
						)
						(arc
							(start 0.1778 0.2794)
							(mid 0.249642 0.249642)
							(end 0.2794 0.1778)
						)
						(arc
							(start 0.2794 -0.1778)
							(mid 0.249642 -0.249642)
							(end 0.1778 -0.2794)
						)
					)
					(width 0)
					(fill yes)
				)
			)
		)
	)
	(footprint ""
		(layer "F.Cu")
		(at 415.3154 -261.6454 180)
		(property "Reference" "R303"
			(at 0 0 180)
			(layer "F.SilkS")
			(hide yes)
			(effects
				(font
					(size 1.27 1.27)
				)
			)
		)
		(property "Value" "10KR2F-2-GP"
			(at 0.064008 -3.993896 180)
			(unlocked yes)
			(layer "F.Fab")
			(hide yes)
			(effects
				(font
					(size 1.016 1.016)
					(thickness 0.1524)
				)
			)
		)
		(property "Device Type" "R402H16"
			(at 0.064008 -5.517896 180)
			(unlocked yes)
			(layer "F.Fab")
			(hide yes)
			(effects
				(font
					(size 1.016 1.016)
					(thickness 0.1524)
				)
			)
		)
		(duplicate_pad_numbers_are_jumpers no)
		(fp_line
			(start 0.508 -0.9398)
			(end -0.508 -0.9398)
			(stroke
				(width 0.1524)
				(type default)
			)
			(layer "F.SilkS")
		)
		(fp_line
			(start -0.508 -0.9398)
			(end -0.508 0.9398)
			(stroke
				(width 0.1524)
				(type default)
			)
			(layer "F.SilkS")
		)
		(fp_rect
			(start -0.508 0.9398)
			(end 0.508 -0.9398)
			(stroke
				(width 0)
				(type default)
			)
			(fill no)
			(layer "F.CrtYd")
		)
		(fp_rect
			(start -0.508 0.9398)
			(end 0.508 -0.9398)
			(stroke
				(width 0)
				(type default)
			)
			(fill no)
			(layer "F.Fab")
		)
		(pad "1" smd custom
			(at 0 -0.4445 180)
			(size 0.1397 0.1397)
			(layers "F.Cu" "F.Mask" "F.Paste")
			(net "P3V3_STBY_B")
			(options
				(clearance outline)
				(anchor circle)
			)
			(primitives
				(gr_poly
					(pts
						(arc
							(start -0.1778 -0.2794)
							(mid -0.249642 -0.249642)
							(end -0.2794 -0.1778)
						)
						(arc
							(start -0.2794 0.1778)
							(mid -0.249642 0.249642)
							(end -0.1778 0.2794)
						)
						(arc
							(start 0.1778 0.2794)
							(mid 0.249642 0.249642)
							(end 0.2794 0.1778)
						)
						(arc
							(start 0.2794 -0.1778)
							(mid 0.249642 -0.249642)
							(end 0.1778 -0.2794)
						)
					)
					(width 0)
					(fill yes)
				)
			)
		)
		(pad "2" smd custom
			(at 0 0.4445 180)
			(size 0.1397 0.1397)
			(layers "F.Cu" "F.Mask" "F.Paste")
			(net "HDD_PRSNT_9")
			(options
				(clearance outline)
				(anchor circle)
			)
			(primitives
				(gr_poly
					(pts
						(arc
							(start -0.1778 -0.2794)
							(mid -0.249642 -0.249642)
							(end -0.2794 -0.1778)
						)
						(arc
							(start -0.2794 0.1778)
							(mid -0.249642 0.249642)
							(end -0.1778 0.2794)
						)
						(arc
							(start 0.1778 0.2794)
							(mid 0.249642 0.249642)
							(end 0.2794 0.1778)
						)
						(arc
							(start 0.2794 -0.1778)
							(mid 0.249642 -0.249642)
							(end 0.1778 -0.2794)
						)
					)
					(width 0)
					(fill yes)
				)
			)
		)
	)
	(footprint ""
		(layer "F.Cu")
		(at 426.974 -151.892 180)
		(property "Reference" "C304"
			(at 0 0 180)
			(layer "F.SilkS")
			(hide yes)
			(effects
				(font
					(size 1.27 1.27)
				)
			)
		)
		(property "Value" "SC10U16V6KX-2GP"
			(at -0.0762 -5.1308 180)
			(unlocked yes)
			(layer "F.Fab")
			(hide yes)
			(effects
				(font
					(size 1.016 1.016)
					(thickness 0.1524)
				)
			)
		)
		(property "Device Type" "C1206H71"
			(at -0.127 -6.6548 180)
			(unlocked yes)
			(layer "F.Fab")
			(hide yes)
			(effects
				(font
					(size 1.016 1.016)
					(thickness 0.1524)
				)
			)
		)
		(duplicate_pad_numbers_are_jumpers no)
		(fp_line
			(start 1.016 2.2352)
			(end -1.016 2.2352)
			(stroke
				(width 0.1524)
				(type default)
			)
			(layer "F.SilkS")
		)
		(fp_line
			(start 1.016 0.8382)
			(end 1.016 2.2352)
			(stroke
				(width 0.1524)
				(type default)
			)
			(layer "F.SilkS")
		)
		(fp_line
			(start 1.016 -2.2352)
			(end 1.016 -0.8382)
			(stroke
				(width 0.1524)
				(type default)
			)
			(layer "F.SilkS")
		)
		(fp_line
			(start -1.016 2.2352)
			(end -1.016 0.8382)
			(stroke
				(width 0.1524)
				(type default)
			)
			(layer "F.SilkS")
		)
		(fp_line
			(start -1.016 -0.8382)
			(end -1.016 -2.2352)
			(stroke
				(width 0.1524)
				(type default)
			)
			(layer "F.SilkS")
		)
		(fp_line
			(start -1.016 -2.2352)
			(end 1.016 -2.2352)
			(stroke
				(width 0.1524)
				(type default)
			)
			(layer "F.SilkS")
		)
		(fp_rect
			(start -1.0922 2.3114)
			(end 1.0922 -2.3114)
			(stroke
				(width 0)
				(type default)
			)
			(fill no)
			(layer "F.CrtYd")
		)
		(fp_poly
			(pts
				(xy 1.0922 -2.3114) (xy 1.0922 2.3114) (xy -1.0922 2.3114) (xy -1.0922 -2.3114)
			)
			(stroke
				(width 0)
				(type default)
			)
			(fill no)
			(layer "F.Fab")
		)
		(pad "1" smd rect
			(at 0 -1.397 180)
			(size 1.651 1.27)
			(layers "F.Cu" "F.Mask" "F.Paste")
			(net "P5V_HDD21")
		)
		(pad "2" smd rect
			(at 0 1.397 180)
			(size 1.651 1.27)
			(layers "F.Cu" "F.Mask" "F.Paste")
			(net "GND")
		)
	)
	(footprint ""
		(layer "F.Cu")
		(at 209.804 -225.679 -90)
		(property "Reference" "R24"
			(at 0 0 270)
			(layer "F.SilkS")
			(hide yes)
			(effects
				(font
					(size 1.27 1.27)
				)
			)
		)
		(property "Value" "4K7R2F-GP"
			(at 0.064008 -3.993896 270)
			(unlocked yes)
			(layer "F.Fab")
			(hide yes)
			(effects
				(font
					(size 1.016 1.016)
					(thickness 0.1524)
				)
			)
		)
		(property "Device Type" "R402H16"
			(at 0.064008 -5.517896 270)
			(unlocked yes)
			(layer "F.Fab")
			(hide yes)
			(effects
				(font
					(size 1.016 1.016)
					(thickness 0.1524)
				)
			)
		)
		(duplicate_pad_numbers_are_jumpers no)
		(fp_line
			(start -0.508 -0.9398)
			(end -0.508 0.9398)
			(stroke
				(width 0.1524)
				(type default)
			)
			(layer "F.SilkS")
		)
		(fp_line
			(start 0.508 -0.9398)
			(end -0.508 -0.9398)
			(stroke
				(width 0.1524)
				(type default)
			)
			(layer "F.SilkS")
		)
		(fp_rect
			(start -0.508 0.9398)
			(end 0.508 -0.9398)
			(stroke
				(width 0)
				(type default)
			)
			(fill no)
			(layer "F.CrtYd")
		)
		(fp_rect
			(start -0.508 0.9398)
			(end 0.508 -0.9398)
			(stroke
				(width 0)
				(type default)
			)
			(fill no)
			(layer "F.Fab")
		)
		(pad "1" smd custom
			(at 0 -0.4445 270)
			(size 0.1397 0.1397)
			(layers "F.Cu" "F.Mask" "F.Paste")
			(net "IO_EXP1_HDD_FAULT_A1")
			(options
				(clearance outline)
				(anchor circle)
			)
			(primitives
				(gr_poly
					(pts
						(arc
							(start -0.1778 -0.2794)
							(mid -0.249642 -0.249642)
							(end -0.2794 -0.1778)
						)
						(arc
							(start -0.2794 0.1778)
							(mid -0.249642 0.249642)
							(end -0.1778 0.2794)
						)
						(arc
							(start 0.1778 0.2794)
							(mid 0.249642 0.249642)
							(end 0.2794 0.1778)
						)
						(arc
							(start 0.2794 -0.1778)
							(mid 0.249642 -0.249642)
							(end 0.1778 -0.2794)
						)
					)
					(width 0)
					(fill yes)
				)
			)
		)
		(pad "2" smd custom
			(at 0 0.4445 270)
			(size 0.1397 0.1397)
			(layers "F.Cu" "F.Mask" "F.Paste")
			(net "GND")
			(options
				(clearance outline)
				(anchor circle)
			)
			(primitives
				(gr_poly
					(pts
						(arc
							(start -0.1778 -0.2794)
							(mid -0.249642 -0.249642)
							(end -0.2794 -0.1778)
						)
						(arc
							(start -0.2794 0.1778)
							(mid -0.249642 0.249642)
							(end -0.1778 0.2794)
						)
						(arc
							(start 0.1778 0.2794)
							(mid 0.249642 0.249642)
							(end 0.2794 0.1778)
						)
						(arc
							(start 0.2794 -0.1778)
							(mid 0.249642 -0.249642)
							(end 0.1778 -0.2794)
						)
					)
					(width 0)
					(fill yes)
				)
			)
		)
	)
	(footprint ""
		(layer "F.Cu")
		(at 457.9874 -19.5072 180)
		(property "Reference" "C480"
			(at 0 0 180)
			(layer "F.SilkS")
			(hide yes)
			(effects
				(font
					(size 1.27 1.27)
				)
			)
		)
		(property "Value" "SCD033U25V2KX-GP"
			(at 1.1811 -2.7051 180)
			(unlocked yes)
			(layer "F.Fab")
			(hide yes)
			(effects
				(font
					(size 1.016 1.016)
					(thickness 0.1524)
				)
			)
		)
		(property "Device Type" "C402H22"
			(at 1.1811 -4.2291 180)
			(unlocked yes)
			(layer "F.Fab")
			(hide yes)
			(effects
				(font
					(size 1.016 1.016)
					(thickness 0.1524)
				)
			)
		)
		(duplicate_pad_numbers_are_jumpers no)
		(fp_rect
			(start -0.4318 0.9525)
			(end 0.4318 -0.9525)
			(stroke
				(width 0)
				(type default)
			)
			(fill no)
			(layer "F.CrtYd")
		)
		(fp_rect
			(start -0.4318 0.9525)
			(end 0.4318 -0.9525)
			(stroke
				(width 0)
				(type default)
			)
			(fill no)
			(layer "F.Fab")
		)
		(pad "1" smd custom
			(at 0 -0.4445 180)
			(size 0.1524 0.1524)
			(layers "F.Cu" "F.Mask" "F.Paste")
			(net "SW_HDD_P34")
			(options
				(clearance outline)
				(anchor circle)
			)
			(primitives
				(gr_poly
					(pts
						(arc
							(start 0.3048 -0.2032)
							(mid 0.275042 -0.275042)
							(end 0.2032 -0.3048)
						)
						(arc
							(start -0.2032 -0.3048)
							(mid -0.275042 -0.275042)
							(end -0.3048 -0.2032)
						)
						(arc
							(start -0.3048 0.2032)
							(mid -0.275042 0.275042)
							(end -0.2032 0.3048)
						)
						(arc
							(start 0.2032 0.3048)
							(mid 0.275042 0.275042)
							(end 0.3048 0.2032)
						)
					)
					(width 0)
					(fill yes)
				)
			)
		)
		(pad "2" smd custom
			(at 0 0.4445 180)
			(size 0.1524 0.1524)
			(layers "F.Cu" "F.Mask" "F.Paste")
			(net "GND")
			(options
				(clearance outline)
				(anchor circle)
			)
			(primitives
				(gr_poly
					(pts
						(arc
							(start 0.3048 -0.2032)
							(mid 0.275042 -0.275042)
							(end 0.2032 -0.3048)
						)
						(arc
							(start -0.2032 -0.3048)
							(mid -0.275042 -0.275042)
							(end -0.3048 -0.2032)
						)
						(arc
							(start -0.3048 0.2032)
							(mid -0.275042 0.275042)
							(end -0.2032 0.3048)
						)
						(arc
							(start 0.2032 0.3048)
							(mid 0.275042 0.275042)
							(end 0.3048 0.2032)
						)
					)
					(width 0)
					(fill yes)
				)
			)
		)
	)
	(footprint ""
		(layer "F.Cu")
		(at 463.404712 -221.75089 -90)
		(property "Reference" "C662"
			(at 0 0 270)
			(layer "F.SilkS")
			(hide yes)
			(effects
				(font
					(size 1.27 1.27)
				)
			)
		)
		(property "Value" "SC2200P50V2KX-2GP"
			(at 1.1811 -2.7051 270)
			(unlocked yes)
			(layer "F.Fab")
			(hide yes)
			(effects
				(font
					(size 1.016 1.016)
					(thickness 0.1524)
				)
			)
		)
		(property "Device Type" "C402H22"
			(at 1.1811 -4.2291 270)
			(unlocked yes)
			(layer "F.Fab")
			(hide yes)
			(effects
				(font
					(size 1.016 1.016)
					(thickness 0.1524)
				)
			)
		)
		(duplicate_pad_numbers_are_jumpers no)
		(fp_rect
			(start -0.4318 0.9525)
			(end 0.4318 -0.9525)
			(stroke
				(width 0)
				(type default)
			)
			(fill no)
			(layer "F.CrtYd")
		)
		(fp_rect
			(start -0.4318 0.9525)
			(end 0.4318 -0.9525)
			(stroke
				(width 0)
				(type default)
			)
			(fill no)
			(layer "F.Fab")
		)
		(pad "1" smd custom
			(at 0 -0.4445 270)
			(size 0.1524 0.1524)
			(layers "F.Cu" "F.Mask" "F.Paste")
			(net "P5V_B_3_LL")
			(options
				(clearance outline)
				(anchor circle)
			)
			(primitives
				(gr_poly
					(pts
						(arc
							(start 0.3048 -0.2032)
							(mid 0.275042 -0.275042)
							(end 0.2032 -0.3048)
						)
						(arc
							(start -0.2032 -0.3048)
							(mid -0.275042 -0.275042)
							(end -0.3048 -0.2032)
						)
						(arc
							(start -0.3048 0.2032)
							(mid -0.275042 0.275042)
							(end -0.2032 0.3048)
						)
						(arc
							(start 0.2032 0.3048)
							(mid 0.275042 0.275042)
							(end 0.3048 0.2032)
						)
					)
					(width 0)
					(fill yes)
				)
			)
		)
		(pad "2" smd custom
			(at 0 0.4445 270)
			(size 0.1524 0.1524)
			(layers "F.Cu" "F.Mask" "F.Paste")
			(net "P5V_B_3_SNB")
			(options
				(clearance outline)
				(anchor circle)
			)
			(primitives
				(gr_poly
					(pts
						(arc
							(start 0.3048 -0.2032)
							(mid 0.275042 -0.275042)
							(end 0.2032 -0.3048)
						)
						(arc
							(start -0.2032 -0.3048)
							(mid -0.275042 -0.275042)
							(end -0.3048 -0.2032)
						)
						(arc
							(start -0.3048 0.2032)
							(mid -0.275042 0.275042)
							(end -0.2032 0.3048)
						)
						(arc
							(start 0.2032 0.3048)
							(mid 0.275042 0.275042)
							(end 0.3048 0.2032)
						)
					)
					(width 0)
					(fill yes)
				)
			)
		)
	)
	(footprint ""
		(layer "F.Cu")
		(at 432.689 -20.447 90)
		(property "Reference" "R845"
			(at 0 0 90)
			(layer "F.SilkS")
			(hide yes)
			(effects
				(font
					(size 1.27 1.27)
				)
			)
		)
		(property "Value" "200KR2F-L-GP"
			(at 0.064008 -3.993896 90)
			(unlocked yes)
			(layer "F.Fab")
			(hide yes)
			(effects
				(font
					(size 1.016 1.016)
					(thickness 0.1524)
				)
			)
		)
		(property "Device Type" "R402H16"
			(at 0.064008 -5.517896 90)
			(unlocked yes)
			(layer "F.Fab")
			(hide yes)
			(effects
				(font
					(size 1.016 1.016)
					(thickness 0.1524)
				)
			)
		)
		(duplicate_pad_numbers_are_jumpers no)
		(fp_line
			(start 0.508 -0.9398)
			(end -0.508 -0.9398)
			(stroke
				(width 0.1524)
				(type default)
			)
			(layer "F.SilkS")
		)
		(fp_line
			(start -0.508 -0.9398)
			(end -0.508 0.9398)
			(stroke
				(width 0.1524)
				(type default)
			)
			(layer "F.SilkS")
		)
		(fp_rect
			(start -0.508 0.9398)
			(end 0.508 -0.9398)
			(stroke
				(width 0)
				(type default)
			)
			(fill no)
			(layer "F.CrtYd")
		)
		(fp_rect
			(start -0.508 0.9398)
			(end 0.508 -0.9398)
			(stroke
				(width 0)
				(type default)
			)
			(fill no)
			(layer "F.Fab")
		)
		(pad "1" smd custom
			(at 0 -0.4445 90)
			(size 0.1397 0.1397)
			(layers "F.Cu" "F.Mask" "F.Paste")
			(net "SW_HDD_R33")
			(options
				(clearance outline)
				(anchor circle)
			)
			(primitives
				(gr_poly
					(pts
						(arc
							(start -0.1778 -0.2794)
							(mid -0.249642 -0.249642)
							(end -0.2794 -0.1778)
						)
						(arc
							(start -0.2794 0.1778)
							(mid -0.249642 0.249642)
							(end -0.1778 0.2794)
						)
						(arc
							(start 0.1778 0.2794)
							(mid 0.249642 0.249642)
							(end 0.2794 0.1778)
						)
						(arc
							(start 0.2794 -0.1778)
							(mid 0.249642 -0.249642)
							(end 0.1778 -0.2794)
						)
					)
					(width 0)
					(fill yes)
				)
			)
		)
		(pad "2" smd custom
			(at 0 0.4445 90)
			(size 0.1397 0.1397)
			(layers "F.Cu" "F.Mask" "F.Paste")
			(net "SW_HDD_N33")
			(options
				(clearance outline)
				(anchor circle)
			)
			(primitives
				(gr_poly
					(pts
						(arc
							(start -0.1778 -0.2794)
							(mid -0.249642 -0.249642)
							(end -0.2794 -0.1778)
						)
						(arc
							(start -0.2794 0.1778)
							(mid -0.249642 0.249642)
							(end -0.1778 0.2794)
						)
						(arc
							(start 0.1778 0.2794)
							(mid 0.249642 0.249642)
							(end 0.2794 0.1778)
						)
						(arc
							(start 0.2794 -0.1778)
							(mid 0.249642 -0.249642)
							(end 0.1778 -0.2794)
						)
					)
					(width 0)
					(fill yes)
				)
			)
		)
	)
	(footprint ""
		(layer "F.Cu")
		(at 176.276 -20.955 90)
		(property "Reference" "C415"
			(at 0 0 90)
			(layer "F.SilkS")
			(hide yes)
			(effects
				(font
					(size 1.27 1.27)
				)
			)
		)
		(property "Value" "SCD033U25V2KX-GP"
			(at 1.1811 -2.7051 90)
			(unlocked yes)
			(layer "F.Fab")
			(hide yes)
			(effects
				(font
					(size 1.016 1.016)
					(thickness 0.1524)
				)
			)
		)
		(property "Device Type" "C402H22"
			(at 1.1811 -4.2291 90)
			(unlocked yes)
			(layer "F.Fab")
			(hide yes)
			(effects
				(font
					(size 1.016 1.016)
					(thickness 0.1524)
				)
			)
		)
		(duplicate_pad_numbers_are_jumpers no)
		(fp_rect
			(start -0.4318 0.9525)
			(end 0.4318 -0.9525)
			(stroke
				(width 0)
				(type default)
			)
			(fill no)
			(layer "F.CrtYd")
		)
		(fp_rect
			(start -0.4318 0.9525)
			(end 0.4318 -0.9525)
			(stroke
				(width 0)
				(type default)
			)
			(fill no)
			(layer "F.Fab")
		)
		(pad "1" smd custom
			(at 0 -0.4445 90)
			(size 0.1524 0.1524)
			(layers "F.Cu" "F.Mask" "F.Paste")
			(net "SW_HDD_P29")
			(options
				(clearance outline)
				(anchor circle)
			)
			(primitives
				(gr_poly
					(pts
						(arc
							(start 0.3048 -0.2032)
							(mid 0.275042 -0.275042)
							(end 0.2032 -0.3048)
						)
						(arc
							(start -0.2032 -0.3048)
							(mid -0.275042 -0.275042)
							(end -0.3048 -0.2032)
						)
						(arc
							(start -0.3048 0.2032)
							(mid -0.275042 0.275042)
							(end -0.2032 0.3048)
						)
						(arc
							(start 0.2032 0.3048)
							(mid 0.275042 0.275042)
							(end 0.3048 0.2032)
						)
					)
					(width 0)
					(fill yes)
				)
			)
		)
		(pad "2" smd custom
			(at 0 0.4445 90)
			(size 0.1524 0.1524)
			(layers "F.Cu" "F.Mask" "F.Paste")
			(net "GND")
			(options
				(clearance outline)
				(anchor circle)
			)
			(primitives
				(gr_poly
					(pts
						(arc
							(start 0.3048 -0.2032)
							(mid 0.275042 -0.275042)
							(end 0.2032 -0.3048)
						)
						(arc
							(start -0.2032 -0.3048)
							(mid -0.275042 -0.275042)
							(end -0.3048 -0.2032)
						)
						(arc
							(start -0.3048 0.2032)
							(mid -0.275042 0.275042)
							(end -0.2032 0.3048)
						)
						(arc
							(start 0.2032 0.3048)
							(mid 0.275042 0.275042)
							(end 0.3048 0.2032)
						)
					)
					(width 0)
					(fill yes)
				)
			)
		)
	)
	(footprint ""
		(layer "F.Cu")
		(at 86.868 -148.209)
		(property "Reference" "R391"
			(at 0 0 0)
			(layer "F.SilkS")
			(hide yes)
			(effects
				(font
					(size 1.27 1.27)
				)
			)
		)
		(property "Value" "2R6F-GP"
			(at -0.0508 -4.8514 0)
			(unlocked yes)
			(layer "F.Fab")
			(hide yes)
			(effects
				(font
					(size 1.016 1.016)
					(thickness 0.1524)
				)
			)
		)
		(property "Device Type" "R1206H26"
			(at 0 -6.3754 0)
			(unlocked yes)
			(layer "F.Fab")
			(hide yes)
			(effects
				(font
					(size 1.016 1.016)
					(thickness 0.1524)
				)
			)
		)
		(duplicate_pad_numbers_are_jumpers no)
		(fp_line
			(start -1.016 -2.2352)
			(end 1.016 -2.2352)
			(stroke
				(width 0.1524)
				(type default)
			)
			(layer "F.SilkS")
		)
		(fp_line
			(start -1.016 2.2352)
			(end -1.016 -2.2352)
			(stroke
				(width 0.1524)
				(type default)
			)
			(layer "F.SilkS")
		)
		(fp_line
			(start 1.016 -2.2352)
			(end 1.016 2.2352)
			(stroke
				(width 0.1524)
				(type default)
			)
			(layer "F.SilkS")
		)
		(fp_line
			(start 1.016 2.2352)
			(end -1.016 2.2352)
			(stroke
				(width 0.1524)
				(type default)
			)
			(layer "F.SilkS")
		)
		(fp_rect
			(start -1.0922 2.3114)
			(end 1.0922 -2.3114)
			(stroke
				(width 0)
				(type default)
			)
			(fill no)
			(layer "F.CrtYd")
		)
		(fp_poly
			(pts
				(xy -1.0922 -2.3114) (xy 1.0922 -2.3114) (xy 1.0922 2.3114) (xy -1.0922 2.3114)
			)
			(stroke
				(width 0)
				(type default)
			)
			(fill no)
			(layer "F.Fab")
		)
		(pad "1" smd rect
			(at 0 -1.397)
			(size 1.651 1.27)
			(layers "F.Cu" "F.Mask" "F.Paste")
			(net "P5V_HDD14")
		)
		(pad "2" smd rect
			(at 0 1.397)
			(size 1.651 1.27)
			(layers "F.Cu" "F.Mask" "F.Paste")
			(net "5V_PRE_14")
		)
	)
	(footprint ""
		(layer "F.Cu")
		(at 259.113782 -226.81311 90)
		(property "Reference" "C40"
			(at 0 0 90)
			(layer "F.SilkS")
			(hide yes)
			(effects
				(font
					(size 1.27 1.27)
				)
			)
		)
		(property "Value" "SCD1U16V2KX-3GP"
			(at 1.1811 -2.7051 90)
			(unlocked yes)
			(layer "F.Fab")
			(hide yes)
			(effects
				(font
					(size 1.016 1.016)
					(thickness 0.1524)
				)
			)
		)
		(property "Device Type" "C402H22"
			(at 1.1811 -4.2291 90)
			(unlocked yes)
			(layer "F.Fab")
			(hide yes)
			(effects
				(font
					(size 1.016 1.016)
					(thickness 0.1524)
				)
			)
		)
		(duplicate_pad_numbers_are_jumpers no)
		(fp_rect
			(start -0.4318 0.9525)
			(end 0.4318 -0.9525)
			(stroke
				(width 0)
				(type default)
			)
			(fill no)
			(layer "F.CrtYd")
		)
		(fp_rect
			(start -0.4318 0.9525)
			(end 0.4318 -0.9525)
			(stroke
				(width 0)
				(type default)
			)
			(fill no)
			(layer "F.Fab")
		)
		(pad "1" smd custom
			(at 0 -0.4445 90)
			(size 0.1524 0.1524)
			(layers "F.Cu" "F.Mask" "F.Paste")
			(net "P5V_B_3_SENSE")
			(options
				(clearance outline)
				(anchor circle)
			)
			(primitives
				(gr_poly
					(pts
						(arc
							(start 0.3048 -0.2032)
							(mid 0.275042 -0.275042)
							(end 0.2032 -0.3048)
						)
						(arc
							(start -0.2032 -0.3048)
							(mid -0.275042 -0.275042)
							(end -0.3048 -0.2032)
						)
						(arc
							(start -0.3048 0.2032)
							(mid -0.275042 0.275042)
							(end -0.2032 0.3048)
						)
						(arc
							(start 0.2032 0.3048)
							(mid 0.275042 0.275042)
							(end 0.3048 0.2032)
						)
					)
					(width 0)
					(fill yes)
				)
			)
		)
		(pad "2" smd custom
			(at 0 0.4445 90)
			(size 0.1524 0.1524)
			(layers "F.Cu" "F.Mask" "F.Paste")
			(net "GND")
			(options
				(clearance outline)
				(anchor circle)
			)
			(primitives
				(gr_poly
					(pts
						(arc
							(start 0.3048 -0.2032)
							(mid 0.275042 -0.275042)
							(end 0.2032 -0.3048)
						)
						(arc
							(start -0.2032 -0.3048)
							(mid -0.275042 -0.275042)
							(end -0.3048 -0.2032)
						)
						(arc
							(start -0.3048 0.2032)
							(mid -0.275042 0.275042)
							(end -0.2032 0.3048)
						)
						(arc
							(start 0.2032 0.3048)
							(mid 0.275042 0.275042)
							(end 0.3048 0.2032)
						)
					)
					(width 0)
					(fill yes)
				)
			)
		)
	)
	(footprint ""
		(layer "F.Cu")
		(at 149.1996 -18.4912 -90)
		(property "Reference" "R722"
			(at 0 0 270)
			(layer "F.SilkS")
			(hide yes)
			(effects
				(font
					(size 1.27 1.27)
				)
			)
		)
		(property "Value" "1KR2F-3-GP"
			(at 0.064008 -3.993896 270)
			(unlocked yes)
			(layer "F.Fab")
			(hide yes)
			(effects
				(font
					(size 1.016 1.016)
					(thickness 0.1524)
				)
			)
		)
		(property "Device Type" "R402H16"
			(at 0.064008 -5.517896 270)
			(unlocked yes)
			(layer "F.Fab")
			(hide yes)
			(effects
				(font
					(size 1.016 1.016)
					(thickness 0.1524)
				)
			)
		)
		(duplicate_pad_numbers_are_jumpers no)
		(fp_line
			(start -0.508 -0.9398)
			(end -0.508 0.9398)
			(stroke
				(width 0.1524)
				(type default)
			)
			(layer "F.SilkS")
		)
		(fp_line
			(start 0.508 -0.9398)
			(end -0.508 -0.9398)
			(stroke
				(width 0.1524)
				(type default)
			)
			(layer "F.SilkS")
		)
		(fp_rect
			(start -0.508 0.9398)
			(end 0.508 -0.9398)
			(stroke
				(width 0)
				(type default)
			)
			(fill no)
			(layer "F.CrtYd")
		)
		(fp_rect
			(start -0.508 0.9398)
			(end 0.508 -0.9398)
			(stroke
				(width 0)
				(type default)
			)
			(fill no)
			(layer "F.Fab")
		)
		(pad "1" smd custom
			(at 0 -0.4445 270)
			(size 0.1397 0.1397)
			(layers "F.Cu" "F.Mask" "F.Paste")
			(net "P3V3_STBY_B")
			(options
				(clearance outline)
				(anchor circle)
			)
			(primitives
				(gr_poly
					(pts
						(arc
							(start -0.1778 -0.2794)
							(mid -0.249642 -0.249642)
							(end -0.2794 -0.1778)
						)
						(arc
							(start -0.2794 0.1778)
							(mid -0.249642 0.249642)
							(end -0.1778 0.2794)
						)
						(arc
							(start 0.1778 0.2794)
							(mid 0.249642 0.249642)
							(end 0.2794 0.1778)
						)
						(arc
							(start 0.2794 -0.1778)
							(mid 0.249642 -0.249642)
							(end 0.1778 -0.2794)
						)
					)
					(width 0)
					(fill yes)
				)
			)
		)
		(pad "2" smd custom
			(at 0 0.4445 270)
			(size 0.1397 0.1397)
			(layers "F.Cu" "F.Mask" "F.Paste")
			(net "SW_PWR_R_HDD28")
			(options
				(clearance outline)
				(anchor circle)
			)
			(primitives
				(gr_poly
					(pts
						(arc
							(start -0.1778 -0.2794)
							(mid -0.249642 -0.249642)
							(end -0.2794 -0.1778)
						)
						(arc
							(start -0.2794 0.1778)
							(mid -0.249642 0.249642)
							(end -0.1778 0.2794)
						)
						(arc
							(start 0.1778 0.2794)
							(mid 0.249642 0.249642)
							(end 0.2794 0.1778)
						)
						(arc
							(start 0.2794 -0.1778)
							(mid 0.249642 -0.249642)
							(end 0.1778 -0.2794)
						)
					)
					(width 0)
					(fill yes)
				)
			)
		)
	)
	(footprint ""
		(layer "F.Cu")
		(at 457.581 -160.02 180)
		(property "Reference" "C321"
			(at 0 0 180)
			(layer "F.SilkS")
			(hide yes)
			(effects
				(font
					(size 1.27 1.27)
				)
			)
		)
		(property "Value" "SC4D7U25V5KX-1-GP"
			(at -0.0762 -6.1214 180)
			(unlocked yes)
			(layer "F.Fab")
			(hide yes)
			(effects
				(font
					(size 1.016 1.016)
					(thickness 0.1524)
				)
			)
		)
		(property "Device Type" "C805H58"
			(at -0.0762 -8.1534 180)
			(unlocked yes)
			(layer "F.Fab")
			(hide yes)
			(effects
				(font
					(size 1.016 1.016)
					(thickness 0.1524)
				)
			)
		)
		(duplicate_pad_numbers_are_jumpers no)
		(fp_line
			(start 0.635 0)
			(end -0.635 0)
			(stroke
				(width 0.508)
				(type default)
			)
			(layer "F.SilkS")
		)
		(fp_rect
			(start -0.9652 1.778)
			(end 0.9652 -1.778)
			(stroke
				(width 0)
				(type default)
			)
			(fill no)
			(layer "F.CrtYd")
		)
		(fp_poly
			(pts
				(xy -0.9652 -1.778) (xy 0.9652 -1.778) (xy 0.9652 1.778) (xy -0.9652 1.778)
			)
			(stroke
				(width 0)
				(type default)
			)
			(fill no)
			(layer "F.Fab")
		)
		(pad "1" smd rect
			(at 0 -0.9652 180)
			(size 1.397 1.143)
			(layers "F.Cu" "F.Mask" "F.Paste")
			(net "P12V_HDD22")
		)
		(pad "2" smd rect
			(at 0 0.9652 180)
			(size 1.397 1.143)
			(layers "F.Cu" "F.Mask" "F.Paste")
			(net "GND")
		)
	)
	(footprint ""
		(layer "F.Cu")
		(at 10.843768 -214.860378 90)
		(property "Reference" "Q243"
			(at 0 0 90)
			(layer "F.SilkS")
			(hide yes)
			(effects
				(font
					(size 1.27 1.27)
				)
			)
		)
		(property "Value" "SSM3K324R-GP"
			(at 0.127 -8.9662 90)
			(unlocked yes)
			(layer "F.Fab")
			(hide yes)
			(effects
				(font
					(size 1.016 1.016)
					(thickness 0.1524)
				)
			)
		)
		(property "Device Type" "SOT23DGS2D4H35"
			(at 0.127 -10.4902 90)
			(unlocked yes)
			(layer "F.Fab")
			(hide yes)
			(effects
				(font
					(size 1.016 1.016)
					(thickness 0.1524)
				)
			)
		)
		(duplicate_pad_numbers_are_jumpers no)
		(fp_line
			(start 1.651 -1.778)
			(end -1.651 -1.778)
			(stroke
				(width 0.1524)
				(type default)
			)
			(layer "F.SilkS")
		)
		(fp_line
			(start -1.651 -1.778)
			(end -1.651 1.778)
			(stroke
				(width 0.1524)
				(type default)
			)
			(layer "F.SilkS")
		)
		(fp_line
			(start 1.651 1.778)
			(end 1.651 -1.778)
			(stroke
				(width 0.1524)
				(type default)
			)
			(layer "F.SilkS")
		)
		(fp_line
			(start -1.651 1.778)
			(end 1.651 1.778)
			(stroke
				(width 0.1524)
				(type default)
			)
			(layer "F.SilkS")
		)
		(fp_poly
			(pts
				(xy -1.778 1.8796) (xy -1.778 -1.8796) (xy 1.778 -1.8796) (xy 1.778 1.8796)
			)
			(stroke
				(width 0)
				(type default)
			)
			(fill no)
			(layer "F.CrtYd")
		)
		(fp_poly
			(pts
				(xy -1.778 1.8796) (xy -1.778 -1.8796) (xy 1.778 -1.8796) (xy 1.778 1.8796)
			)
			(stroke
				(width 0)
				(type default)
			)
			(fill no)
			(layer "F.Fab")
		)
		(pad "D" smd custom
			(at 0 -0.9525 90)
			(size 0.1905 0.1905)
			(layers "F.Cu" "F.Mask" "F.Paste")
			(net "DRV_ACT_0_N")
			(options
				(clearance outline)
				(anchor circle)
			)
			(primitives
				(gr_poly
					(pts
						(arc
							(start -0.1778 0.5715)
							(mid -0.321484 0.511984)
							(end -0.381 0.3683)
						)
						(arc
							(start -0.381 -0.3683)
							(mid -0.321484 -0.511984)
							(end -0.1778 -0.5715)
						)
						(arc
							(start 0.1778 -0.5715)
							(mid 0.321484 -0.511984)
							(end 0.381 -0.3683)
						)
						(arc
							(start 0.381 0.3683)
							(mid 0.321484 0.511984)
							(end 0.1778 0.5715)
						)
					)
					(width 0)
					(fill yes)
				)
			)
		)
		(pad "G" smd custom
			(at -0.98425 0.9525 90)
			(size 0.1905 0.1905)
			(layers "F.Cu" "F.Mask" "F.Paste")
			(net "DRIVE_B_0_ACT")
			(options
				(clearance outline)
				(anchor circle)
			)
			(primitives
				(gr_poly
					(pts
						(arc
							(start -0.1778 0.5715)
							(mid -0.321484 0.511984)
							(end -0.381 0.3683)
						)
						(arc
							(start -0.381 -0.3683)
							(mid -0.321484 -0.511984)
							(end -0.1778 -0.5715)
						)
						(arc
							(start 0.1778 -0.5715)
							(mid 0.321484 -0.511984)
							(end 0.381 -0.3683)
						)
						(arc
							(start 0.381 0.3683)
							(mid 0.321484 0.511984)
							(end 0.1778 0.5715)
						)
					)
					(width 0)
					(fill yes)
				)
			)
		)
		(pad "S" smd custom
			(at 0.98425 0.9525 90)
			(size 0.1905 0.1905)
			(layers "F.Cu" "F.Mask" "F.Paste")
			(net "GND")
			(options
				(clearance outline)
				(anchor circle)
			)
			(primitives
				(gr_poly
					(pts
						(arc
							(start -0.1778 0.5715)
							(mid -0.321484 0.511984)
							(end -0.381 0.3683)
						)
						(arc
							(start -0.381 -0.3683)
							(mid -0.321484 -0.511984)
							(end -0.1778 -0.5715)
						)
						(arc
							(start 0.1778 -0.5715)
							(mid 0.321484 -0.511984)
							(end 0.381 -0.3683)
						)
						(arc
							(start 0.381 0.3683)
							(mid 0.321484 0.511984)
							(end 0.1778 0.5715)
						)
					)
					(width 0)
					(fill yes)
				)
			)
		)
	)
	(footprint ""
		(layer "F.Cu")
		(at 218.403932 -353.794568 90)
		(property "Reference" "C552"
			(at 0 0 90)
			(layer "F.SilkS")
			(hide yes)
			(effects
				(font
					(size 1.27 1.27)
				)
			)
		)
		(property "Value" "SCD033U50V3KX-1GP"
			(at 0 -2.8194 90)
			(unlocked yes)
			(layer "F.Fab")
			(hide yes)
			(effects
				(font
					(size 1.016 1.016)
					(thickness 0.1524)
				)
			)
		)
		(property "Device Type" "C603H36"
			(at 0 -4.3434 90)
			(unlocked yes)
			(layer "F.Fab")
			(hide yes)
			(effects
				(font
					(size 1.016 1.016)
					(thickness 0.1524)
				)
			)
		)
		(duplicate_pad_numbers_are_jumpers no)
		(fp_line
			(start 0.508 0)
			(end -0.508 0)
			(stroke
				(width 0.2032)
				(type default)
			)
			(layer "F.SilkS")
		)
		(fp_rect
			(start -0.5842 1.3335)
			(end 0.5842 -1.3335)
			(stroke
				(width 0)
				(type default)
			)
			(fill no)
			(layer "F.CrtYd")
		)
		(fp_rect
			(start -0.5842 1.3335)
			(end 0.5842 -1.3335)
			(stroke
				(width 0)
				(type default)
			)
			(fill no)
			(layer "F.Fab")
		)
		(pad "1" smd custom
			(at 0 -0.762 90)
			(size 0.2159 0.2159)
			(layers "F.Cu" "F.Mask" "F.Paste")
			(net "MB0_CM_GATE_C")
			(options
				(clearance outline)
				(anchor circle)
			)
			(primitives
				(gr_poly
					(pts
						(arc
							(start -0.3302 -0.4318)
							(mid -0.402042 -0.402042)
							(end -0.4318 -0.3302)
						)
						(arc
							(start -0.4318 0.3302)
							(mid -0.402042 0.402042)
							(end -0.3302 0.4318)
						)
						(arc
							(start 0.3302 0.4318)
							(mid 0.402042 0.402042)
							(end 0.4318 0.3302)
						)
						(arc
							(start 0.4318 -0.3302)
							(mid 0.402042 -0.402042)
							(end 0.3302 -0.4318)
						)
					)
					(width 0)
					(fill yes)
				)
			)
		)
		(pad "2" smd custom
			(at 0 0.762 90)
			(size 0.2159 0.2159)
			(layers "F.Cu" "F.Mask" "F.Paste")
			(net "GND")
			(options
				(clearance outline)
				(anchor circle)
			)
			(primitives
				(gr_poly
					(pts
						(arc
							(start -0.3302 -0.4318)
							(mid -0.402042 -0.402042)
							(end -0.4318 -0.3302)
						)
						(arc
							(start -0.4318 0.3302)
							(mid -0.402042 0.402042)
							(end -0.3302 0.4318)
						)
						(arc
							(start 0.3302 0.4318)
							(mid 0.402042 0.402042)
							(end 0.4318 0.3302)
						)
						(arc
							(start 0.4318 -0.3302)
							(mid 0.402042 -0.402042)
							(end 0.3302 -0.4318)
						)
					)
					(width 0)
					(fill yes)
				)
			)
		)
	)
	(footprint ""
		(layer "F.Cu")
		(at 303.503076 -334.462882)
		(property "Reference" "U12"
			(at 0 0 0)
			(layer "F.SilkS")
			(hide yes)
			(effects
				(font
					(size 1.27 1.27)
				)
			)
		)
		(property "Value" "NCT7368S-GP"
			(at 4.0259 1.5748 0)
			(unlocked yes)
			(layer "F.Fab")
			(hide yes)
			(effects
				(font
					(size 1.016 1.016)
					(thickness 0.1524)
				)
			)
		)
		(property "Device Type" "SOIC8-G3627H69"
			(at 4.0259 0.0508 0)
			(unlocked yes)
			(layer "F.Fab")
			(hide yes)
			(effects
				(font
					(size 1.016 1.016)
					(thickness 0.1524)
				)
			)
		)
		(duplicate_pad_numbers_are_jumpers no)
		(fp_line
			(start -2.8829 -3.6322)
			(end 2.7178 -3.6322)
			(stroke
				(width 0.1524)
				(type default)
			)
			(layer "F.SilkS")
		)
		(fp_line
			(start -2.8829 -0.6223)
			(end -2.2479 0.0127)
			(stroke
				(width 0.1524)
				(type default)
			)
			(layer "F.SilkS")
		)
		(fp_line
			(start -2.8829 0.6477)
			(end -2.8829 -0.6223)
			(stroke
				(width 0.1524)
				(type default)
			)
			(layer "F.SilkS")
		)
		(fp_line
			(start -2.8829 3.6322)
			(end -2.8829 -3.6322)
			(stroke
				(width 0.1524)
				(type default)
			)
			(layer "F.SilkS")
		)
		(fp_line
			(start -2.7051 3.6322)
			(end -2.7051 1.5494)
			(stroke
				(width 0.508)
				(type default)
			)
			(layer "F.SilkS")
		)
		(fp_line
			(start -2.2479 0.0127)
			(end -2.8829 0.6477)
			(stroke
				(width 0.1524)
				(type default)
			)
			(layer "F.SilkS")
		)
		(fp_line
			(start 2.7178 -3.6322)
			(end 2.7178 3.6322)
			(stroke
				(width 0.1524)
				(type default)
			)
			(layer "F.SilkS")
		)
		(fp_line
			(start 2.7178 3.6322)
			(end -2.8829 3.6322)
			(stroke
				(width 0.1524)
				(type default)
			)
			(layer "F.SilkS")
		)
		(fp_poly
			(pts
				(xy -2.1209 2.9972) (xy -2.1209 1.9558) (xy -2.4511 1.9558) (xy -2.4511 -1.9558) (xy -2.1209 -1.9558)
				(xy -2.1209 -2.9972) (xy 2.1209 -2.9972) (xy 2.1209 -1.9558) (xy 2.4511 -1.9558) (xy 2.4511 1.9558)
				(xy 2.1209 1.9558) (xy 2.1209 2.9972)
			)
			(stroke
				(width 0)
				(type default)
			)
			(fill no)
			(layer "F.CrtYd")
		)
		(fp_poly
			(pts
				(xy -2.9591 3.8862) (xy -2.9591 -3.8862) (xy 2.9591 -3.8862) (xy 2.9591 1.95072) (xy 2.4511 1.95072)
				(xy 2.4511 -1.9558) (xy 2.1209 -1.9558) (xy 2.1209 -2.9972) (xy -2.1209 -2.9972) (xy -2.1209 -1.9558)
				(xy -2.4511 -1.9558) (xy -2.4511 1.9558) (xy -2.1209 1.9558) (xy -2.1209 2.9972) (xy 2.1209 2.9972)
				(xy 2.1209 1.9558) (xy 2.9591 1.9558) (xy 2.9591 3.8862)
			)
			(stroke
				(width 0)
				(type default)
			)
			(fill no)
			(layer "F.CrtYd")
		)
		(fp_rect
			(start -2.9591 3.8862)
			(end 2.9591 -3.8862)
			(stroke
				(width 0)
				(type default)
			)
			(fill no)
			(layer "F.Fab")
		)
		(pad "1" smd rect
			(at -1.905 2.5527)
			(size 0.635 1.651)
			(layers "F.Cu" "F.Mask" "F.Paste")
			(net "P3V3_IN")
		)
		(pad "2" smd rect
			(at -0.635 2.5527)
			(size 0.635 1.651)
			(layers "F.Cu" "F.Mask" "F.Paste")
			(net "PWM_SCC_A_ZONE_C")
		)
		(pad "3" smd rect
			(at 0.635 2.5527)
			(size 0.635 1.651)
			(layers "F.Cu" "F.Mask" "F.Paste")
			(net "PWM_BMC_A_ZONE_C")
		)
		(pad "4" smd rect
			(at 1.905 2.5527)
			(size 0.635 1.651)
			(layers "F.Cu" "F.Mask" "F.Paste")
			(net "PWM_BMC_B_ZONE_C")
		)
		(pad "5" smd rect
			(at 1.905 -2.5527)
			(size 0.635 1.651)
			(layers "F.Cu" "F.Mask" "F.Paste")
			(net "PWM_CAMP_SEL1")
		)
		(pad "6" smd rect
			(at 0.635 -2.5527)
			(size 0.635 1.651)
			(layers "F.Cu" "F.Mask" "F.Paste")
			(net "THERMHOT#_C")
		)
		(pad "7" smd rect
			(at -0.635 -2.5527)
			(size 0.635 1.651)
			(layers "F.Cu" "F.Mask" "F.Paste")
			(net "PWM_OUT_C_R")
		)
		(pad "8" smd rect
			(at -1.905 -2.5527)
			(size 0.635 1.651)
			(layers "F.Cu" "F.Mask" "F.Paste")
			(net "PWM_SCC_B_ZONE_C")
		)
		(pad "9" smd rect
			(at 0 0)
			(size 3.6068 2.6924)
			(layers "F.Cu" "F.Mask" "F.Paste")
			(net "GND")
		)
	)
	(footprint ""
		(layer "F.Cu")
		(at 398.907 -128.651 180)
		(property "Reference" "R540"
			(at 0 0 180)
			(layer "F.SilkS")
			(hide yes)
			(effects
				(font
					(size 1.27 1.27)
				)
			)
		)
		(property "Value" "0R2J-2-GP"
			(at 0.064008 -3.993896 180)
			(unlocked yes)
			(layer "F.Fab")
			(hide yes)
			(effects
				(font
					(size 1.016 1.016)
					(thickness 0.1524)
				)
			)
		)
		(property "Device Type" "R402H16"
			(at 0.064008 -5.517896 180)
			(unlocked yes)
			(layer "F.Fab")
			(hide yes)
			(effects
				(font
					(size 1.016 1.016)
					(thickness 0.1524)
				)
			)
		)
		(duplicate_pad_numbers_are_jumpers no)
		(fp_line
			(start 0.508 -0.9398)
			(end -0.508 -0.9398)
			(stroke
				(width 0.1524)
				(type default)
			)
			(layer "F.SilkS")
		)
		(fp_line
			(start -0.508 -0.9398)
			(end -0.508 0.9398)
			(stroke
				(width 0.1524)
				(type default)
			)
			(layer "F.SilkS")
		)
		(fp_rect
			(start -0.508 0.9398)
			(end 0.508 -0.9398)
			(stroke
				(width 0)
				(type default)
			)
			(fill no)
			(layer "F.CrtYd")
		)
		(fp_rect
			(start -0.508 0.9398)
			(end 0.508 -0.9398)
			(stroke
				(width 0)
				(type default)
			)
			(fill no)
			(layer "F.Fab")
		)
		(pad "1" smd custom
			(at 0 -0.4445 180)
			(size 0.1397 0.1397)
			(layers "F.Cu" "F.Mask" "F.Paste")
			(net "DRIVE_B_20_PWR")
			(options
				(clearance outline)
				(anchor circle)
			)
			(primitives
				(gr_poly
					(pts
						(arc
							(start -0.1778 -0.2794)
							(mid -0.249642 -0.249642)
							(end -0.2794 -0.1778)
						)
						(arc
							(start -0.2794 0.1778)
							(mid -0.249642 0.249642)
							(end -0.1778 0.2794)
						)
						(arc
							(start 0.1778 0.2794)
							(mid 0.249642 0.249642)
							(end 0.2794 0.1778)
						)
						(arc
							(start 0.2794 -0.1778)
							(mid 0.249642 -0.249642)
							(end 0.1778 -0.2794)
						)
					)
					(width 0)
					(fill yes)
				)
			)
		)
		(pad "2" smd custom
			(at 0 0.4445 180)
			(size 0.1397 0.1397)
			(layers "F.Cu" "F.Mask" "F.Paste")
			(net "SW_PWR_R_HDD20")
			(options
				(clearance outline)
				(anchor circle)
			)
			(primitives
				(gr_poly
					(pts
						(arc
							(start -0.1778 -0.2794)
							(mid -0.249642 -0.249642)
							(end -0.2794 -0.1778)
						)
						(arc
							(start -0.2794 0.1778)
							(mid -0.249642 0.249642)
							(end -0.1778 0.2794)
						)
						(arc
							(start 0.1778 0.2794)
							(mid 0.249642 0.249642)
							(end 0.2794 0.1778)
						)
						(arc
							(start 0.2794 -0.1778)
							(mid 0.249642 -0.249642)
							(end 0.1778 -0.2794)
						)
					)
					(width 0)
					(fill yes)
				)
			)
		)
	)
	(footprint ""
		(layer "F.Cu")
		(at 340.251796 -212.390228 -90)
		(property "Reference" "R261"
			(at 0 0 270)
			(layer "F.SilkS")
			(hide yes)
			(effects
				(font
					(size 1.27 1.27)
				)
			)
		)
		(property "Value" "4K7R2F-GP"
			(at 0.064008 -3.993896 270)
			(unlocked yes)
			(layer "F.Fab")
			(hide yes)
			(effects
				(font
					(size 1.016 1.016)
					(thickness 0.1524)
				)
			)
		)
		(property "Device Type" "R402H16"
			(at 0.064008 -5.517896 270)
			(unlocked yes)
			(layer "F.Fab")
			(hide yes)
			(effects
				(font
					(size 1.016 1.016)
					(thickness 0.1524)
				)
			)
		)
		(duplicate_pad_numbers_are_jumpers no)
		(fp_line
			(start -0.508 -0.9398)
			(end -0.508 0.9398)
			(stroke
				(width 0.1524)
				(type default)
			)
			(layer "F.SilkS")
		)
		(fp_line
			(start 0.508 -0.9398)
			(end -0.508 -0.9398)
			(stroke
				(width 0.1524)
				(type default)
			)
			(layer "F.SilkS")
		)
		(fp_rect
			(start -0.508 0.9398)
			(end 0.508 -0.9398)
			(stroke
				(width 0)
				(type default)
			)
			(fill no)
			(layer "F.CrtYd")
		)
		(fp_rect
			(start -0.508 0.9398)
			(end 0.508 -0.9398)
			(stroke
				(width 0)
				(type default)
			)
			(fill no)
			(layer "F.Fab")
		)
		(pad "1" smd custom
			(at 0 -0.4445 270)
			(size 0.1397 0.1397)
			(layers "F.Cu" "F.Mask" "F.Paste")
			(net "DRIVE_B_7_ACT")
			(options
				(clearance outline)
				(anchor circle)
			)
			(primitives
				(gr_poly
					(pts
						(arc
							(start -0.1778 -0.2794)
							(mid -0.249642 -0.249642)
							(end -0.2794 -0.1778)
						)
						(arc
							(start -0.2794 0.1778)
							(mid -0.249642 0.249642)
							(end -0.1778 0.2794)
						)
						(arc
							(start 0.1778 0.2794)
							(mid 0.249642 0.249642)
							(end 0.2794 0.1778)
						)
						(arc
							(start 0.2794 -0.1778)
							(mid 0.249642 -0.249642)
							(end 0.1778 -0.2794)
						)
					)
					(width 0)
					(fill yes)
				)
			)
		)
		(pad "2" smd custom
			(at 0 0.4445 270)
			(size 0.1397 0.1397)
			(layers "F.Cu" "F.Mask" "F.Paste")
			(net "GND")
			(options
				(clearance outline)
				(anchor circle)
			)
			(primitives
				(gr_poly
					(pts
						(arc
							(start -0.1778 -0.2794)
							(mid -0.249642 -0.249642)
							(end -0.2794 -0.1778)
						)
						(arc
							(start -0.2794 0.1778)
							(mid -0.249642 0.249642)
							(end -0.1778 0.2794)
						)
						(arc
							(start 0.1778 0.2794)
							(mid 0.249642 0.249642)
							(end 0.2794 0.1778)
						)
						(arc
							(start 0.2794 -0.1778)
							(mid 0.249642 -0.249642)
							(end 0.1778 -0.2794)
						)
					)
					(width 0)
					(fill yes)
				)
			)
		)
	)
	(footprint ""
		(layer "F.Cu")
		(at 241.681 -311.912 180)
		(property "Reference" "R1093"
			(at 0 0 180)
			(layer "F.SilkS")
			(hide yes)
			(effects
				(font
					(size 1.27 1.27)
				)
			)
		)
		(property "Value" "0R2J-2-GP"
			(at 0.064008 -3.993896 180)
			(unlocked yes)
			(layer "F.Fab")
			(hide yes)
			(effects
				(font
					(size 1.016 1.016)
					(thickness 0.1524)
				)
			)
		)
		(property "Device Type" "R402H16"
			(at 0.064008 -5.517896 180)
			(unlocked yes)
			(layer "F.Fab")
			(hide yes)
			(effects
				(font
					(size 1.016 1.016)
					(thickness 0.1524)
				)
			)
		)
		(duplicate_pad_numbers_are_jumpers no)
		(fp_line
			(start 0.508 -0.9398)
			(end -0.508 -0.9398)
			(stroke
				(width 0.1524)
				(type default)
			)
			(layer "F.SilkS")
		)
		(fp_line
			(start -0.508 -0.9398)
			(end -0.508 0.9398)
			(stroke
				(width 0.1524)
				(type default)
			)
			(layer "F.SilkS")
		)
		(fp_rect
			(start -0.508 0.9398)
			(end 0.508 -0.9398)
			(stroke
				(width 0)
				(type default)
			)
			(fill no)
			(layer "F.CrtYd")
		)
		(fp_rect
			(start -0.508 0.9398)
			(end 0.508 -0.9398)
			(stroke
				(width 0)
				(type default)
			)
			(fill no)
			(layer "F.Fab")
		)
		(pad "1" smd custom
			(at 0 -0.4445 180)
			(size 0.1397 0.1397)
			(layers "F.Cu" "F.Mask" "F.Paste")
			(net "MAX31790_A_ADD0")
			(options
				(clearance outline)
				(anchor circle)
			)
			(primitives
				(gr_poly
					(pts
						(arc
							(start -0.1778 -0.2794)
							(mid -0.249642 -0.249642)
							(end -0.2794 -0.1778)
						)
						(arc
							(start -0.2794 0.1778)
							(mid -0.249642 0.249642)
							(end -0.1778 0.2794)
						)
						(arc
							(start 0.1778 0.2794)
							(mid 0.249642 0.249642)
							(end 0.2794 0.1778)
						)
						(arc
							(start 0.2794 -0.1778)
							(mid 0.249642 -0.249642)
							(end 0.1778 -0.2794)
						)
					)
					(width 0)
					(fill yes)
				)
			)
		)
		(pad "2" smd custom
			(at 0 0.4445 180)
			(size 0.1397 0.1397)
			(layers "F.Cu" "F.Mask" "F.Paste")
			(net "GND")
			(options
				(clearance outline)
				(anchor circle)
			)
			(primitives
				(gr_poly
					(pts
						(arc
							(start -0.1778 -0.2794)
							(mid -0.249642 -0.249642)
							(end -0.2794 -0.1778)
						)
						(arc
							(start -0.2794 0.1778)
							(mid -0.249642 0.249642)
							(end -0.1778 0.2794)
						)
						(arc
							(start 0.1778 0.2794)
							(mid 0.249642 0.249642)
							(end 0.2794 0.1778)
						)
						(arc
							(start 0.2794 -0.1778)
							(mid 0.249642 -0.249642)
							(end 0.1778 -0.2794)
						)
					)
					(width 0)
					(fill yes)
				)
			)
		)
	)
	(footprint ""
		(layer "F.Cu")
		(at 367.284 -131.826 180)
		(property "Reference" "R524"
			(at 0 0 180)
			(layer "F.SilkS")
			(hide yes)
			(effects
				(font
					(size 1.27 1.27)
				)
			)
		)
		(property "Value" "0R2J-2-GP"
			(at 0.064008 -3.993896 180)
			(unlocked yes)
			(layer "F.Fab")
			(hide yes)
			(effects
				(font
					(size 1.016 1.016)
					(thickness 0.1524)
				)
			)
		)
		(property "Device Type" "R402H16"
			(at 0.064008 -5.517896 180)
			(unlocked yes)
			(layer "F.Fab")
			(hide yes)
			(effects
				(font
					(size 1.016 1.016)
					(thickness 0.1524)
				)
			)
		)
		(duplicate_pad_numbers_are_jumpers no)
		(fp_line
			(start 0.508 -0.9398)
			(end -0.508 -0.9398)
			(stroke
				(width 0.1524)
				(type default)
			)
			(layer "F.SilkS")
		)
		(fp_line
			(start -0.508 -0.9398)
			(end -0.508 0.9398)
			(stroke
				(width 0.1524)
				(type default)
			)
			(layer "F.SilkS")
		)
		(fp_rect
			(start -0.508 0.9398)
			(end 0.508 -0.9398)
			(stroke
				(width 0)
				(type default)
			)
			(fill no)
			(layer "F.CrtYd")
		)
		(fp_rect
			(start -0.508 0.9398)
			(end 0.508 -0.9398)
			(stroke
				(width 0)
				(type default)
			)
			(fill no)
			(layer "F.Fab")
		)
		(pad "1" smd custom
			(at 0 -0.4445 180)
			(size 0.1397 0.1397)
			(layers "F.Cu" "F.Mask" "F.Paste")
			(net "SW_HDD_G19")
			(options
				(clearance outline)
				(anchor circle)
			)
			(primitives
				(gr_poly
					(pts
						(arc
							(start -0.1778 -0.2794)
							(mid -0.249642 -0.249642)
							(end -0.2794 -0.1778)
						)
						(arc
							(start -0.2794 0.1778)
							(mid -0.249642 0.249642)
							(end -0.1778 0.2794)
						)
						(arc
							(start 0.1778 0.2794)
							(mid 0.249642 0.249642)
							(end 0.2794 0.1778)
						)
						(arc
							(start 0.2794 -0.1778)
							(mid 0.249642 -0.249642)
							(end 0.1778 -0.2794)
						)
					)
					(width 0)
					(fill yes)
				)
			)
		)
		(pad "2" smd custom
			(at 0 0.4445 180)
			(size 0.1397 0.1397)
			(layers "F.Cu" "F.Mask" "F.Paste")
			(net "SW_HDD_R19")
			(options
				(clearance outline)
				(anchor circle)
			)
			(primitives
				(gr_poly
					(pts
						(arc
							(start -0.1778 -0.2794)
							(mid -0.249642 -0.249642)
							(end -0.2794 -0.1778)
						)
						(arc
							(start -0.2794 0.1778)
							(mid -0.249642 0.249642)
							(end -0.1778 0.2794)
						)
						(arc
							(start 0.1778 0.2794)
							(mid 0.249642 0.249642)
							(end 0.2794 0.1778)
						)
						(arc
							(start 0.2794 -0.1778)
							(mid 0.249642 -0.249642)
							(end 0.1778 -0.2794)
						)
					)
					(width 0)
					(fill yes)
				)
			)
		)
	)
	(footprint ""
		(layer "F.Cu")
		(at 378.968 -99.187)
		(property "Reference" "R443"
			(at 0 0 0)
			(layer "F.SilkS")
			(hide yes)
			(effects
				(font
					(size 1.27 1.27)
				)
			)
		)
		(property "Value" "91R3F-1-GP"
			(at -0.0254 -2.5146 0)
			(unlocked yes)
			(layer "F.Fab")
			(hide yes)
			(effects
				(font
					(size 1.016 1.016)
					(thickness 0.1524)
				)
			)
		)
		(property "Device Type" "R603H22"
			(at -0.0254 -4.0386 0)
			(unlocked yes)
			(layer "F.Fab")
			(hide yes)
			(effects
				(font
					(size 1.016 1.016)
					(thickness 0.1524)
				)
			)
		)
		(duplicate_pad_numbers_are_jumpers no)
		(fp_line
			(start -0.4826 0)
			(end -0.2032 0)
			(stroke
				(width 0.2032)
				(type default)
			)
			(layer "F.SilkS")
		)
		(fp_line
			(start 0.2032 0)
			(end 0.4826 0)
			(stroke
				(width 0.2032)
				(type default)
			)
			(layer "F.SilkS")
		)
		(fp_rect
			(start -0.5842 1.3335)
			(end 0.5842 -1.3335)
			(stroke
				(width 0)
				(type default)
			)
			(fill no)
			(layer "F.CrtYd")
		)
		(fp_rect
			(start -0.5842 1.3335)
			(end 0.5842 -1.3335)
			(stroke
				(width 0)
				(type default)
			)
			(fill no)
			(layer "F.Fab")
		)
		(pad "1" smd custom
			(at 0 -0.762)
			(size 0.2159 0.2159)
			(layers "F.Cu" "F.Mask" "F.Paste")
			(net "P5V_B_3")
			(options
				(clearance outline)
				(anchor circle)
			)
			(primitives
				(gr_poly
					(pts
						(arc
							(start -0.3302 -0.4318)
							(mid -0.402042 -0.402042)
							(end -0.4318 -0.3302)
						)
						(arc
							(start -0.4318 0.3302)
							(mid -0.402042 0.402042)
							(end -0.3302 0.4318)
						)
						(arc
							(start 0.3302 0.4318)
							(mid 0.402042 0.402042)
							(end 0.4318 0.3302)
						)
						(arc
							(start 0.4318 -0.3302)
							(mid 0.402042 -0.402042)
							(end 0.3302 -0.4318)
						)
					)
					(width 0)
					(fill yes)
				)
			)
		)
		(pad "2" smd custom
			(at 0 0.762)
			(size 0.2159 0.2159)
			(layers "F.Cu" "F.Mask" "F.Paste")
			(net "DRV_ACT_20")
			(options
				(clearance outline)
				(anchor circle)
			)
			(primitives
				(gr_poly
					(pts
						(arc
							(start -0.3302 -0.4318)
							(mid -0.402042 -0.402042)
							(end -0.4318 -0.3302)
						)
						(arc
							(start -0.4318 0.3302)
							(mid -0.402042 0.402042)
							(end -0.3302 0.4318)
						)
						(arc
							(start 0.3302 0.4318)
							(mid 0.402042 0.402042)
							(end 0.4318 0.3302)
						)
						(arc
							(start 0.4318 -0.3302)
							(mid 0.402042 -0.402042)
							(end 0.3302 -0.4318)
						)
					)
					(width 0)
					(fill yes)
				)
			)
		)
	)
	(footprint ""
		(layer "F.Cu")
		(at 46.482 -254.508 -90)
		(property "Reference" "R185"
			(at 0 0 270)
			(layer "F.SilkS")
			(hide yes)
			(effects
				(font
					(size 1.27 1.27)
				)
			)
		)
		(property "Value" "300KR2F-GP"
			(at 0.064008 -3.993896 270)
			(unlocked yes)
			(layer "F.Fab")
			(hide yes)
			(effects
				(font
					(size 1.016 1.016)
					(thickness 0.1524)
				)
			)
		)
		(property "Device Type" "R402H16"
			(at 0.064008 -5.517896 270)
			(unlocked yes)
			(layer "F.Fab")
			(hide yes)
			(effects
				(font
					(size 1.016 1.016)
					(thickness 0.1524)
				)
			)
		)
		(duplicate_pad_numbers_are_jumpers no)
		(fp_line
			(start -0.508 -0.9398)
			(end -0.508 0.9398)
			(stroke
				(width 0.1524)
				(type default)
			)
			(layer "F.SilkS")
		)
		(fp_line
			(start 0.508 -0.9398)
			(end -0.508 -0.9398)
			(stroke
				(width 0.1524)
				(type default)
			)
			(layer "F.SilkS")
		)
		(fp_rect
			(start -0.508 0.9398)
			(end 0.508 -0.9398)
			(stroke
				(width 0)
				(type default)
			)
			(fill no)
			(layer "F.CrtYd")
		)
		(fp_rect
			(start -0.508 0.9398)
			(end 0.508 -0.9398)
			(stroke
				(width 0)
				(type default)
			)
			(fill no)
			(layer "F.Fab")
		)
		(pad "1" smd custom
			(at 0 -0.4445 270)
			(size 0.1397 0.1397)
			(layers "F.Cu" "F.Mask" "F.Paste")
			(net "SW_HDD_N1")
			(options
				(clearance outline)
				(anchor circle)
			)
			(primitives
				(gr_poly
					(pts
						(arc
							(start -0.1778 -0.2794)
							(mid -0.249642 -0.249642)
							(end -0.2794 -0.1778)
						)
						(arc
							(start -0.2794 0.1778)
							(mid -0.249642 0.249642)
							(end -0.1778 0.2794)
						)
						(arc
							(start 0.1778 0.2794)
							(mid 0.249642 0.249642)
							(end 0.2794 0.1778)
						)
						(arc
							(start 0.2794 -0.1778)
							(mid 0.249642 -0.249642)
							(end 0.1778 -0.2794)
						)
					)
					(width 0)
					(fill yes)
				)
			)
		)
		(pad "2" smd custom
			(at 0 0.4445 270)
			(size 0.1397 0.1397)
			(layers "F.Cu" "F.Mask" "F.Paste")
			(net "P12V_B")
			(options
				(clearance outline)
				(anchor circle)
			)
			(primitives
				(gr_poly
					(pts
						(arc
							(start -0.1778 -0.2794)
							(mid -0.249642 -0.249642)
							(end -0.2794 -0.1778)
						)
						(arc
							(start -0.2794 0.1778)
							(mid -0.249642 0.249642)
							(end -0.1778 0.2794)
						)
						(arc
							(start 0.1778 0.2794)
							(mid 0.249642 0.249642)
							(end 0.2794 0.1778)
						)
						(arc
							(start 0.2794 -0.1778)
							(mid 0.249642 -0.249642)
							(end 0.1778 -0.2794)
						)
					)
					(width 0)
					(fill yes)
				)
			)
		)
	)
	(footprint ""
		(layer "F.Cu")
		(at 209.423 -208.026 -90)
		(property "Reference" "R45"
			(at 0 0 270)
			(layer "F.SilkS")
			(hide yes)
			(effects
				(font
					(size 1.27 1.27)
				)
			)
		)
		(property "Value" "4K7R2F-GP"
			(at 0.064008 -3.993896 270)
			(unlocked yes)
			(layer "F.Fab")
			(hide yes)
			(effects
				(font
					(size 1.016 1.016)
					(thickness 0.1524)
				)
			)
		)
		(property "Device Type" "R402H16"
			(at 0.064008 -5.517896 270)
			(unlocked yes)
			(layer "F.Fab")
			(hide yes)
			(effects
				(font
					(size 1.016 1.016)
					(thickness 0.1524)
				)
			)
		)
		(duplicate_pad_numbers_are_jumpers no)
		(fp_line
			(start -0.508 -0.9398)
			(end -0.508 0.9398)
			(stroke
				(width 0.1524)
				(type default)
			)
			(layer "F.SilkS")
		)
		(fp_line
			(start 0.508 -0.9398)
			(end -0.508 -0.9398)
			(stroke
				(width 0.1524)
				(type default)
			)
			(layer "F.SilkS")
		)
		(fp_rect
			(start -0.508 0.9398)
			(end 0.508 -0.9398)
			(stroke
				(width 0)
				(type default)
			)
			(fill no)
			(layer "F.CrtYd")
		)
		(fp_rect
			(start -0.508 0.9398)
			(end 0.508 -0.9398)
			(stroke
				(width 0)
				(type default)
			)
			(fill no)
			(layer "F.Fab")
		)
		(pad "1" smd custom
			(at 0 -0.4445 270)
			(size 0.1397 0.1397)
			(layers "F.Cu" "F.Mask" "F.Paste")
			(net "IO_EXP5_A0")
			(options
				(clearance outline)
				(anchor circle)
			)
			(primitives
				(gr_poly
					(pts
						(arc
							(start -0.1778 -0.2794)
							(mid -0.249642 -0.249642)
							(end -0.2794 -0.1778)
						)
						(arc
							(start -0.2794 0.1778)
							(mid -0.249642 0.249642)
							(end -0.1778 0.2794)
						)
						(arc
							(start 0.1778 0.2794)
							(mid 0.249642 0.249642)
							(end 0.2794 0.1778)
						)
						(arc
							(start 0.2794 -0.1778)
							(mid 0.249642 -0.249642)
							(end 0.1778 -0.2794)
						)
					)
					(width 0)
					(fill yes)
				)
			)
		)
		(pad "2" smd custom
			(at 0 0.4445 270)
			(size 0.1397 0.1397)
			(layers "F.Cu" "F.Mask" "F.Paste")
			(net "GND")
			(options
				(clearance outline)
				(anchor circle)
			)
			(primitives
				(gr_poly
					(pts
						(arc
							(start -0.1778 -0.2794)
							(mid -0.249642 -0.249642)
							(end -0.2794 -0.1778)
						)
						(arc
							(start -0.2794 0.1778)
							(mid -0.249642 0.249642)
							(end -0.1778 0.2794)
						)
						(arc
							(start 0.1778 0.2794)
							(mid 0.249642 0.249642)
							(end 0.2794 0.1778)
						)
						(arc
							(start 0.2794 -0.1778)
							(mid 0.249642 -0.249642)
							(end 0.1778 -0.2794)
						)
					)
					(width 0)
					(fill yes)
				)
			)
		)
	)
	(footprint ""
		(layer "F.Cu")
		(at 85.5472 -131.2672 -90)
		(property "Reference" "R403"
			(at 0 0 270)
			(layer "F.SilkS")
			(hide yes)
			(effects
				(font
					(size 1.27 1.27)
				)
			)
		)
		(property "Value" "0R2J-2-GP"
			(at 0.064008 -3.993896 270)
			(unlocked yes)
			(layer "F.Fab")
			(hide yes)
			(effects
				(font
					(size 1.016 1.016)
					(thickness 0.1524)
				)
			)
		)
		(property "Device Type" "R402H16"
			(at 0.064008 -5.517896 270)
			(unlocked yes)
			(layer "F.Fab")
			(hide yes)
			(effects
				(font
					(size 1.016 1.016)
					(thickness 0.1524)
				)
			)
		)
		(duplicate_pad_numbers_are_jumpers no)
		(fp_line
			(start -0.508 -0.9398)
			(end -0.508 0.9398)
			(stroke
				(width 0.1524)
				(type default)
			)
			(layer "F.SilkS")
		)
		(fp_line
			(start 0.508 -0.9398)
			(end -0.508 -0.9398)
			(stroke
				(width 0.1524)
				(type default)
			)
			(layer "F.SilkS")
		)
		(fp_rect
			(start -0.508 0.9398)
			(end 0.508 -0.9398)
			(stroke
				(width 0)
				(type default)
			)
			(fill no)
			(layer "F.CrtYd")
		)
		(fp_rect
			(start -0.508 0.9398)
			(end 0.508 -0.9398)
			(stroke
				(width 0)
				(type default)
			)
			(fill no)
			(layer "F.Fab")
		)
		(pad "1" smd custom
			(at 0 -0.4445 270)
			(size 0.1397 0.1397)
			(layers "F.Cu" "F.Mask" "F.Paste")
			(net "DRIVE_B_14_PWR")
			(options
				(clearance outline)
				(anchor circle)
			)
			(primitives
				(gr_poly
					(pts
						(arc
							(start -0.1778 -0.2794)
							(mid -0.249642 -0.249642)
							(end -0.2794 -0.1778)
						)
						(arc
							(start -0.2794 0.1778)
							(mid -0.249642 0.249642)
							(end -0.1778 0.2794)
						)
						(arc
							(start 0.1778 0.2794)
							(mid 0.249642 0.249642)
							(end 0.2794 0.1778)
						)
						(arc
							(start 0.2794 -0.1778)
							(mid 0.249642 -0.249642)
							(end 0.1778 -0.2794)
						)
					)
					(width 0)
					(fill yes)
				)
			)
		)
		(pad "2" smd custom
			(at 0 0.4445 270)
			(size 0.1397 0.1397)
			(layers "F.Cu" "F.Mask" "F.Paste")
			(net "SW_PWR_R_HDD14")
			(options
				(clearance outline)
				(anchor circle)
			)
			(primitives
				(gr_poly
					(pts
						(arc
							(start -0.1778 -0.2794)
							(mid -0.249642 -0.249642)
							(end -0.2794 -0.1778)
						)
						(arc
							(start -0.2794 0.1778)
							(mid -0.249642 0.249642)
							(end -0.1778 0.2794)
						)
						(arc
							(start 0.1778 0.2794)
							(mid 0.249642 0.249642)
							(end 0.2794 0.1778)
						)
						(arc
							(start 0.2794 -0.1778)
							(mid 0.249642 -0.249642)
							(end 0.1778 -0.2794)
						)
					)
					(width 0)
					(fill yes)
				)
			)
		)
	)
	(footprint ""
		(layer "F.Cu")
		(at 410.464 -214.249)
		(property "Reference" "R349"
			(at 0 0 0)
			(layer "F.SilkS")
			(hide yes)
			(effects
				(font
					(size 1.27 1.27)
				)
			)
		)
		(property "Value" "91R3F-1-GP"
			(at -0.0254 -2.5146 0)
			(unlocked yes)
			(layer "F.Fab")
			(hide yes)
			(effects
				(font
					(size 1.016 1.016)
					(thickness 0.1524)
				)
			)
		)
		(property "Device Type" "R603H22"
			(at -0.0254 -4.0386 0)
			(unlocked yes)
			(layer "F.Fab")
			(hide yes)
			(effects
				(font
					(size 1.016 1.016)
					(thickness 0.1524)
				)
			)
		)
		(duplicate_pad_numbers_are_jumpers no)
		(fp_line
			(start -0.4826 0)
			(end -0.2032 0)
			(stroke
				(width 0.2032)
				(type default)
			)
			(layer "F.SilkS")
		)
		(fp_line
			(start 0.2032 0)
			(end 0.4826 0)
			(stroke
				(width 0.2032)
				(type default)
			)
			(layer "F.SilkS")
		)
		(fp_rect
			(start -0.5842 1.3335)
			(end 0.5842 -1.3335)
			(stroke
				(width 0)
				(type default)
			)
			(fill no)
			(layer "F.CrtYd")
		)
		(fp_rect
			(start -0.5842 1.3335)
			(end 0.5842 -1.3335)
			(stroke
				(width 0)
				(type default)
			)
			(fill no)
			(layer "F.Fab")
		)
		(pad "1" smd custom
			(at 0 -0.762)
			(size 0.2159 0.2159)
			(layers "F.Cu" "F.Mask" "F.Paste")
			(net "P5V_B_3")
			(options
				(clearance outline)
				(anchor circle)
			)
			(primitives
				(gr_poly
					(pts
						(arc
							(start -0.3302 -0.4318)
							(mid -0.402042 -0.402042)
							(end -0.4318 -0.3302)
						)
						(arc
							(start -0.4318 0.3302)
							(mid -0.402042 0.402042)
							(end -0.3302 0.4318)
						)
						(arc
							(start 0.3302 0.4318)
							(mid 0.402042 0.402042)
							(end 0.4318 0.3302)
						)
						(arc
							(start 0.4318 -0.3302)
							(mid 0.402042 -0.402042)
							(end 0.3302 -0.4318)
						)
					)
					(width 0)
					(fill yes)
				)
			)
		)
		(pad "2" smd custom
			(at 0 0.762)
			(size 0.2159 0.2159)
			(layers "F.Cu" "F.Mask" "F.Paste")
			(net "DRV_ACT_9")
			(options
				(clearance outline)
				(anchor circle)
			)
			(primitives
				(gr_poly
					(pts
						(arc
							(start -0.3302 -0.4318)
							(mid -0.402042 -0.402042)
							(end -0.4318 -0.3302)
						)
						(arc
							(start -0.4318 0.3302)
							(mid -0.402042 0.402042)
							(end -0.3302 0.4318)
						)
						(arc
							(start 0.3302 0.4318)
							(mid 0.402042 0.402042)
							(end 0.4318 0.3302)
						)
						(arc
							(start 0.4318 -0.3302)
							(mid 0.402042 -0.402042)
							(end 0.3302 -0.4318)
						)
					)
					(width 0)
					(fill yes)
				)
			)
		)
	)
	(footprint ""
		(layer "F.Cu")
		(at 91.300046 -28.910026 -90)
		(property "Reference" "HDDSAS26"
			(at 0 0 270)
			(layer "F.SilkS")
			(hide yes)
			(effects
				(font
					(size 1.27 1.27)
				)
			)
		)
		(property "Value" "SKT-SAS15P-14P-45-GP"
			(at -20.7645 -8.9789 270)
			(unlocked yes)
			(layer "F.Fab")
			(hide yes)
			(effects
				(font
					(size 1.016 1.016)
					(thickness 0.1524)
				)
			)
		)
		(property "Device Type" "10120818-001C-TRLF"
			(at -20.7645 -10.5029 270)
			(unlocked yes)
			(layer "F.Fab")
			(hide yes)
			(effects
				(font
					(size 1.016 1.016)
					(thickness 0.1524)
				)
			)
		)
		(duplicate_pad_numbers_are_jumpers no)
		(fp_line
			(start 1.651 4.2926)
			(end 1.651 3.0099)
			(stroke
				(width 0.1524)
				(type default)
			)
			(layer "F.SilkS")
		)
		(fp_line
			(start 8.509 4.2926)
			(end 1.651 4.2926)
			(stroke
				(width 0.1524)
				(type default)
			)
			(layer "F.SilkS")
		)
		(fp_line
			(start -23.4188 3.0099)
			(end -23.4188 -3.2512)
			(stroke
				(width 0.1524)
				(type default)
			)
			(layer "F.SilkS")
		)
		(fp_line
			(start 1.651 3.0099)
			(end -23.4188 3.0099)
			(stroke
				(width 0.1524)
				(type default)
			)
			(layer "F.SilkS")
		)
		(fp_line
			(start 8.509 3.0099)
			(end 8.509 4.2926)
			(stroke
				(width 0.1524)
				(type default)
			)
			(layer "F.SilkS")
		)
		(fp_line
			(start 23.4188 3.0099)
			(end 8.509 3.0099)
			(stroke
				(width 0.1524)
				(type default)
			)
			(layer "F.SilkS")
		)
		(fp_line
			(start -23.4188 -3.2512)
			(end 23.4188 -3.2512)
			(stroke
				(width 0.1524)
				(type default)
			)
			(layer "F.SilkS")
		)
		(fp_line
			(start 23.4188 -3.2512)
			(end 23.4188 3.0099)
			(stroke
				(width 0.1524)
				(type default)
			)
			(layer "F.SilkS")
		)
		(fp_line
			(start 15.5067 -3.3401)
			(end 16.2687 -3.3401)
			(stroke
				(width 0.3302)
				(type default)
			)
			(layer "F.SilkS")
		)
		(fp_poly
			(pts
				(xy 15.868904 -3.230372) (xy 16.503904 -3.865372) (xy 15.233904 -3.865372)
			)
			(stroke
				(width 0)
				(type default)
			)
			(fill yes)
			(layer "F.SilkS")
		)
		(fp_poly
			(pts
				(xy -22.8727 -2.7559) (xy 22.8727 -2.7559) (xy 22.8727 2.7559) (xy 8.255 2.7559) (xy 8.255 3.5179)
				(xy 1.905 3.5179) (xy 1.905 2.7559) (xy -22.8727 2.7559)
			)
			(stroke
				(width 0)
				(type default)
			)
			(fill no)
			(layer "F.CrtYd")
		)
		(fp_poly
			(pts
				(xy 1.397 4.5466) (xy 1.397 3.2639) (xy -23.6728 3.2639) (xy -23.6728 -3.5052) (xy 23.6728 -3.5052)
				(xy 23.6728 -0.00635) (xy 22.8727 -0.00635) (xy 22.8727 -2.7559) (xy -22.8727 -2.7559) (xy -22.8727 2.7559)
				(xy 1.905 2.7559) (xy 1.905 3.5179) (xy 8.255 3.5179) (xy 8.255 2.7559) (xy 22.8727 2.7559) (xy 22.8727 0.00635)
				(xy 23.6728 0.00635) (xy 23.6728 3.2639) (xy 8.763 3.2639) (xy 8.763 4.5466)
			)
			(stroke
				(width 0)
				(type default)
			)
			(fill no)
			(layer "F.CrtYd")
		)
		(fp_poly
			(pts
				(xy 1.397 4.5466) (xy 1.397 3.2639) (xy -23.6728 3.2639) (xy -23.6728 -3.5052) (xy 23.6728 -3.5052)
				(xy 23.6728 3.2639) (xy 8.763 3.2639) (xy 8.763 4.5466)
			)
			(stroke
				(width 0)
				(type default)
			)
			(fill no)
			(layer "F.Fab")
		)
		(pad "" np_thru_hole circle
			(at -18.874994 0 270)
			(size 0.254 0.254)
			(drill 1.3462)
			(layers "*.Cu" "*.Mask")
			(clearance 0.9017)
			(thermal_gap 0.9017)
		)
		(pad "" np_thru_hole circle
			(at 18.874994 0 270)
			(size 0.254 0.254)
			(drill 0.9398)
			(layers "*.Cu" "*.Mask")
			(clearance 0.6985)
			(thermal_gap 0.6985)
		)
		(pad "G1" smd rect
			(at 21.874988 0 270)
			(size 2.5908 2.5908)
			(layers "F.Cu" "F.Mask" "F.Paste")
			(net "GND")
		)
		(pad "G2" smd rect
			(at -21.874988 0 270)
			(size 2.5908 2.5908)
			(layers "F.Cu" "F.Mask" "F.Paste")
			(net "GND")
		)
		(pad "P1" smd rect
			(at 1.905 -1.82499 270)
			(size 0.6096 2.3622)
			(layers "F.Cu" "F.Mask" "F.Paste")
			(net "Net_1669")
		)
		(pad "P2" smd rect
			(at 0.635 -1.82499 270)
			(size 0.6096 2.3622)
			(layers "F.Cu" "F.Mask" "F.Paste")
			(net "Net_1670")
		)
		(pad "P3" smd rect
			(at -0.635 -1.82499 270)
			(size 0.6096 2.3622)
			(layers "F.Cu" "F.Mask" "F.Paste")
			(net "Net_1671")
		)
		(pad "P4" smd rect
			(at -1.905 -1.82499 270)
			(size 0.6096 2.3622)
			(layers "F.Cu" "F.Mask" "F.Paste")
			(net "GND")
		)
		(pad "P5" smd rect
			(at -3.175 -1.82499 270)
			(size 0.6096 2.3622)
			(layers "F.Cu" "F.Mask" "F.Paste")
			(net "HDD_PRSNT_26")
		)
		(pad "P6" smd rect
			(at -4.445 -1.82499 270)
			(size 0.6096 2.3622)
			(layers "F.Cu" "F.Mask" "F.Paste")
			(net "GND")
		)
		(pad "P7" smd rect
			(at -5.715 -1.82499 270)
			(size 0.6096 2.3622)
			(layers "F.Cu" "F.Mask" "F.Paste")
			(net "5V_PRE_26")
		)
		(pad "P8" smd rect
			(at -6.985 -1.82499 270)
			(size 0.6096 2.3622)
			(layers "F.Cu" "F.Mask" "F.Paste")
			(net "P5V_HDD26")
		)
		(pad "P9" smd rect
			(at -8.255 -1.82499 270)
			(size 0.6096 2.3622)
			(layers "F.Cu" "F.Mask" "F.Paste")
			(net "P5V_HDD26")
		)
		(pad "P10" smd rect
			(at -9.525 -1.82499 270)
			(size 0.6096 2.3622)
			(layers "F.Cu" "F.Mask" "F.Paste")
			(net "GND")
		)
		(pad "P11" smd rect
			(at -10.795 -1.82499 270)
			(size 0.6096 2.3622)
			(layers "F.Cu" "F.Mask" "F.Paste")
			(net "ACT_HDD_26")
		)
		(pad "P12" smd rect
			(at -12.065 -1.82499 270)
			(size 0.6096 2.3622)
			(layers "F.Cu" "F.Mask" "F.Paste")
			(net "GND")
		)
		(pad "P13" smd rect
			(at -13.335 -1.82499 270)
			(size 0.6096 2.3622)
			(layers "F.Cu" "F.Mask" "F.Paste")
			(net "12V_PRE_26")
		)
		(pad "P14" smd rect
			(at -14.605 -1.82499 270)
			(size 0.6096 2.3622)
			(layers "F.Cu" "F.Mask" "F.Paste")
			(net "P12V_HDD26")
		)
		(pad "P15" smd rect
			(at -15.875 -1.82499 270)
			(size 0.6096 2.3622)
			(layers "F.Cu" "F.Mask" "F.Paste")
			(net "P12V_HDD26")
		)
		(pad "S1" smd rect
			(at 15.875 -1.82499 270)
			(size 0.6096 2.3622)
			(layers "F.Cu" "F.Mask" "F.Paste")
			(net "GND")
		)
		(pad "S2" smd rect
			(at 14.605 -1.82499 270)
			(size 0.6096 2.3622)
			(layers "F.Cu" "F.Mask" "F.Paste")
			(net "SAS_HDD_RX_P26")
		)
		(pad "S3" smd rect
			(at 13.335 -1.82499 270)
			(size 0.6096 2.3622)
			(layers "F.Cu" "F.Mask" "F.Paste")
			(net "SAS_HDD_RX_N26")
		)
		(pad "S4" smd rect
			(at 12.065 -1.82499 270)
			(size 0.6096 2.3622)
			(layers "F.Cu" "F.Mask" "F.Paste")
			(net "GND")
		)
		(pad "S5" smd rect
			(at 10.795 -1.82499 270)
			(size 0.6096 2.3622)
			(layers "F.Cu" "F.Mask" "F.Paste")
			(net "PHY_DRV_B_TO_SCC_B_26_DN")
		)
		(pad "S6" smd rect
			(at 9.525 -1.82499 270)
			(size 0.6096 2.3622)
			(layers "F.Cu" "F.Mask" "F.Paste")
			(net "PHY_DRV_B_TO_SCC_B_26_DP")
		)
		(pad "S7" smd rect
			(at 8.255 -1.82499 270)
			(size 0.6096 2.3622)
			(layers "F.Cu" "F.Mask" "F.Paste")
			(net "GND")
		)
		(pad "S8" smd rect
			(at 7.480046 2.845054 270)
			(size 0.508 2.3622)
			(layers "F.Cu" "F.Mask" "F.Paste")
			(net "GND")
		)
		(pad "S9" smd rect
			(at 6.679946 2.845054 270)
			(size 0.508 2.3622)
			(layers "F.Cu" "F.Mask" "F.Paste")
			(net "Net_450")
		)
		(pad "S10" smd rect
			(at 5.8801 2.845054 270)
			(size 0.508 2.3622)
			(layers "F.Cu" "F.Mask" "F.Paste")
			(net "Net_342")
		)
		(pad "S11" smd rect
			(at 5.08 2.845054 270)
			(size 0.508 2.3622)
			(layers "F.Cu" "F.Mask" "F.Paste")
			(net "GND")
		)
		(pad "S12" smd rect
			(at 4.2799 2.845054 270)
			(size 0.508 2.3622)
			(layers "F.Cu" "F.Mask" "F.Paste")
			(net "Net_378")
		)
		(pad "S13" smd rect
			(at 3.480054 2.845054 270)
			(size 0.508 2.3622)
			(layers "F.Cu" "F.Mask" "F.Paste")
			(net "Net_414")
		)
		(pad "S14" smd rect
			(at 2.679954 2.845054 270)
			(size 0.508 2.3622)
			(layers "F.Cu" "F.Mask" "F.Paste")
			(net "GND")
		)
		(zone
			(layer "F.Cu")
			(hatch none 0.5)
			(connect_pads
				(clearance 0)
			)
			(min_thickness 0.25)
			(keepout
				(tracks allowed)
				(vias not_allowed)
				(pads allowed)
				(copperpour not_allowed)
				(footprints allowed)
			)
			(placement
				(enabled no)
				(sheetname "")
			)
			(fill
				(thermal_gap 0.5)
				(thermal_bridge_width 0.5)
				(island_removal_mode 0)
			)
			(polygon
				(pts
					(xy 94.957646 -45.648626) (xy 87.883746 -45.648626) (xy 87.883746 -52.582826) (xy 88.988646 -52.582826)
					(xy 88.988646 -48.468026) (xy 93.611446 -48.468026) (xy 93.611446 -52.582826) (xy 94.957646 -52.582826)
				)
			)
		)
		(zone
			(layer "F.Cu")
			(hatch none 0.5)
			(connect_pads
				(clearance 0)
			)
			(min_thickness 0.25)
			(keepout
				(tracks not_allowed)
				(vias allowed)
				(pads allowed)
				(copperpour not_allowed)
				(footprints allowed)
			)
			(placement
				(enabled no)
				(sheetname "")
			)
			(fill
				(thermal_gap 0.5)
				(thermal_bridge_width 0.5)
				(island_removal_mode 0)
			)
			(polygon
				(pts
					(xy 94.957646 -45.648626) (xy 87.883746 -45.648626) (xy 87.883746 -52.582826) (xy 88.988646 -52.582826)
					(xy 88.988646 -48.468026) (xy 93.611446 -48.468026) (xy 93.611446 -52.582826) (xy 94.957646 -52.582826)
				)
			)
		)
		(zone
			(layer "F.Cu")
			(hatch none 0.5)
			(connect_pads
				(clearance 0)
			)
			(min_thickness 0.25)
			(keepout
				(tracks allowed)
				(vias not_allowed)
				(pads allowed)
				(copperpour not_allowed)
				(footprints allowed)
			)
			(placement
				(enabled no)
				(sheetname "")
			)
			(fill
				(thermal_gap 0.5)
				(thermal_bridge_width 0.5)
				(island_removal_mode 0)
			)
			(polygon
				(pts
					(xy 94.957646 -12.171426) (xy 87.883746 -12.171426) (xy 87.883746 -5.237226) (xy 88.988646 -5.237226)
					(xy 88.988646 -9.352026) (xy 93.611446 -9.352026) (xy 93.611446 -5.237226) (xy 94.957646 -5.237226)
				)
			)
		)
		(zone
			(layer "F.Cu")
			(hatch none 0.5)
			(connect_pads
				(clearance 0)
			)
			(min_thickness 0.25)
			(keepout
				(tracks not_allowed)
				(vias allowed)
				(pads allowed)
				(copperpour not_allowed)
				(footprints allowed)
			)
			(placement
				(enabled no)
				(sheetname "")
			)
			(fill
				(thermal_gap 0.5)
				(thermal_bridge_width 0.5)
				(island_removal_mode 0)
			)
			(polygon
				(pts
					(xy 94.957646 -12.171426) (xy 87.883746 -12.171426) (xy 87.883746 -5.237226) (xy 88.988646 -5.237226)
					(xy 88.988646 -9.352026) (xy 93.611446 -9.352026) (xy 93.611446 -5.237226) (xy 94.957646 -5.237226)
				)
			)
		)
		(zone
			(layers "F.Cu" "B.Cu" "In1.Cu" "In2.Cu" "In3.Cu" "In4.Cu" "In5.Cu" "In6.Cu")
			(hatch none 0.5)
			(connect_pads
				(clearance 0)
			)
			(min_thickness 0.25)
			(keepout
				(tracks not_allowed)
				(vias allowed)
				(pads allowed)
				(copperpour not_allowed)
				(footprints allowed)
			)
			(placement
				(enabled no)
				(sheetname "")
			)
			(fill
				(thermal_gap 0.5)
				(thermal_bridge_width 0.5)
				(island_removal_mode 0)
			)
			(polygon
				(pts
					(arc
						(start 92.074746 -10.035032)
						(mid 90.525346 -10.035032)
						(end 92.074746 -10.035032)
					)
				)
			)
		)
		(zone
			(layers "F.Cu" "B.Cu" "In1.Cu" "In2.Cu" "In3.Cu" "In4.Cu" "In5.Cu" "In6.Cu")
			(hatch none 0.5)
			(connect_pads
				(clearance 0)
			)
			(min_thickness 0.25)
			(keepout
				(tracks not_allowed)
				(vias allowed)
				(pads allowed)
				(copperpour not_allowed)
				(footprints allowed)
			)
			(placement
				(enabled no)
				(sheetname "")
			)
			(fill
				(thermal_gap 0.5)
				(thermal_bridge_width 0.5)
				(island_removal_mode 0)
			)
			(polygon
				(pts
					(arc
						(start 92.277946 -47.78502)
						(mid 90.322146 -47.78502)
						(end 92.277946 -47.78502)
					)
				)
			)
		)
	)
	(footprint ""
		(layer "F.Cu")
		(at 147.548092 -212.44687 -90)
		(property "Reference" "R213"
			(at 0 0 270)
			(layer "F.SilkS")
			(hide yes)
			(effects
				(font
					(size 1.27 1.27)
				)
			)
		)
		(property "Value" "4K7R2F-GP"
			(at 0.064008 -3.993896 270)
			(unlocked yes)
			(layer "F.Fab")
			(hide yes)
			(effects
				(font
					(size 1.016 1.016)
					(thickness 0.1524)
				)
			)
		)
		(property "Device Type" "R402H16"
			(at 0.064008 -5.517896 270)
			(unlocked yes)
			(layer "F.Fab")
			(hide yes)
			(effects
				(font
					(size 1.016 1.016)
					(thickness 0.1524)
				)
			)
		)
		(duplicate_pad_numbers_are_jumpers no)
		(fp_line
			(start -0.508 -0.9398)
			(end -0.508 0.9398)
			(stroke
				(width 0.1524)
				(type default)
			)
			(layer "F.SilkS")
		)
		(fp_line
			(start 0.508 -0.9398)
			(end -0.508 -0.9398)
			(stroke
				(width 0.1524)
				(type default)
			)
			(layer "F.SilkS")
		)
		(fp_rect
			(start -0.508 0.9398)
			(end 0.508 -0.9398)
			(stroke
				(width 0)
				(type default)
			)
			(fill no)
			(layer "F.CrtYd")
		)
		(fp_rect
			(start -0.508 0.9398)
			(end 0.508 -0.9398)
			(stroke
				(width 0)
				(type default)
			)
			(fill no)
			(layer "F.Fab")
		)
		(pad "1" smd custom
			(at 0 -0.4445 270)
			(size 0.1397 0.1397)
			(layers "F.Cu" "F.Mask" "F.Paste")
			(net "DRIVE_B_4_ACT")
			(options
				(clearance outline)
				(anchor circle)
			)
			(primitives
				(gr_poly
					(pts
						(arc
							(start -0.1778 -0.2794)
							(mid -0.249642 -0.249642)
							(end -0.2794 -0.1778)
						)
						(arc
							(start -0.2794 0.1778)
							(mid -0.249642 0.249642)
							(end -0.1778 0.2794)
						)
						(arc
							(start 0.1778 0.2794)
							(mid 0.249642 0.249642)
							(end 0.2794 0.1778)
						)
						(arc
							(start 0.2794 -0.1778)
							(mid 0.249642 -0.249642)
							(end 0.1778 -0.2794)
						)
					)
					(width 0)
					(fill yes)
				)
			)
		)
		(pad "2" smd custom
			(at 0 0.4445 270)
			(size 0.1397 0.1397)
			(layers "F.Cu" "F.Mask" "F.Paste")
			(net "GND")
			(options
				(clearance outline)
				(anchor circle)
			)
			(primitives
				(gr_poly
					(pts
						(arc
							(start -0.1778 -0.2794)
							(mid -0.249642 -0.249642)
							(end -0.2794 -0.1778)
						)
						(arc
							(start -0.2794 0.1778)
							(mid -0.249642 0.249642)
							(end -0.1778 0.2794)
						)
						(arc
							(start 0.1778 0.2794)
							(mid 0.249642 0.249642)
							(end 0.2794 0.1778)
						)
						(arc
							(start 0.2794 -0.1778)
							(mid 0.249642 -0.249642)
							(end 0.1778 -0.2794)
						)
					)
					(width 0)
					(fill yes)
				)
			)
		)
	)
	(footprint ""
		(layer "F.Cu")
		(at 83.3374 -148.717 -90)
		(property "Reference" "C212"
			(at 0 0 270)
			(layer "F.SilkS")
			(hide yes)
			(effects
				(font
					(size 1.27 1.27)
				)
			)
		)
		(property "Value" "SC1U16V3KX-5GP"
			(at 0 -2.8194 270)
			(unlocked yes)
			(layer "F.Fab")
			(hide yes)
			(effects
				(font
					(size 1.016 1.016)
					(thickness 0.1524)
				)
			)
		)
		(property "Device Type" "C603H36"
			(at 0 -4.3434 270)
			(unlocked yes)
			(layer "F.Fab")
			(hide yes)
			(effects
				(font
					(size 1.016 1.016)
					(thickness 0.1524)
				)
			)
		)
		(duplicate_pad_numbers_are_jumpers no)
		(fp_line
			(start 0.508 0)
			(end -0.508 0)
			(stroke
				(width 0.2032)
				(type default)
			)
			(layer "F.SilkS")
		)
		(fp_rect
			(start -0.5842 1.3335)
			(end 0.5842 -1.3335)
			(stroke
				(width 0)
				(type default)
			)
			(fill no)
			(layer "F.CrtYd")
		)
		(fp_rect
			(start -0.5842 1.3335)
			(end 0.5842 -1.3335)
			(stroke
				(width 0)
				(type default)
			)
			(fill no)
			(layer "F.Fab")
		)
		(pad "1" smd custom
			(at 0 -0.762 270)
			(size 0.2159 0.2159)
			(layers "F.Cu" "F.Mask" "F.Paste")
			(net "P5V_HDD14")
			(options
				(clearance outline)
				(anchor circle)
			)
			(primitives
				(gr_poly
					(pts
						(arc
							(start -0.3302 -0.4318)
							(mid -0.402042 -0.402042)
							(end -0.4318 -0.3302)
						)
						(arc
							(start -0.4318 0.3302)
							(mid -0.402042 0.402042)
							(end -0.3302 0.4318)
						)
						(arc
							(start 0.3302 0.4318)
							(mid 0.402042 0.402042)
							(end 0.4318 0.3302)
						)
						(arc
							(start 0.4318 -0.3302)
							(mid 0.402042 -0.402042)
							(end 0.3302 -0.4318)
						)
					)
					(width 0)
					(fill yes)
				)
			)
		)
		(pad "2" smd custom
			(at 0 0.762 270)
			(size 0.2159 0.2159)
			(layers "F.Cu" "F.Mask" "F.Paste")
			(net "GND")
			(options
				(clearance outline)
				(anchor circle)
			)
			(primitives
				(gr_poly
					(pts
						(arc
							(start -0.3302 -0.4318)
							(mid -0.402042 -0.402042)
							(end -0.4318 -0.3302)
						)
						(arc
							(start -0.4318 0.3302)
							(mid -0.402042 0.402042)
							(end -0.3302 0.4318)
						)
						(arc
							(start 0.3302 0.4318)
							(mid 0.402042 0.402042)
							(end 0.4318 0.3302)
						)
						(arc
							(start 0.4318 -0.3302)
							(mid 0.402042 -0.402042)
							(end 0.3302 -0.4318)
						)
					)
					(width 0)
					(fill yes)
				)
			)
		)
	)
	(footprint ""
		(layer "F.Cu")
		(at 149.1996 -133.4516 -90)
		(property "Reference" "R446"
			(at 0 0 270)
			(layer "F.SilkS")
			(hide yes)
			(effects
				(font
					(size 1.27 1.27)
				)
			)
		)
		(property "Value" "1KR2F-3-GP"
			(at 0.064008 -3.993896 270)
			(unlocked yes)
			(layer "F.Fab")
			(hide yes)
			(effects
				(font
					(size 1.016 1.016)
					(thickness 0.1524)
				)
			)
		)
		(property "Device Type" "R402H16"
			(at 0.064008 -5.517896 270)
			(unlocked yes)
			(layer "F.Fab")
			(hide yes)
			(effects
				(font
					(size 1.016 1.016)
					(thickness 0.1524)
				)
			)
		)
		(duplicate_pad_numbers_are_jumpers no)
		(fp_line
			(start -0.508 -0.9398)
			(end -0.508 0.9398)
			(stroke
				(width 0.1524)
				(type default)
			)
			(layer "F.SilkS")
		)
		(fp_line
			(start 0.508 -0.9398)
			(end -0.508 -0.9398)
			(stroke
				(width 0.1524)
				(type default)
			)
			(layer "F.SilkS")
		)
		(fp_rect
			(start -0.508 0.9398)
			(end 0.508 -0.9398)
			(stroke
				(width 0)
				(type default)
			)
			(fill no)
			(layer "F.CrtYd")
		)
		(fp_rect
			(start -0.508 0.9398)
			(end 0.508 -0.9398)
			(stroke
				(width 0)
				(type default)
			)
			(fill no)
			(layer "F.Fab")
		)
		(pad "1" smd custom
			(at 0 -0.4445 270)
			(size 0.1397 0.1397)
			(layers "F.Cu" "F.Mask" "F.Paste")
			(net "P3V3_STBY_B")
			(options
				(clearance outline)
				(anchor circle)
			)
			(primitives
				(gr_poly
					(pts
						(arc
							(start -0.1778 -0.2794)
							(mid -0.249642 -0.249642)
							(end -0.2794 -0.1778)
						)
						(arc
							(start -0.2794 0.1778)
							(mid -0.249642 0.249642)
							(end -0.1778 0.2794)
						)
						(arc
							(start 0.1778 0.2794)
							(mid 0.249642 0.249642)
							(end 0.2794 0.1778)
						)
						(arc
							(start 0.2794 -0.1778)
							(mid 0.249642 -0.249642)
							(end 0.1778 -0.2794)
						)
					)
					(width 0)
					(fill yes)
				)
			)
		)
		(pad "2" smd custom
			(at 0 0.4445 270)
			(size 0.1397 0.1397)
			(layers "F.Cu" "F.Mask" "F.Paste")
			(net "SW_PWR_R_HDD16")
			(options
				(clearance outline)
				(anchor circle)
			)
			(primitives
				(gr_poly
					(pts
						(arc
							(start -0.1778 -0.2794)
							(mid -0.249642 -0.249642)
							(end -0.2794 -0.1778)
						)
						(arc
							(start -0.2794 0.1778)
							(mid -0.249642 0.249642)
							(end -0.1778 0.2794)
						)
						(arc
							(start 0.1778 0.2794)
							(mid 0.249642 0.249642)
							(end 0.2794 0.1778)
						)
						(arc
							(start 0.2794 -0.1778)
							(mid 0.249642 -0.249642)
							(end 0.1778 -0.2794)
						)
					)
					(width 0)
					(fill yes)
				)
			)
		)
	)
	(footprint ""
		(layer "F.Cu")
		(at 435.269386 -120.651778 -90)
		(property "Reference" "R1168"
			(at 0 0 270)
			(layer "F.SilkS")
			(hide yes)
			(effects
				(font
					(size 1.27 1.27)
				)
			)
		)
		(property "Value" "143KR2F-L-1-GP"
			(at 0.064008 -3.993896 270)
			(unlocked yes)
			(layer "F.Fab")
			(hide yes)
			(effects
				(font
					(size 1.016 1.016)
					(thickness 0.1524)
				)
			)
		)
		(property "Device Type" "R402H16"
			(at 0.064008 -5.517896 270)
			(unlocked yes)
			(layer "F.Fab")
			(hide yes)
			(effects
				(font
					(size 1.016 1.016)
					(thickness 0.1524)
				)
			)
		)
		(duplicate_pad_numbers_are_jumpers no)
		(fp_line
			(start -0.508 -0.9398)
			(end -0.508 0.9398)
			(stroke
				(width 0.1524)
				(type default)
			)
			(layer "F.SilkS")
		)
		(fp_line
			(start 0.508 -0.9398)
			(end -0.508 -0.9398)
			(stroke
				(width 0.1524)
				(type default)
			)
			(layer "F.SilkS")
		)
		(fp_rect
			(start -0.508 0.9398)
			(end 0.508 -0.9398)
			(stroke
				(width 0)
				(type default)
			)
			(fill no)
			(layer "F.CrtYd")
		)
		(fp_rect
			(start -0.508 0.9398)
			(end 0.508 -0.9398)
			(stroke
				(width 0)
				(type default)
			)
			(fill no)
			(layer "F.Fab")
		)
		(pad "1" smd custom
			(at 0 -0.4445 270)
			(size 0.1397 0.1397)
			(layers "F.Cu" "F.Mask" "F.Paste")
			(net "AGND_P5V_B_4")
			(options
				(clearance outline)
				(anchor circle)
			)
			(primitives
				(gr_poly
					(pts
						(arc
							(start -0.1778 -0.2794)
							(mid -0.249642 -0.249642)
							(end -0.2794 -0.1778)
						)
						(arc
							(start -0.2794 0.1778)
							(mid -0.249642 0.249642)
							(end -0.1778 0.2794)
						)
						(arc
							(start 0.1778 0.2794)
							(mid 0.249642 0.249642)
							(end 0.2794 0.1778)
						)
						(arc
							(start 0.2794 -0.1778)
							(mid 0.249642 -0.249642)
							(end 0.1778 -0.2794)
						)
					)
					(width 0)
					(fill yes)
				)
			)
		)
		(pad "2" smd custom
			(at 0 0.4445 270)
			(size 0.1397 0.1397)
			(layers "F.Cu" "F.Mask" "F.Paste")
			(net "P5V_B_4_TRIP")
			(options
				(clearance outline)
				(anchor circle)
			)
			(primitives
				(gr_poly
					(pts
						(arc
							(start -0.1778 -0.2794)
							(mid -0.249642 -0.249642)
							(end -0.2794 -0.1778)
						)
						(arc
							(start -0.2794 0.1778)
							(mid -0.249642 0.249642)
							(end -0.1778 0.2794)
						)
						(arc
							(start 0.1778 0.2794)
							(mid 0.249642 0.249642)
							(end 0.2794 0.1778)
						)
						(arc
							(start 0.2794 -0.1778)
							(mid 0.249642 -0.249642)
							(end 0.1778 -0.2794)
						)
					)
					(width 0)
					(fill yes)
				)
			)
		)
	)
	(footprint ""
		(layer "F.Cu")
		(at 451.749922 -143.91005 -90)
		(property "Reference" "HDDSAS22"
			(at 0 0 270)
			(layer "F.SilkS")
			(hide yes)
			(effects
				(font
					(size 1.27 1.27)
				)
			)
		)
		(property "Value" "SKT-SAS15P-14P-45-GP"
			(at -20.7645 -8.9789 270)
			(unlocked yes)
			(layer "F.Fab")
			(hide yes)
			(effects
				(font
					(size 1.016 1.016)
					(thickness 0.1524)
				)
			)
		)
		(property "Device Type" "10120818-001C-TRLF"
			(at -20.7645 -10.5029 270)
			(unlocked yes)
			(layer "F.Fab")
			(hide yes)
			(effects
				(font
					(size 1.016 1.016)
					(thickness 0.1524)
				)
			)
		)
		(duplicate_pad_numbers_are_jumpers no)
		(fp_line
			(start 1.651 4.2926)
			(end 1.651 3.0099)
			(stroke
				(width 0.1524)
				(type default)
			)
			(layer "F.SilkS")
		)
		(fp_line
			(start 8.509 4.2926)
			(end 1.651 4.2926)
			(stroke
				(width 0.1524)
				(type default)
			)
			(layer "F.SilkS")
		)
		(fp_line
			(start -23.4188 3.0099)
			(end -23.4188 -3.2512)
			(stroke
				(width 0.1524)
				(type default)
			)
			(layer "F.SilkS")
		)
		(fp_line
			(start 1.651 3.0099)
			(end -23.4188 3.0099)
			(stroke
				(width 0.1524)
				(type default)
			)
			(layer "F.SilkS")
		)
		(fp_line
			(start 8.509 3.0099)
			(end 8.509 4.2926)
			(stroke
				(width 0.1524)
				(type default)
			)
			(layer "F.SilkS")
		)
		(fp_line
			(start 23.4188 3.0099)
			(end 8.509 3.0099)
			(stroke
				(width 0.1524)
				(type default)
			)
			(layer "F.SilkS")
		)
		(fp_line
			(start -23.4188 -3.2512)
			(end 23.4188 -3.2512)
			(stroke
				(width 0.1524)
				(type default)
			)
			(layer "F.SilkS")
		)
		(fp_line
			(start 23.4188 -3.2512)
			(end 23.4188 3.0099)
			(stroke
				(width 0.1524)
				(type default)
			)
			(layer "F.SilkS")
		)
		(fp_line
			(start 15.5067 -3.3401)
			(end 16.2687 -3.3401)
			(stroke
				(width 0.3302)
				(type default)
			)
			(layer "F.SilkS")
		)
		(fp_poly
			(pts
				(xy 15.868904 -3.230372) (xy 16.503904 -3.865372) (xy 15.233904 -3.865372)
			)
			(stroke
				(width 0)
				(type default)
			)
			(fill yes)
			(layer "F.SilkS")
		)
		(fp_poly
			(pts
				(xy -22.8727 -2.7559) (xy 22.8727 -2.7559) (xy 22.8727 2.7559) (xy 8.255 2.7559) (xy 8.255 3.5179)
				(xy 1.905 3.5179) (xy 1.905 2.7559) (xy -22.8727 2.7559)
			)
			(stroke
				(width 0)
				(type default)
			)
			(fill no)
			(layer "F.CrtYd")
		)
		(fp_poly
			(pts
				(xy 1.397 4.5466) (xy 1.397 3.2639) (xy -23.6728 3.2639) (xy -23.6728 -3.5052) (xy 23.6728 -3.5052)
				(xy 23.6728 -0.00635) (xy 22.8727 -0.00635) (xy 22.8727 -2.7559) (xy -22.8727 -2.7559) (xy -22.8727 2.7559)
				(xy 1.905 2.7559) (xy 1.905 3.5179) (xy 8.255 3.5179) (xy 8.255 2.7559) (xy 22.8727 2.7559) (xy 22.8727 0.00635)
				(xy 23.6728 0.00635) (xy 23.6728 3.2639) (xy 8.763 3.2639) (xy 8.763 4.5466)
			)
			(stroke
				(width 0)
				(type default)
			)
			(fill no)
			(layer "F.CrtYd")
		)
		(fp_poly
			(pts
				(xy 1.397 4.5466) (xy 1.397 3.2639) (xy -23.6728 3.2639) (xy -23.6728 -3.5052) (xy 23.6728 -3.5052)
				(xy 23.6728 3.2639) (xy 8.763 3.2639) (xy 8.763 4.5466)
			)
			(stroke
				(width 0)
				(type default)
			)
			(fill no)
			(layer "F.Fab")
		)
		(pad "" np_thru_hole circle
			(at -18.874994 0 270)
			(size 0.254 0.254)
			(drill 1.3462)
			(layers "*.Cu" "*.Mask")
			(clearance 0.9017)
			(thermal_gap 0.9017)
		)
		(pad "" np_thru_hole circle
			(at 18.874994 0 270)
			(size 0.254 0.254)
			(drill 0.9398)
			(layers "*.Cu" "*.Mask")
			(clearance 0.6985)
			(thermal_gap 0.6985)
		)
		(pad "G1" smd rect
			(at 21.874988 0 270)
			(size 2.5908 2.5908)
			(layers "F.Cu" "F.Mask" "F.Paste")
			(net "GND")
		)
		(pad "G2" smd rect
			(at -21.874988 0 270)
			(size 2.5908 2.5908)
			(layers "F.Cu" "F.Mask" "F.Paste")
			(net "GND")
		)
		(pad "P1" smd rect
			(at 1.905 -1.82499 270)
			(size 0.6096 2.3622)
			(layers "F.Cu" "F.Mask" "F.Paste")
			(net "Net_1689")
		)
		(pad "P2" smd rect
			(at 0.635 -1.82499 270)
			(size 0.6096 2.3622)
			(layers "F.Cu" "F.Mask" "F.Paste")
			(net "Net_1690")
		)
		(pad "P3" smd rect
			(at -0.635 -1.82499 270)
			(size 0.6096 2.3622)
			(layers "F.Cu" "F.Mask" "F.Paste")
			(net "Net_1691")
		)
		(pad "P4" smd rect
			(at -1.905 -1.82499 270)
			(size 0.6096 2.3622)
			(layers "F.Cu" "F.Mask" "F.Paste")
			(net "GND")
		)
		(pad "P5" smd rect
			(at -3.175 -1.82499 270)
			(size 0.6096 2.3622)
			(layers "F.Cu" "F.Mask" "F.Paste")
			(net "HDD_PRSNT_22")
		)
		(pad "P6" smd rect
			(at -4.445 -1.82499 270)
			(size 0.6096 2.3622)
			(layers "F.Cu" "F.Mask" "F.Paste")
			(net "GND")
		)
		(pad "P7" smd rect
			(at -5.715 -1.82499 270)
			(size 0.6096 2.3622)
			(layers "F.Cu" "F.Mask" "F.Paste")
			(net "5V_PRE_22")
		)
		(pad "P8" smd rect
			(at -6.985 -1.82499 270)
			(size 0.6096 2.3622)
			(layers "F.Cu" "F.Mask" "F.Paste")
			(net "P5V_HDD22")
		)
		(pad "P9" smd rect
			(at -8.255 -1.82499 270)
			(size 0.6096 2.3622)
			(layers "F.Cu" "F.Mask" "F.Paste")
			(net "P5V_HDD22")
		)
		(pad "P10" smd rect
			(at -9.525 -1.82499 270)
			(size 0.6096 2.3622)
			(layers "F.Cu" "F.Mask" "F.Paste")
			(net "GND")
		)
		(pad "P11" smd rect
			(at -10.795 -1.82499 270)
			(size 0.6096 2.3622)
			(layers "F.Cu" "F.Mask" "F.Paste")
			(net "ACT_HDD_22")
		)
		(pad "P12" smd rect
			(at -12.065 -1.82499 270)
			(size 0.6096 2.3622)
			(layers "F.Cu" "F.Mask" "F.Paste")
			(net "GND")
		)
		(pad "P13" smd rect
			(at -13.335 -1.82499 270)
			(size 0.6096 2.3622)
			(layers "F.Cu" "F.Mask" "F.Paste")
			(net "12V_PRE_22")
		)
		(pad "P14" smd rect
			(at -14.605 -1.82499 270)
			(size 0.6096 2.3622)
			(layers "F.Cu" "F.Mask" "F.Paste")
			(net "P12V_HDD22")
		)
		(pad "P15" smd rect
			(at -15.875 -1.82499 270)
			(size 0.6096 2.3622)
			(layers "F.Cu" "F.Mask" "F.Paste")
			(net "P12V_HDD22")
		)
		(pad "S1" smd rect
			(at 15.875 -1.82499 270)
			(size 0.6096 2.3622)
			(layers "F.Cu" "F.Mask" "F.Paste")
			(net "GND")
		)
		(pad "S2" smd rect
			(at 14.605 -1.82499 270)
			(size 0.6096 2.3622)
			(layers "F.Cu" "F.Mask" "F.Paste")
			(net "SAS_HDD_RX_P22")
		)
		(pad "S3" smd rect
			(at 13.335 -1.82499 270)
			(size 0.6096 2.3622)
			(layers "F.Cu" "F.Mask" "F.Paste")
			(net "SAS_HDD_RX_N22")
		)
		(pad "S4" smd rect
			(at 12.065 -1.82499 270)
			(size 0.6096 2.3622)
			(layers "F.Cu" "F.Mask" "F.Paste")
			(net "GND")
		)
		(pad "S5" smd rect
			(at 10.795 -1.82499 270)
			(size 0.6096 2.3622)
			(layers "F.Cu" "F.Mask" "F.Paste")
			(net "PHY_DRV_B_TO_SCC_B_22_DN")
		)
		(pad "S6" smd rect
			(at 9.525 -1.82499 270)
			(size 0.6096 2.3622)
			(layers "F.Cu" "F.Mask" "F.Paste")
			(net "PHY_DRV_B_TO_SCC_B_22_DP")
		)
		(pad "S7" smd rect
			(at 8.255 -1.82499 270)
			(size 0.6096 2.3622)
			(layers "F.Cu" "F.Mask" "F.Paste")
			(net "GND")
		)
		(pad "S8" smd rect
			(at 7.480046 2.845054 270)
			(size 0.508 2.3622)
			(layers "F.Cu" "F.Mask" "F.Paste")
			(net "GND")
		)
		(pad "S9" smd rect
			(at 6.679946 2.845054 270)
			(size 0.508 2.3622)
			(layers "F.Cu" "F.Mask" "F.Paste")
			(net "Net_446")
		)
		(pad "S10" smd rect
			(at 5.8801 2.845054 270)
			(size 0.508 2.3622)
			(layers "F.Cu" "F.Mask" "F.Paste")
			(net "Net_338")
		)
		(pad "S11" smd rect
			(at 5.08 2.845054 270)
			(size 0.508 2.3622)
			(layers "F.Cu" "F.Mask" "F.Paste")
			(net "GND")
		)
		(pad "S12" smd rect
			(at 4.2799 2.845054 270)
			(size 0.508 2.3622)
			(layers "F.Cu" "F.Mask" "F.Paste")
			(net "Net_374")
		)
		(pad "S13" smd rect
			(at 3.480054 2.845054 270)
			(size 0.508 2.3622)
			(layers "F.Cu" "F.Mask" "F.Paste")
			(net "Net_410")
		)
		(pad "S14" smd rect
			(at 2.679954 2.845054 270)
			(size 0.508 2.3622)
			(layers "F.Cu" "F.Mask" "F.Paste")
			(net "GND")
		)
		(zone
			(layer "F.Cu")
			(hatch none 0.5)
			(connect_pads
				(clearance 0)
			)
			(min_thickness 0.25)
			(keepout
				(tracks allowed)
				(vias not_allowed)
				(pads allowed)
				(copperpour not_allowed)
				(footprints allowed)
			)
			(placement
				(enabled no)
				(sheetname "")
			)
			(fill
				(thermal_gap 0.5)
				(thermal_bridge_width 0.5)
				(island_removal_mode 0)
			)
			(polygon
				(pts
					(xy 455.407522 -160.64865) (xy 448.333622 -160.64865) (xy 448.333622 -167.58285) (xy 449.438522 -167.58285)
					(xy 449.438522 -163.46805) (xy 454.061322 -163.46805) (xy 454.061322 -167.58285) (xy 455.407522 -167.58285)
				)
			)
		)
		(zone
			(layer "F.Cu")
			(hatch none 0.5)
			(connect_pads
				(clearance 0)
			)
			(min_thickness 0.25)
			(keepout
				(tracks not_allowed)
				(vias allowed)
				(pads allowed)
				(copperpour not_allowed)
				(footprints allowed)
			)
			(placement
				(enabled no)
				(sheetname "")
			)
			(fill
				(thermal_gap 0.5)
				(thermal_bridge_width 0.5)
				(island_removal_mode 0)
			)
			(polygon
				(pts
					(xy 455.407522 -160.64865) (xy 448.333622 -160.64865) (xy 448.333622 -167.58285) (xy 449.438522 -167.58285)
					(xy 449.438522 -163.46805) (xy 454.061322 -163.46805) (xy 454.061322 -167.58285) (xy 455.407522 -167.58285)
				)
			)
		)
		(zone
			(layer "F.Cu")
			(hatch none 0.5)
			(connect_pads
				(clearance 0)
			)
			(min_thickness 0.25)
			(keepout
				(tracks not_allowed)
				(vias allowed)
				(pads allowed)
				(copperpour not_allowed)
				(footprints allowed)
			)
			(placement
				(enabled no)
				(sheetname "")
			)
			(fill
				(thermal_gap 0.5)
				(thermal_bridge_width 0.5)
				(island_removal_mode 0)
			)
			(polygon
				(pts
					(xy 455.407522 -127.17145) (xy 448.333622 -127.17145) (xy 448.333622 -120.23725) (xy 449.438522 -120.23725)
					(xy 449.438522 -124.35205) (xy 454.061322 -124.35205) (xy 454.061322 -120.23725) (xy 455.407522 -120.23725)
				)
			)
		)
		(zone
			(layer "F.Cu")
			(hatch none 0.5)
			(connect_pads
				(clearance 0)
			)
			(min_thickness 0.25)
			(keepout
				(tracks allowed)
				(vias not_allowed)
				(pads allowed)
				(copperpour not_allowed)
				(footprints allowed)
			)
			(placement
				(enabled no)
				(sheetname "")
			)
			(fill
				(thermal_gap 0.5)
				(thermal_bridge_width 0.5)
				(island_removal_mode 0)
			)
			(polygon
				(pts
					(xy 455.407522 -127.17145) (xy 448.333622 -127.17145) (xy 448.333622 -120.23725) (xy 449.438522 -120.23725)
					(xy 449.438522 -124.35205) (xy 454.061322 -124.35205) (xy 454.061322 -120.23725) (xy 455.407522 -120.23725)
				)
			)
		)
		(zone
			(layers "F.Cu" "B.Cu" "In1.Cu" "In2.Cu" "In3.Cu" "In4.Cu" "In5.Cu" "In6.Cu")
			(hatch none 0.5)
			(connect_pads
				(clearance 0)
			)
			(min_thickness 0.25)
			(keepout
				(tracks not_allowed)
				(vias allowed)
				(pads allowed)
				(copperpour not_allowed)
				(footprints allowed)
			)
			(placement
				(enabled no)
				(sheetname "")
			)
			(fill
				(thermal_gap 0.5)
				(thermal_bridge_width 0.5)
				(island_removal_mode 0)
			)
			(polygon
				(pts
					(arc
						(start 452.524622 -125.035056)
						(mid 450.975222 -125.035056)
						(end 452.524622 -125.035056)
					)
				)
			)
		)
		(zone
			(layers "F.Cu" "B.Cu" "In1.Cu" "In2.Cu" "In3.Cu" "In4.Cu" "In5.Cu" "In6.Cu")
			(hatch none 0.5)
			(connect_pads
				(clearance 0)
			)
			(min_thickness 0.25)
			(keepout
				(tracks not_allowed)
				(vias allowed)
				(pads allowed)
				(copperpour not_allowed)
				(footprints allowed)
			)
			(placement
				(enabled no)
				(sheetname "")
			)
			(fill
				(thermal_gap 0.5)
				(thermal_bridge_width 0.5)
				(island_removal_mode 0)
			)
			(polygon
				(pts
					(arc
						(start 452.727822 -162.785044)
						(mid 450.772022 -162.785044)
						(end 452.727822 -162.785044)
					)
				)
			)
		)
	)
	(footprint ""
		(layer "F.Cu")
		(at 263.113774 -217.419936 -90)
		(property "Reference" "R119"
			(at 0 0 270)
			(layer "F.SilkS")
			(hide yes)
			(effects
				(font
					(size 1.27 1.27)
				)
			)
		)
		(property "Value" "4K7R2F-GP"
			(at 0.064008 -3.993896 270)
			(unlocked yes)
			(layer "F.Fab")
			(hide yes)
			(effects
				(font
					(size 1.016 1.016)
					(thickness 0.1524)
				)
			)
		)
		(property "Device Type" "R402H16"
			(at 0.064008 -5.517896 270)
			(unlocked yes)
			(layer "F.Fab")
			(hide yes)
			(effects
				(font
					(size 1.016 1.016)
					(thickness 0.1524)
				)
			)
		)
		(duplicate_pad_numbers_are_jumpers no)
		(fp_line
			(start -0.508 -0.9398)
			(end -0.508 0.9398)
			(stroke
				(width 0.1524)
				(type default)
			)
			(layer "F.SilkS")
		)
		(fp_line
			(start 0.508 -0.9398)
			(end -0.508 -0.9398)
			(stroke
				(width 0.1524)
				(type default)
			)
			(layer "F.SilkS")
		)
		(fp_rect
			(start -0.508 0.9398)
			(end 0.508 -0.9398)
			(stroke
				(width 0)
				(type default)
			)
			(fill no)
			(layer "F.CrtYd")
		)
		(fp_rect
			(start -0.508 0.9398)
			(end 0.508 -0.9398)
			(stroke
				(width 0)
				(type default)
			)
			(fill no)
			(layer "F.Fab")
		)
		(pad "1" smd custom
			(at 0 -0.4445 270)
			(size 0.1397 0.1397)
			(layers "F.Cu" "F.Mask" "F.Paste")
			(net "P3V3_STBY_B")
			(options
				(clearance outline)
				(anchor circle)
			)
			(primitives
				(gr_poly
					(pts
						(arc
							(start -0.1778 -0.2794)
							(mid -0.249642 -0.249642)
							(end -0.2794 -0.1778)
						)
						(arc
							(start -0.2794 0.1778)
							(mid -0.249642 0.249642)
							(end -0.1778 0.2794)
						)
						(arc
							(start 0.1778 0.2794)
							(mid 0.249642 0.249642)
							(end 0.2794 0.1778)
						)
						(arc
							(start 0.2794 -0.1778)
							(mid 0.249642 -0.249642)
							(end 0.1778 -0.2794)
						)
					)
					(width 0)
					(fill yes)
				)
			)
		)
		(pad "2" smd custom
			(at 0 0.4445 270)
			(size 0.1397 0.1397)
			(layers "F.Cu" "F.Mask" "F.Paste")
			(net "VOL_SEN_ADDR0")
			(options
				(clearance outline)
				(anchor circle)
			)
			(primitives
				(gr_poly
					(pts
						(arc
							(start -0.1778 -0.2794)
							(mid -0.249642 -0.249642)
							(end -0.2794 -0.1778)
						)
						(arc
							(start -0.2794 0.1778)
							(mid -0.249642 0.249642)
							(end -0.1778 0.2794)
						)
						(arc
							(start 0.1778 0.2794)
							(mid 0.249642 0.249642)
							(end 0.2794 0.1778)
						)
						(arc
							(start 0.2794 -0.1778)
							(mid 0.249642 -0.249642)
							(end 0.1778 -0.2794)
						)
					)
					(width 0)
					(fill yes)
				)
			)
		)
	)
	(footprint ""
		(layer "F.Cu")
		(at 400.431 -133.858 90)
		(property "Reference" "D20"
			(at 0 0 90)
			(layer "F.SilkS")
			(hide yes)
			(effects
				(font
					(size 1.27 1.27)
				)
			)
		)
		(property "Value" "RB551V30-GP"
			(at 0 -6.7818 90)
			(unlocked yes)
			(layer "F.Fab")
			(hide yes)
			(effects
				(font
					(size 1.016 1.016)
					(thickness 0.1524)
				)
			)
		)
		(property "Device Type" "SOD323AKH38"
			(at 0 -8.6868 90)
			(unlocked yes)
			(layer "F.Fab")
			(hide yes)
			(effects
				(font
					(size 1.016 1.016)
					(thickness 0.1524)
				)
			)
		)
		(duplicate_pad_numbers_are_jumpers no)
		(fp_line
			(start 0.889 -1.9304)
			(end 0.889 2.159)
			(stroke
				(width 0.1524)
				(type default)
			)
			(layer "F.SilkS")
		)
		(fp_line
			(start -0.889 -1.9304)
			(end 0.889 -1.9304)
			(stroke
				(width 0.1524)
				(type default)
			)
			(layer "F.SilkS")
		)
		(fp_line
			(start 0.762 2.0574)
			(end -0.762 2.0574)
			(stroke
				(width 0.508)
				(type default)
			)
			(layer "F.SilkS")
		)
		(fp_line
			(start 0.889 2.159)
			(end -0.889 2.159)
			(stroke
				(width 0.1524)
				(type default)
			)
			(layer "F.SilkS")
		)
		(fp_line
			(start -0.889 2.159)
			(end -0.889 -1.9304)
			(stroke
				(width 0.1524)
				(type default)
			)
			(layer "F.SilkS")
		)
		(fp_rect
			(start -1.016 2.3114)
			(end 1.016 -2.0066)
			(stroke
				(width 0)
				(type default)
			)
			(fill no)
			(layer "F.CrtYd")
		)
		(fp_poly
			(pts
				(xy -1.016 -2.0066) (xy 1.016 -2.0066) (xy 1.016 2.3114) (xy -1.016 2.3114)
			)
			(stroke
				(width 0)
				(type default)
			)
			(fill no)
			(layer "F.Fab")
		)
		(pad "A" smd rect
			(at 0 -1.143 90)
			(size 0.5588 1.016)
			(layers "F.Cu" "F.Mask" "F.Paste")
			(net "SW_HDD_R20")
		)
		(pad "K" smd rect
			(at 0 1.143 90)
			(size 0.5588 1.016)
			(layers "F.Cu" "F.Mask" "F.Paste")
			(net "SW_HDD_N20")
		)
	)
	(footprint ""
		(layer "F.Cu")
		(at 315.839348 -213.153752)
		(property "Reference" "R301"
			(at 0 0 0)
			(layer "F.SilkS")
			(hide yes)
			(effects
				(font
					(size 1.27 1.27)
				)
			)
		)
		(property "Value" "91R3F-1-GP"
			(at -0.0254 -2.5146 0)
			(unlocked yes)
			(layer "F.Fab")
			(hide yes)
			(effects
				(font
					(size 1.016 1.016)
					(thickness 0.1524)
				)
			)
		)
		(property "Device Type" "R603H22"
			(at -0.0254 -4.0386 0)
			(unlocked yes)
			(layer "F.Fab")
			(hide yes)
			(effects
				(font
					(size 1.016 1.016)
					(thickness 0.1524)
				)
			)
		)
		(duplicate_pad_numbers_are_jumpers no)
		(fp_line
			(start -0.4826 0)
			(end -0.2032 0)
			(stroke
				(width 0.2032)
				(type default)
			)
			(layer "F.SilkS")
		)
		(fp_line
			(start 0.2032 0)
			(end 0.4826 0)
			(stroke
				(width 0.2032)
				(type default)
			)
			(layer "F.SilkS")
		)
		(fp_rect
			(start -0.5842 1.3335)
			(end 0.5842 -1.3335)
			(stroke
				(width 0)
				(type default)
			)
			(fill no)
			(layer "F.CrtYd")
		)
		(fp_rect
			(start -0.5842 1.3335)
			(end 0.5842 -1.3335)
			(stroke
				(width 0)
				(type default)
			)
			(fill no)
			(layer "F.Fab")
		)
		(pad "1" smd custom
			(at 0 -0.762)
			(size 0.2159 0.2159)
			(layers "F.Cu" "F.Mask" "F.Paste")
			(net "P5V_B_3")
			(options
				(clearance outline)
				(anchor circle)
			)
			(primitives
				(gr_poly
					(pts
						(arc
							(start -0.3302 -0.4318)
							(mid -0.402042 -0.402042)
							(end -0.4318 -0.3302)
						)
						(arc
							(start -0.4318 0.3302)
							(mid -0.402042 0.402042)
							(end -0.3302 0.4318)
						)
						(arc
							(start 0.3302 0.4318)
							(mid 0.402042 0.402042)
							(end 0.4318 0.3302)
						)
						(arc
							(start 0.4318 -0.3302)
							(mid 0.402042 -0.402042)
							(end 0.3302 -0.4318)
						)
					)
					(width 0)
					(fill yes)
				)
			)
		)
		(pad "2" smd custom
			(at 0 0.762)
			(size 0.2159 0.2159)
			(layers "F.Cu" "F.Mask" "F.Paste")
			(net "DRV_ACT_6")
			(options
				(clearance outline)
				(anchor circle)
			)
			(primitives
				(gr_poly
					(pts
						(arc
							(start -0.3302 -0.4318)
							(mid -0.402042 -0.402042)
							(end -0.4318 -0.3302)
						)
						(arc
							(start -0.4318 0.3302)
							(mid -0.402042 0.402042)
							(end -0.3302 0.4318)
						)
						(arc
							(start 0.3302 0.4318)
							(mid 0.402042 0.402042)
							(end 0.4318 0.3302)
						)
						(arc
							(start 0.4318 -0.3302)
							(mid 0.402042 -0.402042)
							(end 0.3302 -0.4318)
						)
					)
					(width 0)
					(fill yes)
				)
			)
		)
	)
	(footprint ""
		(layer "F.Cu")
		(at 426.72 -243.586)
		(property "Reference" "R311"
			(at 0 0 0)
			(layer "F.SilkS")
			(hide yes)
			(effects
				(font
					(size 1.27 1.27)
				)
			)
		)
		(property "Value" "4K7R2F-GP"
			(at 0.064008 -3.993896 0)
			(unlocked yes)
			(layer "F.Fab")
			(hide yes)
			(effects
				(font
					(size 1.016 1.016)
					(thickness 0.1524)
				)
			)
		)
		(property "Device Type" "R402H16"
			(at 0.064008 -5.517896 0)
			(unlocked yes)
			(layer "F.Fab")
			(hide yes)
			(effects
				(font
					(size 1.016 1.016)
					(thickness 0.1524)
				)
			)
		)
		(duplicate_pad_numbers_are_jumpers no)
		(fp_line
			(start -0.508 -0.9398)
			(end -0.508 0.9398)
			(stroke
				(width 0.1524)
				(type default)
			)
			(layer "F.SilkS")
		)
		(fp_line
			(start 0.508 -0.9398)
			(end -0.508 -0.9398)
			(stroke
				(width 0.1524)
				(type default)
			)
			(layer "F.SilkS")
		)
		(fp_rect
			(start -0.508 0.9398)
			(end 0.508 -0.9398)
			(stroke
				(width 0)
				(type default)
			)
			(fill no)
			(layer "F.CrtYd")
		)
		(fp_rect
			(start -0.508 0.9398)
			(end 0.508 -0.9398)
			(stroke
				(width 0)
				(type default)
			)
			(fill no)
			(layer "F.Fab")
		)
		(pad "1" smd custom
			(at 0 -0.4445)
			(size 0.1397 0.1397)
			(layers "F.Cu" "F.Mask" "F.Paste")
			(net "SW_PWR_R_HDD9")
			(options
				(clearance outline)
				(anchor circle)
			)
			(primitives
				(gr_poly
					(pts
						(arc
							(start -0.1778 -0.2794)
							(mid -0.249642 -0.249642)
							(end -0.2794 -0.1778)
						)
						(arc
							(start -0.2794 0.1778)
							(mid -0.249642 0.249642)
							(end -0.1778 0.2794)
						)
						(arc
							(start 0.1778 0.2794)
							(mid 0.249642 0.249642)
							(end 0.2794 0.1778)
						)
						(arc
							(start 0.2794 -0.1778)
							(mid 0.249642 -0.249642)
							(end 0.1778 -0.2794)
						)
					)
					(width 0)
					(fill yes)
				)
			)
		)
		(pad "2" smd custom
			(at 0 0.4445)
			(size 0.1397 0.1397)
			(layers "F.Cu" "F.Mask" "F.Paste")
			(net "GND")
			(options
				(clearance outline)
				(anchor circle)
			)
			(primitives
				(gr_poly
					(pts
						(arc
							(start -0.1778 -0.2794)
							(mid -0.249642 -0.249642)
							(end -0.2794 -0.1778)
						)
						(arc
							(start -0.2794 0.1778)
							(mid -0.249642 0.249642)
							(end -0.1778 0.2794)
						)
						(arc
							(start 0.1778 0.2794)
							(mid 0.249642 0.249642)
							(end 0.2794 0.1778)
						)
						(arc
							(start 0.2794 -0.1778)
							(mid 0.249642 -0.249642)
							(end 0.1778 -0.2794)
						)
					)
					(width 0)
					(fill yes)
				)
			)
		)
	)
	(footprint ""
		(layer "F.Cu")
		(at 365.0234 -40.5892 -90)
		(property "Reference" "R784"
			(at 0 0 270)
			(layer "F.SilkS")
			(hide yes)
			(effects
				(font
					(size 1.27 1.27)
				)
			)
		)
		(property "Value" "2R6F-GP"
			(at -0.0508 -4.8514 270)
			(unlocked yes)
			(layer "F.Fab")
			(hide yes)
			(effects
				(font
					(size 1.016 1.016)
					(thickness 0.1524)
				)
			)
		)
		(property "Device Type" "R1206H26"
			(at 0 -6.3754 270)
			(unlocked yes)
			(layer "F.Fab")
			(hide yes)
			(effects
				(font
					(size 1.016 1.016)
					(thickness 0.1524)
				)
			)
		)
		(duplicate_pad_numbers_are_jumpers no)
		(fp_line
			(start -1.016 2.2352)
			(end -1.016 -2.2352)
			(stroke
				(width 0.1524)
				(type default)
			)
			(layer "F.SilkS")
		)
		(fp_line
			(start 1.016 2.2352)
			(end -1.016 2.2352)
			(stroke
				(width 0.1524)
				(type default)
			)
			(layer "F.SilkS")
		)
		(fp_line
			(start -1.016 -2.2352)
			(end 1.016 -2.2352)
			(stroke
				(width 0.1524)
				(type default)
			)
			(layer "F.SilkS")
		)
		(fp_line
			(start 1.016 -2.2352)
			(end 1.016 2.2352)
			(stroke
				(width 0.1524)
				(type default)
			)
			(layer "F.SilkS")
		)
		(fp_rect
			(start -1.0922 2.3114)
			(end 1.0922 -2.3114)
			(stroke
				(width 0)
				(type default)
			)
			(fill no)
			(layer "F.CrtYd")
		)
		(fp_poly
			(pts
				(xy -1.0922 -2.3114) (xy 1.0922 -2.3114) (xy 1.0922 2.3114) (xy -1.0922 2.3114)
			)
			(stroke
				(width 0)
				(type default)
			)
			(fill no)
			(layer "F.Fab")
		)
		(pad "1" smd rect
			(at 0 -1.397 270)
			(size 1.651 1.27)
			(layers "F.Cu" "F.Mask" "F.Paste")
			(net "P12V_HDD31")
		)
		(pad "2" smd rect
			(at 0 1.397 270)
			(size 1.651 1.27)
			(layers "F.Cu" "F.Mask" "F.Paste")
			(net "12V_PRE_31")
		)
	)
	(footprint ""
		(layer "F.Cu")
		(at 178.0032 -148.717 -90)
		(property "Reference" "C251"
			(at 0 0 270)
			(layer "F.SilkS")
			(hide yes)
			(effects
				(font
					(size 1.27 1.27)
				)
			)
		)
		(property "Value" "SC1U16V3KX-5GP"
			(at 0 -2.8194 270)
			(unlocked yes)
			(layer "F.Fab")
			(hide yes)
			(effects
				(font
					(size 1.016 1.016)
					(thickness 0.1524)
				)
			)
		)
		(property "Device Type" "C603H36"
			(at 0 -4.3434 270)
			(unlocked yes)
			(layer "F.Fab")
			(hide yes)
			(effects
				(font
					(size 1.016 1.016)
					(thickness 0.1524)
				)
			)
		)
		(duplicate_pad_numbers_are_jumpers no)
		(fp_line
			(start 0.508 0)
			(end -0.508 0)
			(stroke
				(width 0.2032)
				(type default)
			)
			(layer "F.SilkS")
		)
		(fp_rect
			(start -0.5842 1.3335)
			(end 0.5842 -1.3335)
			(stroke
				(width 0)
				(type default)
			)
			(fill no)
			(layer "F.CrtYd")
		)
		(fp_rect
			(start -0.5842 1.3335)
			(end 0.5842 -1.3335)
			(stroke
				(width 0)
				(type default)
			)
			(fill no)
			(layer "F.Fab")
		)
		(pad "1" smd custom
			(at 0 -0.762 270)
			(size 0.2159 0.2159)
			(layers "F.Cu" "F.Mask" "F.Paste")
			(net "P5V_HDD17")
			(options
				(clearance outline)
				(anchor circle)
			)
			(primitives
				(gr_poly
					(pts
						(arc
							(start -0.3302 -0.4318)
							(mid -0.402042 -0.402042)
							(end -0.4318 -0.3302)
						)
						(arc
							(start -0.4318 0.3302)
							(mid -0.402042 0.402042)
							(end -0.3302 0.4318)
						)
						(arc
							(start 0.3302 0.4318)
							(mid 0.402042 0.402042)
							(end 0.4318 0.3302)
						)
						(arc
							(start 0.4318 -0.3302)
							(mid 0.402042 -0.402042)
							(end 0.3302 -0.4318)
						)
					)
					(width 0)
					(fill yes)
				)
			)
		)
		(pad "2" smd custom
			(at 0 0.762 270)
			(size 0.2159 0.2159)
			(layers "F.Cu" "F.Mask" "F.Paste")
			(net "GND")
			(options
				(clearance outline)
				(anchor circle)
			)
			(primitives
				(gr_poly
					(pts
						(arc
							(start -0.3302 -0.4318)
							(mid -0.402042 -0.402042)
							(end -0.4318 -0.3302)
						)
						(arc
							(start -0.4318 0.3302)
							(mid -0.402042 0.402042)
							(end -0.3302 0.4318)
						)
						(arc
							(start 0.3302 0.4318)
							(mid 0.402042 0.402042)
							(end 0.4318 0.3302)
						)
						(arc
							(start 0.4318 -0.3302)
							(mid 0.402042 -0.402042)
							(end 0.3302 -0.4318)
						)
					)
					(width 0)
					(fill yes)
				)
			)
		)
	)
	(footprint ""
		(layer "F.Cu")
		(at 49.349914 -180.399944)
		(property "Reference" "LED2"
			(at 0 0 0)
			(layer "F.SilkS")
			(hide yes)
			(effects
				(font
					(size 1.27 1.27)
				)
			)
		)
		(property "Value" "LED-BY-19-GP"
			(at -2.132076 1.414018 0)
			(unlocked yes)
			(layer "F.Fab")
			(hide yes)
			(effects
				(font
					(size 1.016 1.016)
					(thickness 0.1524)
				)
			)
		)
		(property "Device Type" "LED-1615-4PH26"
			(at -2.132076 -0.109982 0)
			(unlocked yes)
			(layer "F.Fab")
			(hide yes)
			(effects
				(font
					(size 1.016 1.016)
					(thickness 0.1524)
				)
			)
		)
		(duplicate_pad_numbers_are_jumpers no)
		(fp_line
			(start -1.2954 0.254)
			(end -1.2954 1.6002)
			(stroke
				(width 0.508)
				(type default)
			)
			(layer "F.SilkS")
		)
		(fp_line
			(start -1.2954 1.6002)
			(end 1.2954 1.6002)
			(stroke
				(width 0.508)
				(type default)
			)
			(layer "F.SilkS")
		)
		(fp_line
			(start -1.1176 -1.4224)
			(end 1.1176 -1.4224)
			(stroke
				(width 0.1524)
				(type default)
			)
			(layer "F.SilkS")
		)
		(fp_line
			(start -1.1176 1.4224)
			(end -1.1176 -1.4224)
			(stroke
				(width 0.1524)
				(type default)
			)
			(layer "F.SilkS")
		)
		(fp_line
			(start 1.1176 -1.4224)
			(end 1.1176 1.4224)
			(stroke
				(width 0.1524)
				(type default)
			)
			(layer "F.SilkS")
		)
		(fp_line
			(start 1.1176 1.4224)
			(end -1.1176 1.4224)
			(stroke
				(width 0.1524)
				(type default)
			)
			(layer "F.SilkS")
		)
		(fp_line
			(start 1.2954 1.6002)
			(end 1.2954 0.254)
			(stroke
				(width 0.508)
				(type default)
			)
			(layer "F.SilkS")
		)
		(fp_rect
			(start -0.7493 0.8001)
			(end 0.7493 -0.8001)
			(stroke
				(width 0)
				(type default)
			)
			(fill no)
			(layer "F.CrtYd")
		)
		(fp_poly
			(pts
				(xy -1.3716 1.6764) (xy -1.3716 -1.6764) (xy 1.3716 -1.6764) (xy 1.3716 0.0635) (xy 0.7493 0.0635)
				(xy 0.7493 -0.8001) (xy -0.7493 -0.8001) (xy -0.7493 0.8001) (xy 0.7493 0.8001) (xy 0.7493 0.0762)
				(xy 1.3716 0.0762) (xy 1.3716 1.6764)
			)
			(stroke
				(width 0)
				(type default)
			)
			(fill no)
			(layer "F.CrtYd")
		)
		(fp_rect
			(start -1.3716 1.6764)
			(end 1.3716 -1.6764)
			(stroke
				(width 0)
				(type default)
			)
			(fill no)
			(layer "F.Fab")
		)
		(pad "1" smd rect
			(at 0.50038 -0.73025)
			(size 0.7112 0.8636)
			(layers "F.Cu" "F.Mask" "F.Paste")
			(net "DRV_ACT_1")
		)
		(pad "2" smd rect
			(at -0.50038 -0.73025)
			(size 0.7112 0.8636)
			(layers "F.Cu" "F.Mask" "F.Paste")
			(net "FLT_HDD1")
		)
		(pad "3" smd rect
			(at 0.50038 0.73025)
			(size 0.7112 0.8636)
			(layers "F.Cu" "F.Mask" "F.Paste")
			(net "DRV_ACT_1_N")
		)
		(pad "4" smd rect
			(at -0.50038 0.73025)
			(size 0.7112 0.8636)
			(layers "F.Cu" "F.Mask" "F.Paste")
			(net "FLT_HDD1_N")
		)
	)
	(footprint ""
		(layer "F.Cu")
		(at 473.202 -244.348)
		(property "Reference" "R343"
			(at 0 0 0)
			(layer "F.SilkS")
			(hide yes)
			(effects
				(font
					(size 1.27 1.27)
				)
			)
		)
		(property "Value" "4K7R2F-GP"
			(at 0.064008 -3.993896 0)
			(unlocked yes)
			(layer "F.Fab")
			(hide yes)
			(effects
				(font
					(size 1.016 1.016)
					(thickness 0.1524)
				)
			)
		)
		(property "Device Type" "R402H16"
			(at 0.064008 -5.517896 0)
			(unlocked yes)
			(layer "F.Fab")
			(hide yes)
			(effects
				(font
					(size 1.016 1.016)
					(thickness 0.1524)
				)
			)
		)
		(duplicate_pad_numbers_are_jumpers no)
		(fp_line
			(start -0.508 -0.9398)
			(end -0.508 0.9398)
			(stroke
				(width 0.1524)
				(type default)
			)
			(layer "F.SilkS")
		)
		(fp_line
			(start 0.508 -0.9398)
			(end -0.508 -0.9398)
			(stroke
				(width 0.1524)
				(type default)
			)
			(layer "F.SilkS")
		)
		(fp_rect
			(start -0.508 0.9398)
			(end 0.508 -0.9398)
			(stroke
				(width 0)
				(type default)
			)
			(fill no)
			(layer "F.CrtYd")
		)
		(fp_rect
			(start -0.508 0.9398)
			(end 0.508 -0.9398)
			(stroke
				(width 0)
				(type default)
			)
			(fill no)
			(layer "F.Fab")
		)
		(pad "1" smd custom
			(at 0 -0.4445)
			(size 0.1397 0.1397)
			(layers "F.Cu" "F.Mask" "F.Paste")
			(net "SW_PWR_R_HDD11")
			(options
				(clearance outline)
				(anchor circle)
			)
			(primitives
				(gr_poly
					(pts
						(arc
							(start -0.1778 -0.2794)
							(mid -0.249642 -0.249642)
							(end -0.2794 -0.1778)
						)
						(arc
							(start -0.2794 0.1778)
							(mid -0.249642 0.249642)
							(end -0.1778 0.2794)
						)
						(arc
							(start 0.1778 0.2794)
							(mid 0.249642 0.249642)
							(end 0.2794 0.1778)
						)
						(arc
							(start 0.2794 -0.1778)
							(mid 0.249642 -0.249642)
							(end 0.1778 -0.2794)
						)
					)
					(width 0)
					(fill yes)
				)
			)
		)
		(pad "2" smd custom
			(at 0 0.4445)
			(size 0.1397 0.1397)
			(layers "F.Cu" "F.Mask" "F.Paste")
			(net "GND")
			(options
				(clearance outline)
				(anchor circle)
			)
			(primitives
				(gr_poly
					(pts
						(arc
							(start -0.1778 -0.2794)
							(mid -0.249642 -0.249642)
							(end -0.2794 -0.1778)
						)
						(arc
							(start -0.2794 0.1778)
							(mid -0.249642 0.249642)
							(end -0.1778 0.2794)
						)
						(arc
							(start 0.1778 0.2794)
							(mid 0.249642 0.249642)
							(end 0.2794 0.1778)
						)
						(arc
							(start 0.2794 -0.1778)
							(mid 0.249642 -0.249642)
							(end 0.1778 -0.2794)
						)
					)
					(width 0)
					(fill yes)
				)
			)
		)
	)
	(footprint ""
		(layer "F.Cu")
		(at 77.978 -30.861)
		(property "Reference" "Q132"
			(at 0 0 0)
			(layer "F.SilkS")
			(hide yes)
			(effects
				(font
					(size 1.27 1.27)
				)
			)
		)
		(property "Value" "AO4407AL-GP"
			(at -3.707384 -1.5367 0)
			(unlocked yes)
			(layer "F.Fab")
			(hide yes)
			(effects
				(font
					(size 1.016 1.016)
					(thickness 0.1524)
				)
			)
		)
		(property "Device Type" "SOIC8H69"
			(at -3.707384 -3.0607 0)
			(unlocked yes)
			(layer "F.Fab")
			(hide yes)
			(effects
				(font
					(size 1.016 1.016)
					(thickness 0.1524)
				)
			)
		)
		(duplicate_pad_numbers_are_jumpers no)
		(fp_line
			(start -2.7432 -1.4224)
			(end -2.7432 1.4224)
			(stroke
				(width 0.1524)
				(type default)
			)
			(layer "F.SilkS")
		)
		(fp_line
			(start -2.7432 1.4224)
			(end -2.6416 1.4224)
			(stroke
				(width 0.1524)
				(type default)
			)
			(layer "F.SilkS")
		)
		(fp_line
			(start -2.7432 1.4224)
			(end 2.1336 1.4224)
			(stroke
				(width 0.1524)
				(type default)
			)
			(layer "F.SilkS")
		)
		(fp_line
			(start -2.7178 -0.508)
			(end -2.1844 -0.0508)
			(stroke
				(width 0.1524)
				(type default)
			)
			(layer "F.SilkS")
		)
		(fp_line
			(start -2.6289 3.4417)
			(end -2.6289 1.4732)
			(stroke
				(width 0.381)
				(type default)
			)
			(layer "F.SilkS")
		)
		(fp_line
			(start -2.1844 -0.0508)
			(end -2.7178 0.508)
			(stroke
				(width 0.1524)
				(type default)
			)
			(layer "F.SilkS")
		)
		(fp_line
			(start 2.1336 -1.4224)
			(end -2.7432 -1.4224)
			(stroke
				(width 0.1524)
				(type default)
			)
			(layer "F.SilkS")
		)
		(fp_line
			(start 2.1336 1.4224)
			(end 2.1336 -1.4224)
			(stroke
				(width 0.1524)
				(type default)
			)
			(layer "F.SilkS")
		)
		(fp_poly
			(pts
				(xy -2.2098 -1.4224) (xy -2.2098 1.4224) (xy 2.2098 1.4224) (xy 2.2098 -1.4224)
			)
			(stroke
				(width 0)
				(type default)
			)
			(fill yes)
			(layer "F.SilkS")
		)
		(fp_rect
			(start -2.450084 2.999994)
			(end 2.450084 -2.999994)
			(stroke
				(width 0)
				(type default)
			)
			(fill no)
			(layer "F.CrtYd")
		)
		(fp_poly
			(pts
				(xy -2.8194 3.6322) (xy -2.8194 -3.6322) (xy 2.8194 -3.6322) (xy 2.8194 1.18364) (xy 2.450084 1.18364)
				(xy 2.450084 -2.999994) (xy -2.450084 -2.999994) (xy -2.450084 2.999994) (xy 2.450084 2.999994)
				(xy 2.450084 1.18618) (xy 2.8194 1.18618) (xy 2.8194 3.6322)
			)
			(stroke
				(width 0)
				(type default)
			)
			(fill no)
			(layer "F.CrtYd")
		)
		(fp_rect
			(start -2.8194 3.6322)
			(end 2.8194 -3.6322)
			(stroke
				(width 0)
				(type default)
			)
			(fill no)
			(layer "F.Fab")
		)
		(pad "1" smd rect
			(at -1.905 2.54)
			(size 0.635 1.651)
			(layers "F.Cu" "F.Mask" "F.Paste")
			(net "P12V_B")
		)
		(pad "2" smd rect
			(at -0.635 2.54)
			(size 0.635 1.651)
			(layers "F.Cu" "F.Mask" "F.Paste")
			(net "P12V_B")
		)
		(pad "3" smd rect
			(at 0.635 2.54)
			(size 0.635 1.651)
			(layers "F.Cu" "F.Mask" "F.Paste")
			(net "P12V_B")
		)
		(pad "4" smd rect
			(at 1.905 2.54)
			(size 0.635 1.651)
			(layers "F.Cu" "F.Mask" "F.Paste")
			(net "SW_HDD_N26")
		)
		(pad "5" smd rect
			(at 1.905 -2.54)
			(size 0.635 1.651)
			(layers "F.Cu" "F.Mask" "F.Paste")
			(net "P12V_HDD26")
		)
		(pad "6" smd rect
			(at 0.635 -2.54)
			(size 0.635 1.651)
			(layers "F.Cu" "F.Mask" "F.Paste")
			(net "P12V_HDD26")
		)
		(pad "7" smd rect
			(at -0.635 -2.54)
			(size 0.635 1.651)
			(layers "F.Cu" "F.Mask" "F.Paste")
			(net "P12V_HDD26")
		)
		(pad "8" smd rect
			(at -1.905 -2.54)
			(size 0.635 1.651)
			(layers "F.Cu" "F.Mask" "F.Paste")
			(net "P12V_HDD26")
		)
	)
	(footprint ""
		(layer "F.Cu")
		(at 190.213488 -14.660626 90)
		(property "Reference" "C406"
			(at 0 0 90)
			(layer "F.SilkS")
			(hide yes)
			(effects
				(font
					(size 1.27 1.27)
				)
			)
		)
		(property "Value" "SCD01U16V1KX-GP"
			(at -2.8321 -1.7399 90)
			(unlocked yes)
			(layer "F.Fab")
			(hide yes)
			(effects
				(font
					(size 1.016 1.016)
					(thickness 0.1524)
				)
			)
		)
		(property "Device Type" "C0201H13"
			(at -2.8321 -3.2639 90)
			(unlocked yes)
			(layer "F.Fab")
			(hide yes)
			(effects
				(font
					(size 1.016 1.016)
					(thickness 0.1524)
				)
			)
		)
		(duplicate_pad_numbers_are_jumpers no)
		(fp_rect
			(start -0.2794 0.6477)
			(end 0.2794 -0.6477)
			(stroke
				(width 0)
				(type default)
			)
			(fill no)
			(layer "F.CrtYd")
		)
		(fp_rect
			(start -0.2794 0.6477)
			(end 0.2794 -0.6477)
			(stroke
				(width 0)
				(type default)
			)
			(fill no)
			(layer "F.Fab")
		)
		(pad "1" smd custom
			(at 0 -0.2794 90)
			(size 0.0762 0.0762)
			(layers "F.Cu" "F.Mask" "F.Paste")
			(net "SAS_HDD_RX_P29")
			(options
				(clearance outline)
				(anchor circle)
			)
			(primitives
				(gr_poly
					(pts
						(arc
							(start 0.1524 -0.127)
							(mid 0.137521 -0.162921)
							(end 0.1016 -0.1778)
						)
						(arc
							(start -0.1016 -0.1778)
							(mid -0.137521 -0.162921)
							(end -0.1524 -0.127)
						)
						(arc
							(start -0.1524 0.127)
							(mid -0.137521 0.162921)
							(end -0.1016 0.1778)
						)
						(arc
							(start 0.1016 0.1778)
							(mid 0.137521 0.162921)
							(end 0.1524 0.127)
						)
					)
					(width 0)
					(fill yes)
				)
			)
		)
		(pad "2" smd custom
			(at 0 0.2794 90)
			(size 0.0762 0.0762)
			(layers "F.Cu" "F.Mask" "F.Paste")
			(net "PHY_SCC_B_TO_DRV_B_29_DP")
			(options
				(clearance outline)
				(anchor circle)
			)
			(primitives
				(gr_poly
					(pts
						(arc
							(start 0.1524 -0.127)
							(mid 0.137521 -0.162921)
							(end 0.1016 -0.1778)
						)
						(arc
							(start -0.1016 -0.1778)
							(mid -0.137521 -0.162921)
							(end -0.1524 -0.127)
						)
						(arc
							(start -0.1524 0.127)
							(mid -0.137521 0.162921)
							(end -0.1016 0.1778)
						)
						(arc
							(start 0.1016 0.1778)
							(mid 0.137521 0.162921)
							(end 0.1524 0.127)
						)
					)
					(width 0)
					(fill yes)
				)
			)
		)
	)
	(footprint ""
		(layer "F.Cu")
		(at 286.086804 -287.690052 -90)
		(property "Reference" "PWR1"
			(at 0 0 270)
			(layer "F.SilkS")
			(hide yes)
			(effects
				(font
					(size 1.27 1.27)
				)
			)
		)
		(property "Value" "AMP-CONN8-2R-2-GP"
			(at 15.875 6.604 270)
			(unlocked yes)
			(layer "F.Fab")
			(hide yes)
			(effects
				(font
					(size 1.016 1.016)
					(thickness 0.1524)
				)
			)
		)
		(property "Device Type" "PREFIT-8P-5697-1H404"
			(at 15.875 5.08 270)
			(unlocked yes)
			(layer "F.Fab")
			(hide yes)
			(effects
				(font
					(size 1.016 1.016)
					(thickness 0.1524)
				)
			)
		)
		(duplicate_pad_numbers_are_jumpers no)
		(fp_line
			(start -1.4478 8.2804)
			(end -1.4478 -1.9558)
			(stroke
				(width 0.1524)
				(type default)
			)
			(layer "F.SilkS")
		)
		(fp_line
			(start 4.6482 8.2804)
			(end -1.4478 8.2804)
			(stroke
				(width 0.1524)
				(type default)
			)
			(layer "F.SilkS")
		)
		(fp_line
			(start -1.4478 -1.9558)
			(end 4.6482 -1.9558)
			(stroke
				(width 0.1524)
				(type default)
			)
			(layer "F.SilkS")
		)
		(fp_line
			(start 4.6482 -1.9558)
			(end 4.6482 8.2804)
			(stroke
				(width 0.1524)
				(type default)
			)
			(layer "F.SilkS")
		)
		(fp_poly
			(pts
				(xy -1.4478 8.2804) (xy -1.4478 -0.864616) (xy -0.8636 -0.864616) (xy -0.8636 8.128) (xy 4.063492 8.128)
				(xy 4.063492 -0.864616) (xy 4.6482 -0.864616) (xy 4.6482 8.2804)
			)
			(stroke
				(width 0)
				(type default)
			)
			(fill yes)
			(layer "F.SilkS")
		)
		(fp_poly
			(pts
				(arc
					(start 0.2032 7.8486)
					(mid 0 8.0518)
					(end -0.2032 7.8486)
				)
				(arc
					(start -0.2032 7.6454)
					(mid 0 7.4422)
					(end 0.2032 7.6454)
				)
			)
			(stroke
				(width 0)
				(type default)
			)
			(fill yes)
			(layer "F.SilkS")
		)
		(fp_poly
			(pts
				(arc
					(start 3.403092 7.8486)
					(mid 3.199892 8.0518)
					(end 2.996692 7.8486)
				)
				(arc
					(start 2.996692 7.6454)
					(mid 3.199892 7.4422)
					(end 3.403092 7.6454)
				)
			)
			(stroke
				(width 0)
				(type default)
			)
			(fill yes)
			(layer "F.SilkS")
		)
		(fp_rect
			(start -5.6134 11.938)
			(end 8.8138 -5.6134)
			(stroke
				(width 0)
				(type default)
			)
			(fill no)
			(layer "B.CrtYd")
		)
		(fp_rect
			(start -1.1938 8.0264)
			(end 4.3942 -1.7018)
			(stroke
				(width 0)
				(type default)
			)
			(fill no)
			(layer "F.CrtYd")
		)
		(fp_poly
			(pts
				(xy -6.1976 13.0302) (xy -6.1976 -6.7056) (xy 9.398 -6.7056) (xy 9.398 0) (xy 4.9022 0) (xy 4.9022 -2.2098)
				(xy -1.7018 -2.2098) (xy -1.7018 8.5344) (xy 4.9022 8.5344) (xy 4.9022 0.0127) (xy 9.398 0.0127)
				(xy 9.398 13.0302)
			)
			(stroke
				(width 0)
				(type default)
			)
			(fill no)
			(layer "F.CrtYd")
		)
		(fp_poly
			(pts
				(xy -1.7018 8.5344) (xy -1.7018 -2.2098) (xy 4.9022 -2.2098) (xy 4.9022 0) (xy 4.3942 0) (xy 4.3942 -1.7018)
				(xy -1.1938 -1.7018) (xy -1.1938 8.0264) (xy 4.3942 8.0264) (xy 4.3942 0.0127) (xy 4.9022 0.0127)
				(xy 4.9022 8.5344)
			)
			(stroke
				(width 0)
				(type default)
			)
			(fill no)
			(layer "F.CrtYd")
		)
		(fp_rect
			(start -10.6172 16.9418)
			(end 13.8176 -10.6172)
			(stroke
				(width 0)
				(type default)
			)
			(fill no)
			(layer "B.Fab")
		)
		(fp_rect
			(start -5.6134 11.938)
			(end 8.8138 -5.6134)
			(stroke
				(width 0)
				(type default)
			)
			(fill no)
			(layer "B.Fab")
		)
		(fp_rect
			(start -11.2014 18.034)
			(end 14.4018 -11.7094)
			(stroke
				(width 0)
				(type default)
			)
			(fill no)
			(layer "F.Fab")
		)
		(fp_rect
			(start -6.1976 13.0302)
			(end 9.398 -6.7056)
			(stroke
				(width 0)
				(type default)
			)
			(fill no)
			(layer "F.Fab")
		)
		(fp_rect
			(start -1.7018 8.5344)
			(end 4.9022 -2.2098)
			(stroke
				(width 0)
				(type default)
			)
			(fill no)
			(layer "F.Fab")
		)
		(fp_text user "Pre Fit"
			(at -2.286 -1.3462 270)
			(unlocked yes)
			(layer "F.SilkS")
			(effects
				(font
					(size 1.016 1.016)
					(thickness 0.1524)
				)
				(justify left)
			)
		)
		(fp_text user "Can not place BGA,CSP,Wave Solder Component"
			(at -24.9428 14.9352 270)
			(unlocked yes)
			(layer "B.Fab")
			(effects
				(font
					(size 1.016 1.016)
					(thickness 0.1524)
				)
				(justify left)
			)
		)
		(fp_text user "Can not place BGA,CSP,Wave Solder Component"
			(at -22.987 15.9258 270)
			(unlocked yes)
			(layer "F.Fab")
			(effects
				(font
					(size 1.016 1.016)
					(thickness 0.1524)
				)
				(justify left)
			)
		)
		(fp_text user "High Limit 2mm"
			(at -6.604 11.3538 270)
			(unlocked yes)
			(layer "F.Fab")
			(effects
				(font
					(size 1.016 1.016)
					(thickness 0.1524)
				)
				(justify left)
			)
		)
		(pad "A1" thru_hole oval
			(at 0 0 270)
			(size 1.2192 2.921)
			(drill 0.739902
				(offset 0 0.849884)
			)
			(layers "*.Cu" "*.Mask")
			(remove_unused_layers no)
			(net "P12V_B")
			(clearance 0.127)
			(thermal_gap 0.127)
			(padstack
				(mode front_inner_back)
				(layer "Inner"
					(shape circle)
					(size 1.2192 1.2192)
					(clearance 0.127)
				)
				(layer "B.Cu"
					(shape circle)
					(size 1.2192 1.2192)
					(clearance 0.127)
				)
			)
		)
		(pad "A2" thru_hole circle
			(at 0 1.700022 270)
			(size 1.2192 1.2192)
			(drill 0.739902)
			(layers "*.Cu" "*.Mask")
			(remove_unused_layers no)
			(net "P12V_B")
			(clearance 0.127)
			(thermal_gap 0.127)
		)
		(pad "A3" thru_hole oval
			(at 0 4.629912 270)
			(size 1.2192 2.921)
			(drill 0.739902
				(offset 0 0.849884)
			)
			(layers "*.Cu" "*.Mask")
			(remove_unused_layers no)
			(net "P12V_B")
			(clearance 0.127)
			(thermal_gap 0.127)
			(padstack
				(mode front_inner_back)
				(layer "Inner"
					(shape circle)
					(size 1.2192 1.2192)
					(clearance 0.127)
				)
				(layer "B.Cu"
					(shape circle)
					(size 1.2192 1.2192)
					(clearance 0.127)
				)
			)
		)
		(pad "A4" thru_hole circle
			(at 0 6.329934 270)
			(size 1.2192 1.2192)
			(drill 0.739902)
			(layers "*.Cu" "*.Mask")
			(remove_unused_layers no)
			(net "P12V_B")
			(clearance 0.127)
			(thermal_gap 0.127)
		)
		(pad "B1" thru_hole oval
			(at 3.199892 0 270)
			(size 1.2192 2.921)
			(drill 0.739902
				(offset 0 0.849884)
			)
			(layers "*.Cu" "*.Mask")
			(remove_unused_layers no)
			(net "GND")
			(clearance 0.127)
			(thermal_gap 0.127)
			(padstack
				(mode front_inner_back)
				(layer "Inner"
					(shape circle)
					(size 1.2192 1.2192)
					(clearance 0.127)
				)
				(layer "B.Cu"
					(shape circle)
					(size 1.2192 1.2192)
					(clearance 0.127)
				)
			)
		)
		(pad "B2" thru_hole circle
			(at 3.199892 1.700022 270)
			(size 1.2192 1.2192)
			(drill 0.739902)
			(layers "*.Cu" "*.Mask")
			(remove_unused_layers no)
			(net "GND")
			(clearance 0.127)
			(thermal_gap 0.127)
		)
		(pad "B3" thru_hole oval
			(at 3.199892 4.629912 270)
			(size 1.2192 2.921)
			(drill 0.739902
				(offset 0 0.849884)
			)
			(layers "*.Cu" "*.Mask")
			(remove_unused_layers no)
			(net "GND")
			(clearance 0.127)
			(thermal_gap 0.127)
			(padstack
				(mode front_inner_back)
				(layer "Inner"
					(shape circle)
					(size 1.2192 1.2192)
					(clearance 0.127)
				)
				(layer "B.Cu"
					(shape circle)
					(size 1.2192 1.2192)
					(clearance 0.127)
				)
			)
		)
		(pad "B4" thru_hole circle
			(at 3.199892 6.329934 270)
			(size 1.2192 1.2192)
			(drill 0.739902)
			(layers "*.Cu" "*.Mask")
			(remove_unused_layers no)
			(net "GND")
			(clearance 0.127)
			(thermal_gap 0.127)
		)
		(zone
			(layer "F.Cu")
			(hatch none 0.5)
			(connect_pads
				(clearance 0)
			)
			(min_thickness 0.25)
			(keepout
				(tracks allowed)
				(vias not_allowed)
				(pads allowed)
				(copperpour not_allowed)
				(footprints allowed)
			)
			(placement
				(enabled no)
				(sheetname "")
			)
			(fill
				(thermal_gap 0.5)
				(thermal_bridge_width 0.5)
				(island_removal_mode 0)
			)
			(polygon
				(pts
					(xy 278.906732 -288.539936) (xy 278.906732 -283.640022) (xy 286.936688 -283.640022) (xy 286.936688 -288.539936)
				)
			)
		)
		(zone
			(layer "F.Cu")
			(hatch none 0.5)
			(connect_pads
				(clearance 0)
			)
			(min_thickness 0.25)
			(keepout
				(tracks not_allowed)
				(vias allowed)
				(pads allowed)
				(copperpour not_allowed)
				(footprints allowed)
			)
			(placement
				(enabled no)
				(sheetname "")
			)
			(fill
				(thermal_gap 0.5)
				(thermal_bridge_width 0.5)
				(island_removal_mode 0)
			)
			(polygon
				(pts
					(xy 278.906732 -288.539936) (xy 278.906732 -283.640022) (xy 286.936688 -283.640022) (xy 286.936688 -288.539936)
				)
			)
		)
	)
	(footprint ""
		(layer "F.Cu")
		(at 251.394468 -222.9612)
		(property "Reference" "R111"
			(at 0 0 0)
			(layer "F.SilkS")
			(hide yes)
			(effects
				(font
					(size 1.27 1.27)
				)
			)
		)
		(property "Value" "4K7R2F-GP"
			(at 0.064008 -3.993896 0)
			(unlocked yes)
			(layer "F.Fab")
			(hide yes)
			(effects
				(font
					(size 1.016 1.016)
					(thickness 0.1524)
				)
			)
		)
		(property "Device Type" "R402H16"
			(at 0.064008 -5.517896 0)
			(unlocked yes)
			(layer "F.Fab")
			(hide yes)
			(effects
				(font
					(size 1.016 1.016)
					(thickness 0.1524)
				)
			)
		)
		(duplicate_pad_numbers_are_jumpers no)
		(fp_line
			(start -0.508 -0.9398)
			(end -0.508 0.9398)
			(stroke
				(width 0.1524)
				(type default)
			)
			(layer "F.SilkS")
		)
		(fp_line
			(start 0.508 -0.9398)
			(end -0.508 -0.9398)
			(stroke
				(width 0.1524)
				(type default)
			)
			(layer "F.SilkS")
		)
		(fp_rect
			(start -0.508 0.9398)
			(end 0.508 -0.9398)
			(stroke
				(width 0)
				(type default)
			)
			(fill no)
			(layer "F.CrtYd")
		)
		(fp_rect
			(start -0.508 0.9398)
			(end 0.508 -0.9398)
			(stroke
				(width 0)
				(type default)
			)
			(fill no)
			(layer "F.Fab")
		)
		(pad "1" smd custom
			(at 0 -0.4445)
			(size 0.1397 0.1397)
			(layers "F.Cu" "F.Mask" "F.Paste")
			(net "P3V3_STBY_B")
			(options
				(clearance outline)
				(anchor circle)
			)
			(primitives
				(gr_poly
					(pts
						(arc
							(start -0.1778 -0.2794)
							(mid -0.249642 -0.249642)
							(end -0.2794 -0.1778)
						)
						(arc
							(start -0.2794 0.1778)
							(mid -0.249642 0.249642)
							(end -0.1778 0.2794)
						)
						(arc
							(start 0.1778 0.2794)
							(mid 0.249642 0.249642)
							(end 0.2794 0.1778)
						)
						(arc
							(start 0.2794 -0.1778)
							(mid 0.249642 -0.249642)
							(end 0.1778 -0.2794)
						)
					)
					(width 0)
					(fill yes)
				)
			)
		)
		(pad "2" smd custom
			(at 0 0.4445)
			(size 0.1397 0.1397)
			(layers "F.Cu" "F.Mask" "F.Paste")
			(net "EEPROM_A0")
			(options
				(clearance outline)
				(anchor circle)
			)
			(primitives
				(gr_poly
					(pts
						(arc
							(start -0.1778 -0.2794)
							(mid -0.249642 -0.249642)
							(end -0.2794 -0.1778)
						)
						(arc
							(start -0.2794 0.1778)
							(mid -0.249642 0.249642)
							(end -0.1778 0.2794)
						)
						(arc
							(start 0.1778 0.2794)
							(mid 0.249642 0.249642)
							(end 0.2794 0.1778)
						)
						(arc
							(start 0.2794 -0.1778)
							(mid 0.249642 -0.249642)
							(end 0.1778 -0.2794)
						)
					)
					(width 0)
					(fill yes)
				)
			)
		)
	)
	(footprint ""
		(layer "F.Cu")
		(at 111.379 -253.111 90)
		(property "Reference" "R211"
			(at 0 0 90)
			(layer "F.SilkS")
			(hide yes)
			(effects
				(font
					(size 1.27 1.27)
				)
			)
		)
		(property "Value" "4K7R2J-2-GP"
			(at 0.064008 -3.993896 90)
			(unlocked yes)
			(layer "F.Fab")
			(hide yes)
			(effects
				(font
					(size 1.016 1.016)
					(thickness 0.1524)
				)
			)
		)
		(property "Device Type" "R402H16"
			(at 0.064008 -5.517896 90)
			(unlocked yes)
			(layer "F.Fab")
			(hide yes)
			(effects
				(font
					(size 1.016 1.016)
					(thickness 0.1524)
				)
			)
		)
		(duplicate_pad_numbers_are_jumpers no)
		(fp_line
			(start 0.508 -0.9398)
			(end -0.508 -0.9398)
			(stroke
				(width 0.1524)
				(type default)
			)
			(layer "F.SilkS")
		)
		(fp_line
			(start -0.508 -0.9398)
			(end -0.508 0.9398)
			(stroke
				(width 0.1524)
				(type default)
			)
			(layer "F.SilkS")
		)
		(fp_rect
			(start -0.508 0.9398)
			(end 0.508 -0.9398)
			(stroke
				(width 0)
				(type default)
			)
			(fill no)
			(layer "F.CrtYd")
		)
		(fp_rect
			(start -0.508 0.9398)
			(end 0.508 -0.9398)
			(stroke
				(width 0)
				(type default)
			)
			(fill no)
			(layer "F.Fab")
		)
		(pad "1" smd custom
			(at 0 -0.4445 90)
			(size 0.1397 0.1397)
			(layers "F.Cu" "F.Mask" "F.Paste")
			(net "P12V_B")
			(options
				(clearance outline)
				(anchor circle)
			)
			(primitives
				(gr_poly
					(pts
						(arc
							(start -0.1778 -0.2794)
							(mid -0.249642 -0.249642)
							(end -0.2794 -0.1778)
						)
						(arc
							(start -0.2794 0.1778)
							(mid -0.249642 0.249642)
							(end -0.1778 0.2794)
						)
						(arc
							(start 0.1778 0.2794)
							(mid 0.249642 0.249642)
							(end 0.2794 0.1778)
						)
						(arc
							(start 0.2794 -0.1778)
							(mid 0.249642 -0.249642)
							(end 0.1778 -0.2794)
						)
					)
					(width 0)
					(fill yes)
				)
			)
		)
		(pad "2" smd custom
			(at 0 0.4445 90)
			(size 0.1397 0.1397)
			(layers "F.Cu" "F.Mask" "F.Paste")
			(net "SW_HDD_P3")
			(options
				(clearance outline)
				(anchor circle)
			)
			(primitives
				(gr_poly
					(pts
						(arc
							(start -0.1778 -0.2794)
							(mid -0.249642 -0.249642)
							(end -0.2794 -0.1778)
						)
						(arc
							(start -0.2794 0.1778)
							(mid -0.249642 0.249642)
							(end -0.1778 0.2794)
						)
						(arc
							(start 0.1778 0.2794)
							(mid 0.249642 0.249642)
							(end 0.2794 0.1778)
						)
						(arc
							(start 0.2794 -0.1778)
							(mid 0.249642 -0.249642)
							(end 0.1778 -0.2794)
						)
					)
					(width 0)
					(fill yes)
				)
			)
		)
	)
	(footprint ""
		(layer "F.Cu")
		(at 377.698 -99.187)
		(property "Reference" "R436"
			(at 0 0 0)
			(layer "F.SilkS")
			(hide yes)
			(effects
				(font
					(size 1.27 1.27)
				)
			)
		)
		(property "Value" "130R3F-GP"
			(at -0.0254 -2.5146 0)
			(unlocked yes)
			(layer "F.Fab")
			(hide yes)
			(effects
				(font
					(size 1.016 1.016)
					(thickness 0.1524)
				)
			)
		)
		(property "Device Type" "R603H22"
			(at -0.0254 -4.0386 0)
			(unlocked yes)
			(layer "F.Fab")
			(hide yes)
			(effects
				(font
					(size 1.016 1.016)
					(thickness 0.1524)
				)
			)
		)
		(duplicate_pad_numbers_are_jumpers no)
		(fp_line
			(start -0.4826 0)
			(end -0.2032 0)
			(stroke
				(width 0.2032)
				(type default)
			)
			(layer "F.SilkS")
		)
		(fp_line
			(start 0.2032 0)
			(end 0.4826 0)
			(stroke
				(width 0.2032)
				(type default)
			)
			(layer "F.SilkS")
		)
		(fp_rect
			(start -0.5842 1.3335)
			(end 0.5842 -1.3335)
			(stroke
				(width 0)
				(type default)
			)
			(fill no)
			(layer "F.CrtYd")
		)
		(fp_rect
			(start -0.5842 1.3335)
			(end 0.5842 -1.3335)
			(stroke
				(width 0)
				(type default)
			)
			(fill no)
			(layer "F.Fab")
		)
		(pad "1" smd custom
			(at 0 -0.762)
			(size 0.2159 0.2159)
			(layers "F.Cu" "F.Mask" "F.Paste")
			(net "P5V_B_3")
			(options
				(clearance outline)
				(anchor circle)
			)
			(primitives
				(gr_poly
					(pts
						(arc
							(start -0.3302 -0.4318)
							(mid -0.402042 -0.402042)
							(end -0.4318 -0.3302)
						)
						(arc
							(start -0.4318 0.3302)
							(mid -0.402042 0.402042)
							(end -0.3302 0.4318)
						)
						(arc
							(start 0.3302 0.4318)
							(mid 0.402042 0.402042)
							(end 0.4318 0.3302)
						)
						(arc
							(start 0.4318 -0.3302)
							(mid 0.402042 -0.402042)
							(end 0.3302 -0.4318)
						)
					)
					(width 0)
					(fill yes)
				)
			)
		)
		(pad "2" smd custom
			(at 0 0.762)
			(size 0.2159 0.2159)
			(layers "F.Cu" "F.Mask" "F.Paste")
			(net "FLT_HDD20")
			(options
				(clearance outline)
				(anchor circle)
			)
			(primitives
				(gr_poly
					(pts
						(arc
							(start -0.3302 -0.4318)
							(mid -0.402042 -0.402042)
							(end -0.4318 -0.3302)
						)
						(arc
							(start -0.4318 0.3302)
							(mid -0.402042 0.402042)
							(end -0.3302 0.4318)
						)
						(arc
							(start 0.3302 0.4318)
							(mid 0.402042 0.402042)
							(end 0.4318 0.3302)
						)
						(arc
							(start 0.4318 -0.3302)
							(mid 0.402042 -0.402042)
							(end 0.3302 -0.4318)
						)
					)
					(width 0)
					(fill yes)
				)
			)
		)
	)
	(footprint ""
		(layer "F.Cu")
		(at 455.93 -37.846 180)
		(property "Reference" "C472"
			(at 0 0 180)
			(layer "F.SilkS")
			(hide yes)
			(effects
				(font
					(size 1.27 1.27)
				)
			)
		)
		(property "Value" "SC1U16V3KX-5GP"
			(at 0 -2.8194 180)
			(unlocked yes)
			(layer "F.Fab")
			(hide yes)
			(effects
				(font
					(size 1.016 1.016)
					(thickness 0.1524)
				)
			)
		)
		(property "Device Type" "C603H36"
			(at 0 -4.3434 180)
			(unlocked yes)
			(layer "F.Fab")
			(hide yes)
			(effects
				(font
					(size 1.016 1.016)
					(thickness 0.1524)
				)
			)
		)
		(duplicate_pad_numbers_are_jumpers no)
		(fp_line
			(start 0.508 0)
			(end -0.508 0)
			(stroke
				(width 0.2032)
				(type default)
			)
			(layer "F.SilkS")
		)
		(fp_rect
			(start -0.5842 1.3335)
			(end 0.5842 -1.3335)
			(stroke
				(width 0)
				(type default)
			)
			(fill no)
			(layer "F.CrtYd")
		)
		(fp_rect
			(start -0.5842 1.3335)
			(end 0.5842 -1.3335)
			(stroke
				(width 0)
				(type default)
			)
			(fill no)
			(layer "F.Fab")
		)
		(pad "1" smd custom
			(at 0 -0.762 180)
			(size 0.2159 0.2159)
			(layers "F.Cu" "F.Mask" "F.Paste")
			(net "P5V_HDD34")
			(options
				(clearance outline)
				(anchor circle)
			)
			(primitives
				(gr_poly
					(pts
						(arc
							(start -0.3302 -0.4318)
							(mid -0.402042 -0.402042)
							(end -0.4318 -0.3302)
						)
						(arc
							(start -0.4318 0.3302)
							(mid -0.402042 0.402042)
							(end -0.3302 0.4318)
						)
						(arc
							(start 0.3302 0.4318)
							(mid 0.402042 0.402042)
							(end 0.4318 0.3302)
						)
						(arc
							(start 0.4318 -0.3302)
							(mid 0.402042 -0.402042)
							(end 0.3302 -0.4318)
						)
					)
					(width 0)
					(fill yes)
				)
			)
		)
		(pad "2" smd custom
			(at 0 0.762 180)
			(size 0.2159 0.2159)
			(layers "F.Cu" "F.Mask" "F.Paste")
			(net "GND")
			(options
				(clearance outline)
				(anchor circle)
			)
			(primitives
				(gr_poly
					(pts
						(arc
							(start -0.3302 -0.4318)
							(mid -0.402042 -0.402042)
							(end -0.4318 -0.3302)
						)
						(arc
							(start -0.4318 0.3302)
							(mid -0.402042 0.402042)
							(end -0.3302 0.4318)
						)
						(arc
							(start 0.3302 0.4318)
							(mid 0.402042 0.402042)
							(end 0.4318 0.3302)
						)
						(arc
							(start 0.4318 -0.3302)
							(mid 0.402042 -0.402042)
							(end 0.3302 -0.4318)
						)
					)
					(width 0)
					(fill yes)
				)
			)
		)
	)
	(footprint ""
		(layer "F.Cu")
		(at 231.267 -198.8312 90)
		(property "Reference" "R71"
			(at 0 0 90)
			(layer "F.SilkS")
			(hide yes)
			(effects
				(font
					(size 1.27 1.27)
				)
			)
		)
		(property "Value" "4K7R2F-GP"
			(at 0.064008 -3.993896 90)
			(unlocked yes)
			(layer "F.Fab")
			(hide yes)
			(effects
				(font
					(size 1.016 1.016)
					(thickness 0.1524)
				)
			)
		)
		(property "Device Type" "R402H16"
			(at 0.064008 -5.517896 90)
			(unlocked yes)
			(layer "F.Fab")
			(hide yes)
			(effects
				(font
					(size 1.016 1.016)
					(thickness 0.1524)
				)
			)
		)
		(duplicate_pad_numbers_are_jumpers no)
		(fp_line
			(start 0.508 -0.9398)
			(end -0.508 -0.9398)
			(stroke
				(width 0.1524)
				(type default)
			)
			(layer "F.SilkS")
		)
		(fp_line
			(start -0.508 -0.9398)
			(end -0.508 0.9398)
			(stroke
				(width 0.1524)
				(type default)
			)
			(layer "F.SilkS")
		)
		(fp_rect
			(start -0.508 0.9398)
			(end 0.508 -0.9398)
			(stroke
				(width 0)
				(type default)
			)
			(fill no)
			(layer "F.CrtYd")
		)
		(fp_rect
			(start -0.508 0.9398)
			(end 0.508 -0.9398)
			(stroke
				(width 0)
				(type default)
			)
			(fill no)
			(layer "F.Fab")
		)
		(pad "1" smd custom
			(at 0 -0.4445 90)
			(size 0.1397 0.1397)
			(layers "F.Cu" "F.Mask" "F.Paste")
			(net "P3V3_STBY_B")
			(options
				(clearance outline)
				(anchor circle)
			)
			(primitives
				(gr_poly
					(pts
						(arc
							(start -0.1778 -0.2794)
							(mid -0.249642 -0.249642)
							(end -0.2794 -0.1778)
						)
						(arc
							(start -0.2794 0.1778)
							(mid -0.249642 0.249642)
							(end -0.1778 0.2794)
						)
						(arc
							(start 0.1778 0.2794)
							(mid 0.249642 0.249642)
							(end 0.2794 0.1778)
						)
						(arc
							(start 0.2794 -0.1778)
							(mid 0.249642 -0.249642)
							(end 0.1778 -0.2794)
						)
					)
					(width 0)
					(fill yes)
				)
			)
		)
		(pad "2" smd custom
			(at 0 0.4445 90)
			(size 0.1397 0.1397)
			(layers "F.Cu" "F.Mask" "F.Paste")
			(net "IO_EXP2_A0")
			(options
				(clearance outline)
				(anchor circle)
			)
			(primitives
				(gr_poly
					(pts
						(arc
							(start -0.1778 -0.2794)
							(mid -0.249642 -0.249642)
							(end -0.2794 -0.1778)
						)
						(arc
							(start -0.2794 0.1778)
							(mid -0.249642 0.249642)
							(end -0.1778 0.2794)
						)
						(arc
							(start 0.1778 0.2794)
							(mid 0.249642 0.249642)
							(end 0.2794 0.1778)
						)
						(arc
							(start 0.2794 -0.1778)
							(mid 0.249642 -0.249642)
							(end 0.1778 -0.2794)
						)
					)
					(width 0)
					(fill yes)
				)
			)
		)
	)
	(footprint ""
		(layer "F.Cu")
		(at 444.513208 -112.710976 90)
		(property "Reference" "C679"
			(at 0 0 90)
			(layer "F.SilkS")
			(hide yes)
			(effects
				(font
					(size 1.27 1.27)
				)
			)
		)
		(property "Value" "SCD1U16V2KX-3GP"
			(at 1.1811 -2.7051 90)
			(unlocked yes)
			(layer "F.Fab")
			(hide yes)
			(effects
				(font
					(size 1.016 1.016)
					(thickness 0.1524)
				)
			)
		)
		(property "Device Type" "C402H22"
			(at 1.1811 -4.2291 90)
			(unlocked yes)
			(layer "F.Fab")
			(hide yes)
			(effects
				(font
					(size 1.016 1.016)
					(thickness 0.1524)
				)
			)
		)
		(duplicate_pad_numbers_are_jumpers no)
		(fp_rect
			(start -0.4318 0.9525)
			(end 0.4318 -0.9525)
			(stroke
				(width 0)
				(type default)
			)
			(fill no)
			(layer "F.CrtYd")
		)
		(fp_rect
			(start -0.4318 0.9525)
			(end 0.4318 -0.9525)
			(stroke
				(width 0)
				(type default)
			)
			(fill no)
			(layer "F.Fab")
		)
		(pad "1" smd custom
			(at 0 -0.4445 90)
			(size 0.1524 0.1524)
			(layers "F.Cu" "F.Mask" "F.Paste")
			(net "P5V_B_4_VBST_RC")
			(options
				(clearance outline)
				(anchor circle)
			)
			(primitives
				(gr_poly
					(pts
						(arc
							(start 0.3048 -0.2032)
							(mid 0.275042 -0.275042)
							(end 0.2032 -0.3048)
						)
						(arc
							(start -0.2032 -0.3048)
							(mid -0.275042 -0.275042)
							(end -0.3048 -0.2032)
						)
						(arc
							(start -0.3048 0.2032)
							(mid -0.275042 0.275042)
							(end -0.2032 0.3048)
						)
						(arc
							(start 0.2032 0.3048)
							(mid 0.275042 0.275042)
							(end 0.3048 0.2032)
						)
					)
					(width 0)
					(fill yes)
				)
			)
		)
		(pad "2" smd custom
			(at 0 0.4445 90)
			(size 0.1524 0.1524)
			(layers "F.Cu" "F.Mask" "F.Paste")
			(net "P5V_B_4_LL")
			(options
				(clearance outline)
				(anchor circle)
			)
			(primitives
				(gr_poly
					(pts
						(arc
							(start 0.3048 -0.2032)
							(mid 0.275042 -0.275042)
							(end 0.2032 -0.3048)
						)
						(arc
							(start -0.2032 -0.3048)
							(mid -0.275042 -0.275042)
							(end -0.3048 -0.2032)
						)
						(arc
							(start -0.3048 0.2032)
							(mid -0.275042 0.275042)
							(end -0.2032 0.3048)
						)
						(arc
							(start 0.2032 0.3048)
							(mid 0.275042 0.275042)
							(end 0.3048 0.2032)
						)
					)
					(width 0)
					(fill yes)
				)
			)
		)
	)
	(footprint ""
		(layer "F.Cu")
		(at 221.73946 -165.40226 -90)
		(property "Reference" "R55"
			(at 0 0 270)
			(layer "F.SilkS")
			(hide yes)
			(effects
				(font
					(size 1.27 1.27)
				)
			)
		)
		(property "Value" "4K7R2F-GP"
			(at 0.064008 -3.993896 270)
			(unlocked yes)
			(layer "F.Fab")
			(hide yes)
			(effects
				(font
					(size 1.016 1.016)
					(thickness 0.1524)
				)
			)
		)
		(property "Device Type" "R402H16"
			(at 0.064008 -5.517896 270)
			(unlocked yes)
			(layer "F.Fab")
			(hide yes)
			(effects
				(font
					(size 1.016 1.016)
					(thickness 0.1524)
				)
			)
		)
		(duplicate_pad_numbers_are_jumpers no)
		(fp_line
			(start -0.508 -0.9398)
			(end -0.508 0.9398)
			(stroke
				(width 0.1524)
				(type default)
			)
			(layer "F.SilkS")
		)
		(fp_line
			(start 0.508 -0.9398)
			(end -0.508 -0.9398)
			(stroke
				(width 0.1524)
				(type default)
			)
			(layer "F.SilkS")
		)
		(fp_rect
			(start -0.508 0.9398)
			(end 0.508 -0.9398)
			(stroke
				(width 0)
				(type default)
			)
			(fill no)
			(layer "F.CrtYd")
		)
		(fp_rect
			(start -0.508 0.9398)
			(end 0.508 -0.9398)
			(stroke
				(width 0)
				(type default)
			)
			(fill no)
			(layer "F.Fab")
		)
		(pad "1" smd custom
			(at 0 -0.4445 270)
			(size 0.1397 0.1397)
			(layers "F.Cu" "F.Mask" "F.Paste")
			(net "P3V3_STBY_B")
			(options
				(clearance outline)
				(anchor circle)
			)
			(primitives
				(gr_poly
					(pts
						(arc
							(start -0.1778 -0.2794)
							(mid -0.249642 -0.249642)
							(end -0.2794 -0.1778)
						)
						(arc
							(start -0.2794 0.1778)
							(mid -0.249642 0.249642)
							(end -0.1778 0.2794)
						)
						(arc
							(start 0.1778 0.2794)
							(mid 0.249642 0.249642)
							(end 0.2794 0.1778)
						)
						(arc
							(start 0.2794 -0.1778)
							(mid 0.249642 -0.249642)
							(end 0.1778 -0.2794)
						)
					)
					(width 0)
					(fill yes)
				)
			)
		)
		(pad "2" smd custom
			(at 0 0.4445 270)
			(size 0.1397 0.1397)
			(layers "F.Cu" "F.Mask" "F.Paste")
			(net "IO_EXP6_A2")
			(options
				(clearance outline)
				(anchor circle)
			)
			(primitives
				(gr_poly
					(pts
						(arc
							(start -0.1778 -0.2794)
							(mid -0.249642 -0.249642)
							(end -0.2794 -0.1778)
						)
						(arc
							(start -0.2794 0.1778)
							(mid -0.249642 0.249642)
							(end -0.1778 0.2794)
						)
						(arc
							(start 0.1778 0.2794)
							(mid 0.249642 0.249642)
							(end 0.2794 0.1778)
						)
						(arc
							(start 0.2794 -0.1778)
							(mid 0.249642 -0.249642)
							(end 0.1778 -0.2794)
						)
					)
					(width 0)
					(fill yes)
				)
			)
		)
	)
	(footprint ""
		(layer "F.Cu")
		(at 176.6824 -9.9314 180)
		(property "Reference" "C416"
			(at 0 0 180)
			(layer "F.SilkS")
			(hide yes)
			(effects
				(font
					(size 1.27 1.27)
				)
			)
		)
		(property "Value" "SCD033U25V2KX-GP"
			(at 1.1811 -2.7051 180)
			(unlocked yes)
			(layer "F.Fab")
			(hide yes)
			(effects
				(font
					(size 1.016 1.016)
					(thickness 0.1524)
				)
			)
		)
		(property "Device Type" "C402H22"
			(at 1.1811 -4.2291 180)
			(unlocked yes)
			(layer "F.Fab")
			(hide yes)
			(effects
				(font
					(size 1.016 1.016)
					(thickness 0.1524)
				)
			)
		)
		(duplicate_pad_numbers_are_jumpers no)
		(fp_rect
			(start -0.4318 0.9525)
			(end 0.4318 -0.9525)
			(stroke
				(width 0)
				(type default)
			)
			(fill no)
			(layer "F.CrtYd")
		)
		(fp_rect
			(start -0.4318 0.9525)
			(end 0.4318 -0.9525)
			(stroke
				(width 0)
				(type default)
			)
			(fill no)
			(layer "F.Fab")
		)
		(pad "1" smd custom
			(at 0 -0.4445 180)
			(size 0.1524 0.1524)
			(layers "F.Cu" "F.Mask" "F.Paste")
			(net "P12V_B")
			(options
				(clearance outline)
				(anchor circle)
			)
			(primitives
				(gr_poly
					(pts
						(arc
							(start 0.3048 -0.2032)
							(mid 0.275042 -0.275042)
							(end 0.2032 -0.3048)
						)
						(arc
							(start -0.2032 -0.3048)
							(mid -0.275042 -0.275042)
							(end -0.3048 -0.2032)
						)
						(arc
							(start -0.3048 0.2032)
							(mid -0.275042 0.275042)
							(end -0.2032 0.3048)
						)
						(arc
							(start 0.2032 0.3048)
							(mid 0.275042 0.275042)
							(end 0.3048 0.2032)
						)
					)
					(width 0)
					(fill yes)
				)
			)
		)
		(pad "2" smd custom
			(at 0 0.4445 180)
			(size 0.1524 0.1524)
			(layers "F.Cu" "F.Mask" "F.Paste")
			(net "SW_HDD_N29")
			(options
				(clearance outline)
				(anchor circle)
			)
			(primitives
				(gr_poly
					(pts
						(arc
							(start 0.3048 -0.2032)
							(mid 0.275042 -0.275042)
							(end 0.2032 -0.3048)
						)
						(arc
							(start -0.2032 -0.3048)
							(mid -0.275042 -0.275042)
							(end -0.3048 -0.2032)
						)
						(arc
							(start -0.3048 0.2032)
							(mid -0.275042 0.275042)
							(end -0.2032 0.3048)
						)
						(arc
							(start 0.2032 0.3048)
							(mid 0.275042 0.275042)
							(end 0.3048 0.2032)
						)
					)
					(width 0)
					(fill yes)
				)
			)
		)
	)
	(footprint ""
		(layer "F.Cu")
		(at 282.619958 -104.894888)
		(property "Reference" "TC3"
			(at 0 0 0)
			(layer "F.SilkS")
			(hide yes)
			(effects
				(font
					(size 1.27 1.27)
				)
			)
		)
		(property "Value" "SE270U16VM-8-GP"
			(at -4.5974 -2.54 0)
			(unlocked yes)
			(layer "F.Fab")
			(hide yes)
			(effects
				(font
					(size 1.016 1.016)
					(thickness 0.1524)
				)
			)
		)
		(property "Device Type" "SE361416H394"
			(at -4.5974 -4.064 0)
			(unlocked yes)
			(layer "F.Fab")
			(hide yes)
			(effects
				(font
					(size 1.016 1.016)
					(thickness 0.1524)
				)
			)
		)
		(duplicate_pad_numbers_are_jumpers no)
		(fp_line
			(start -3.556 -3.4163)
			(end -2.3622 -4.6101)
			(stroke
				(width 0.1524)
				(type default)
			)
			(layer "F.SilkS")
		)
		(fp_line
			(start -3.556 4.6101)
			(end -3.556 -3.4163)
			(stroke
				(width 0.1524)
				(type default)
			)
			(layer "F.SilkS")
		)
		(fp_line
			(start -2.3622 -4.6101)
			(end 2.3622 -4.6101)
			(stroke
				(width 0.1524)
				(type default)
			)
			(layer "F.SilkS")
		)
		(fp_line
			(start 2.3622 -4.6101)
			(end 3.556 -3.4163)
			(stroke
				(width 0.1524)
				(type default)
			)
			(layer "F.SilkS")
		)
		(fp_line
			(start 3.556 -3.4163)
			(end 3.556 4.6101)
			(stroke
				(width 0.1524)
				(type default)
			)
			(layer "F.SilkS")
		)
		(fp_line
			(start 3.556 4.6101)
			(end -3.556 4.6101)
			(stroke
				(width 0.1524)
				(type default)
			)
			(layer "F.SilkS")
		)
		(fp_rect
			(start -3.302 3.6449)
			(end 3.302 -3.6449)
			(stroke
				(width 0)
				(type default)
			)
			(fill no)
			(layer "F.CrtYd")
		)
		(fp_poly
			(pts
				(xy 3.81 4.6863) (xy 3.81 -3.4925) (xy 3.302 -3.4925) (xy 3.302 3.6449) (xy -3.302 3.6449) (xy -3.302 -3.6449)
				(xy 3.302 -3.6449) (xy 3.302 -3.5052) (xy 3.81 -3.5052) (xy 3.81 -4.6863) (xy -3.81 -4.6863) (xy -3.81 4.6863)
			)
			(stroke
				(width 0)
				(type default)
			)
			(fill no)
			(layer "F.CrtYd")
		)
		(fp_rect
			(start -3.81 4.6863)
			(end 3.81 -4.6863)
			(stroke
				(width 0)
				(type default)
			)
			(fill no)
			(layer "F.Fab")
		)
		(pad "1" smd rect
			(at 0 -2.574036)
			(size 1.4224 3.556)
			(layers "F.Cu" "F.Mask" "F.Paste")
			(net "P12V_B")
		)
		(pad "2" smd rect
			(at 0 2.574036)
			(size 1.4224 3.556)
			(layers "F.Cu" "F.Mask" "F.Paste")
			(net "GND")
		)
	)
	(footprint ""
		(layer "F.Cu")
		(at 265.625072 -337.309206 90)
		(property "Reference" "R1054"
			(at 0 0 90)
			(layer "F.SilkS")
			(hide yes)
			(effects
				(font
					(size 1.27 1.27)
				)
			)
		)
		(property "Value" "10R5F-1-GP"
			(at 0 -8.9535 90)
			(unlocked yes)
			(layer "F.Fab")
			(hide yes)
			(effects
				(font
					(size 1.27 1.016)
					(thickness 0.1524)
				)
			)
		)
		(property "Device Type" "R805H24"
			(at 0 -10.6299 90)
			(unlocked yes)
			(layer "F.Fab")
			(hide yes)
			(effects
				(font
					(size 1.27 1.016)
					(thickness 0.1524)
				)
			)
		)
		(duplicate_pad_numbers_are_jumpers no)
		(fp_line
			(start 0.889 -1.7018)
			(end -0.889 -1.7018)
			(stroke
				(width 0.1524)
				(type default)
			)
			(layer "F.SilkS")
		)
		(fp_line
			(start 0.889 -1.7018)
			(end 0.889 -0.381)
			(stroke
				(width 0.1524)
				(type default)
			)
			(layer "F.SilkS")
		)
		(fp_line
			(start -0.889 -1.7018)
			(end -0.889 0.2794)
			(stroke
				(width 0.1524)
				(type default)
			)
			(layer "F.SilkS")
		)
		(fp_line
			(start -0.889 0.0762)
			(end -0.889 1.7018)
			(stroke
				(width 0.1524)
				(type default)
			)
			(layer "F.SilkS")
		)
		(fp_line
			(start 0.889 1.7018)
			(end 0.889 -0.508)
			(stroke
				(width 0.1524)
				(type default)
			)
			(layer "F.SilkS")
		)
		(fp_line
			(start -0.889 1.7018)
			(end 0.889 1.7018)
			(stroke
				(width 0.1524)
				(type default)
			)
			(layer "F.SilkS")
		)
		(fp_poly
			(pts
				(xy 0.9652 -1.778) (xy 0.9652 1.778) (xy -0.9652 1.778) (xy -0.9652 -1.778)
			)
			(stroke
				(width 0)
				(type default)
			)
			(fill no)
			(layer "F.CrtYd")
		)
		(fp_rect
			(start -0.9652 1.778)
			(end 0.9652 -1.778)
			(stroke
				(width 0)
				(type default)
			)
			(fill no)
			(layer "F.Fab")
		)
		(pad "1" smd rect
			(at 0 -0.9652 90)
			(size 1.397 1.143)
			(layers "F.Cu" "F.Mask" "F.Paste")
			(net "MB3_12V_CTRL_GATE3")
		)
		(pad "2" smd rect
			(at 0 0.9652 90)
			(size 1.397 1.143)
			(layers "F.Cu" "F.Mask" "F.Paste")
			(net "MB3_CM_GATE_R")
		)
	)
	(footprint ""
		(layer "F.Cu")
		(at 370.205 -258.826 90)
		(property "Reference" "C130"
			(at 0 0 90)
			(layer "F.SilkS")
			(hide yes)
			(effects
				(font
					(size 1.27 1.27)
				)
			)
		)
		(property "Value" "SCD033U25V2KX-GP"
			(at 1.1811 -2.7051 90)
			(unlocked yes)
			(layer "F.Fab")
			(hide yes)
			(effects
				(font
					(size 1.016 1.016)
					(thickness 0.1524)
				)
			)
		)
		(property "Device Type" "C402H22"
			(at 1.1811 -4.2291 90)
			(unlocked yes)
			(layer "F.Fab")
			(hide yes)
			(effects
				(font
					(size 1.016 1.016)
					(thickness 0.1524)
				)
			)
		)
		(duplicate_pad_numbers_are_jumpers no)
		(fp_rect
			(start -0.4318 0.9525)
			(end 0.4318 -0.9525)
			(stroke
				(width 0)
				(type default)
			)
			(fill no)
			(layer "F.CrtYd")
		)
		(fp_rect
			(start -0.4318 0.9525)
			(end 0.4318 -0.9525)
			(stroke
				(width 0)
				(type default)
			)
			(fill no)
			(layer "F.Fab")
		)
		(pad "1" smd custom
			(at 0 -0.4445 90)
			(size 0.1524 0.1524)
			(layers "F.Cu" "F.Mask" "F.Paste")
			(net "P12V_B")
			(options
				(clearance outline)
				(anchor circle)
			)
			(primitives
				(gr_poly
					(pts
						(arc
							(start 0.3048 -0.2032)
							(mid 0.275042 -0.275042)
							(end 0.2032 -0.3048)
						)
						(arc
							(start -0.2032 -0.3048)
							(mid -0.275042 -0.275042)
							(end -0.3048 -0.2032)
						)
						(arc
							(start -0.3048 0.2032)
							(mid -0.275042 0.275042)
							(end -0.2032 0.3048)
						)
						(arc
							(start 0.2032 0.3048)
							(mid 0.275042 0.275042)
							(end 0.3048 0.2032)
						)
					)
					(width 0)
					(fill yes)
				)
			)
		)
		(pad "2" smd custom
			(at 0 0.4445 90)
			(size 0.1524 0.1524)
			(layers "F.Cu" "F.Mask" "F.Paste")
			(net "SW_HDD_N7")
			(options
				(clearance outline)
				(anchor circle)
			)
			(primitives
				(gr_poly
					(pts
						(arc
							(start 0.3048 -0.2032)
							(mid 0.275042 -0.275042)
							(end 0.2032 -0.3048)
						)
						(arc
							(start -0.2032 -0.3048)
							(mid -0.275042 -0.275042)
							(end -0.3048 -0.2032)
						)
						(arc
							(start -0.3048 0.2032)
							(mid -0.275042 0.275042)
							(end -0.2032 0.3048)
						)
						(arc
							(start 0.2032 0.3048)
							(mid 0.275042 0.275042)
							(end 0.3048 0.2032)
						)
					)
					(width 0)
					(fill yes)
				)
			)
		)
	)
	(footprint ""
		(layer "F.Cu")
		(at 464.82 -142.875 -90)
		(property "Reference" "R591"
			(at 0 0 270)
			(layer "F.SilkS")
			(hide yes)
			(effects
				(font
					(size 1.27 1.27)
				)
			)
		)
		(property "Value" "300KR2F-GP"
			(at 0.064008 -3.993896 270)
			(unlocked yes)
			(layer "F.Fab")
			(hide yes)
			(effects
				(font
					(size 1.016 1.016)
					(thickness 0.1524)
				)
			)
		)
		(property "Device Type" "R402H16"
			(at 0.064008 -5.517896 270)
			(unlocked yes)
			(layer "F.Fab")
			(hide yes)
			(effects
				(font
					(size 1.016 1.016)
					(thickness 0.1524)
				)
			)
		)
		(duplicate_pad_numbers_are_jumpers no)
		(fp_line
			(start -0.508 -0.9398)
			(end -0.508 0.9398)
			(stroke
				(width 0.1524)
				(type default)
			)
			(layer "F.SilkS")
		)
		(fp_line
			(start 0.508 -0.9398)
			(end -0.508 -0.9398)
			(stroke
				(width 0.1524)
				(type default)
			)
			(layer "F.SilkS")
		)
		(fp_rect
			(start -0.508 0.9398)
			(end 0.508 -0.9398)
			(stroke
				(width 0)
				(type default)
			)
			(fill no)
			(layer "F.CrtYd")
		)
		(fp_rect
			(start -0.508 0.9398)
			(end 0.508 -0.9398)
			(stroke
				(width 0)
				(type default)
			)
			(fill no)
			(layer "F.Fab")
		)
		(pad "1" smd custom
			(at 0 -0.4445 270)
			(size 0.1397 0.1397)
			(layers "F.Cu" "F.Mask" "F.Paste")
			(net "SW_HDD_N22")
			(options
				(clearance outline)
				(anchor circle)
			)
			(primitives
				(gr_poly
					(pts
						(arc
							(start -0.1778 -0.2794)
							(mid -0.249642 -0.249642)
							(end -0.2794 -0.1778)
						)
						(arc
							(start -0.2794 0.1778)
							(mid -0.249642 0.249642)
							(end -0.1778 0.2794)
						)
						(arc
							(start 0.1778 0.2794)
							(mid 0.249642 0.249642)
							(end 0.2794 0.1778)
						)
						(arc
							(start 0.2794 -0.1778)
							(mid 0.249642 -0.249642)
							(end 0.1778 -0.2794)
						)
					)
					(width 0)
					(fill yes)
				)
			)
		)
		(pad "2" smd custom
			(at 0 0.4445 270)
			(size 0.1397 0.1397)
			(layers "F.Cu" "F.Mask" "F.Paste")
			(net "P12V_B")
			(options
				(clearance outline)
				(anchor circle)
			)
			(primitives
				(gr_poly
					(pts
						(arc
							(start -0.1778 -0.2794)
							(mid -0.249642 -0.249642)
							(end -0.2794 -0.1778)
						)
						(arc
							(start -0.2794 0.1778)
							(mid -0.249642 0.249642)
							(end -0.1778 0.2794)
						)
						(arc
							(start 0.1778 0.2794)
							(mid 0.249642 0.249642)
							(end 0.2794 0.1778)
						)
						(arc
							(start 0.2794 -0.1778)
							(mid 0.249642 -0.249642)
							(end 0.1778 -0.2794)
						)
					)
					(width 0)
					(fill yes)
				)
			)
		)
	)
	(footprint ""
		(layer "F.Cu")
		(at 16.891 -17.653 180)
		(property "Reference" "D24"
			(at 0 0 180)
			(layer "F.SilkS")
			(hide yes)
			(effects
				(font
					(size 1.27 1.27)
				)
			)
		)
		(property "Value" "RB551V30-GP"
			(at 0 -6.7818 180)
			(unlocked yes)
			(layer "F.Fab")
			(hide yes)
			(effects
				(font
					(size 1.016 1.016)
					(thickness 0.1524)
				)
			)
		)
		(property "Device Type" "SOD323AKH38"
			(at 0 -8.6868 180)
			(unlocked yes)
			(layer "F.Fab")
			(hide yes)
			(effects
				(font
					(size 1.016 1.016)
					(thickness 0.1524)
				)
			)
		)
		(duplicate_pad_numbers_are_jumpers no)
		(fp_line
			(start 0.889 2.159)
			(end -0.889 2.159)
			(stroke
				(width 0.1524)
				(type default)
			)
			(layer "F.SilkS")
		)
		(fp_line
			(start 0.889 -1.9304)
			(end 0.889 2.159)
			(stroke
				(width 0.1524)
				(type default)
			)
			(layer "F.SilkS")
		)
		(fp_line
			(start 0.762 2.0574)
			(end -0.762 2.0574)
			(stroke
				(width 0.508)
				(type default)
			)
			(layer "F.SilkS")
		)
		(fp_line
			(start -0.889 2.159)
			(end -0.889 -1.9304)
			(stroke
				(width 0.1524)
				(type default)
			)
			(layer "F.SilkS")
		)
		(fp_line
			(start -0.889 -1.9304)
			(end 0.889 -1.9304)
			(stroke
				(width 0.1524)
				(type default)
			)
			(layer "F.SilkS")
		)
		(fp_rect
			(start -1.016 2.3114)
			(end 1.016 -2.0066)
			(stroke
				(width 0)
				(type default)
			)
			(fill no)
			(layer "F.CrtYd")
		)
		(fp_poly
			(pts
				(xy -1.016 -2.0066) (xy 1.016 -2.0066) (xy 1.016 2.3114) (xy -1.016 2.3114)
			)
			(stroke
				(width 0)
				(type default)
			)
			(fill no)
			(layer "F.Fab")
		)
		(pad "A" smd rect
			(at 0 -1.143 180)
			(size 0.5588 1.016)
			(layers "F.Cu" "F.Mask" "F.Paste")
			(net "SW_HDD_R24")
		)
		(pad "K" smd rect
			(at 0 1.143 180)
			(size 0.5588 1.016)
			(layers "F.Cu" "F.Mask" "F.Paste")
			(net "SW_HDD_N24")
		)
	)
	(footprint ""
		(layer "F.Cu")
		(at 18.669 -214.249)
		(property "Reference" "R204"
			(at 0 0 0)
			(layer "F.SilkS")
			(hide yes)
			(effects
				(font
					(size 1.27 1.27)
				)
			)
		)
		(property "Value" "91R3F-1-GP"
			(at -0.0254 -2.5146 0)
			(unlocked yes)
			(layer "F.Fab")
			(hide yes)
			(effects
				(font
					(size 1.016 1.016)
					(thickness 0.1524)
				)
			)
		)
		(property "Device Type" "R603H22"
			(at -0.0254 -4.0386 0)
			(unlocked yes)
			(layer "F.Fab")
			(hide yes)
			(effects
				(font
					(size 1.016 1.016)
					(thickness 0.1524)
				)
			)
		)
		(duplicate_pad_numbers_are_jumpers no)
		(fp_line
			(start -0.4826 0)
			(end -0.2032 0)
			(stroke
				(width 0.2032)
				(type default)
			)
			(layer "F.SilkS")
		)
		(fp_line
			(start 0.2032 0)
			(end 0.4826 0)
			(stroke
				(width 0.2032)
				(type default)
			)
			(layer "F.SilkS")
		)
		(fp_rect
			(start -0.5842 1.3335)
			(end 0.5842 -1.3335)
			(stroke
				(width 0)
				(type default)
			)
			(fill no)
			(layer "F.CrtYd")
		)
		(fp_rect
			(start -0.5842 1.3335)
			(end 0.5842 -1.3335)
			(stroke
				(width 0)
				(type default)
			)
			(fill no)
			(layer "F.Fab")
		)
		(pad "1" smd custom
			(at 0 -0.762)
			(size 0.2159 0.2159)
			(layers "F.Cu" "F.Mask" "F.Paste")
			(net "P5V_B_1")
			(options
				(clearance outline)
				(anchor circle)
			)
			(primitives
				(gr_poly
					(pts
						(arc
							(start -0.3302 -0.4318)
							(mid -0.402042 -0.402042)
							(end -0.4318 -0.3302)
						)
						(arc
							(start -0.4318 0.3302)
							(mid -0.402042 0.402042)
							(end -0.3302 0.4318)
						)
						(arc
							(start 0.3302 0.4318)
							(mid 0.402042 0.402042)
							(end 0.4318 0.3302)
						)
						(arc
							(start 0.4318 -0.3302)
							(mid 0.402042 -0.402042)
							(end 0.3302 -0.4318)
						)
					)
					(width 0)
					(fill yes)
				)
			)
		)
		(pad "2" smd custom
			(at 0 0.762)
			(size 0.2159 0.2159)
			(layers "F.Cu" "F.Mask" "F.Paste")
			(net "DRV_ACT_0")
			(options
				(clearance outline)
				(anchor circle)
			)
			(primitives
				(gr_poly
					(pts
						(arc
							(start -0.3302 -0.4318)
							(mid -0.402042 -0.402042)
							(end -0.4318 -0.3302)
						)
						(arc
							(start -0.4318 0.3302)
							(mid -0.402042 0.402042)
							(end -0.3302 0.4318)
						)
						(arc
							(start 0.3302 0.4318)
							(mid 0.402042 0.402042)
							(end 0.4318 0.3302)
						)
						(arc
							(start 0.4318 -0.3302)
							(mid 0.402042 -0.402042)
							(end 0.3302 -0.4318)
						)
					)
					(width 0)
					(fill yes)
				)
			)
		)
	)
	(footprint ""
		(layer "F.Cu")
		(at 401.193 -250.444 90)
		(property "Reference" "R298"
			(at 0 0 90)
			(layer "F.SilkS")
			(hide yes)
			(effects
				(font
					(size 1.27 1.27)
				)
			)
		)
		(property "Value" "200KR2F-L-GP"
			(at 0.064008 -3.993896 90)
			(unlocked yes)
			(layer "F.Fab")
			(hide yes)
			(effects
				(font
					(size 1.016 1.016)
					(thickness 0.1524)
				)
			)
		)
		(property "Device Type" "R402H16"
			(at 0.064008 -5.517896 90)
			(unlocked yes)
			(layer "F.Fab")
			(hide yes)
			(effects
				(font
					(size 1.016 1.016)
					(thickness 0.1524)
				)
			)
		)
		(duplicate_pad_numbers_are_jumpers no)
		(fp_line
			(start 0.508 -0.9398)
			(end -0.508 -0.9398)
			(stroke
				(width 0.1524)
				(type default)
			)
			(layer "F.SilkS")
		)
		(fp_line
			(start -0.508 -0.9398)
			(end -0.508 0.9398)
			(stroke
				(width 0.1524)
				(type default)
			)
			(layer "F.SilkS")
		)
		(fp_rect
			(start -0.508 0.9398)
			(end 0.508 -0.9398)
			(stroke
				(width 0)
				(type default)
			)
			(fill no)
			(layer "F.CrtYd")
		)
		(fp_rect
			(start -0.508 0.9398)
			(end 0.508 -0.9398)
			(stroke
				(width 0)
				(type default)
			)
			(fill no)
			(layer "F.Fab")
		)
		(pad "1" smd custom
			(at 0 -0.4445 90)
			(size 0.1397 0.1397)
			(layers "F.Cu" "F.Mask" "F.Paste")
			(net "SW_HDD_R8")
			(options
				(clearance outline)
				(anchor circle)
			)
			(primitives
				(gr_poly
					(pts
						(arc
							(start -0.1778 -0.2794)
							(mid -0.249642 -0.249642)
							(end -0.2794 -0.1778)
						)
						(arc
							(start -0.2794 0.1778)
							(mid -0.249642 0.249642)
							(end -0.1778 0.2794)
						)
						(arc
							(start 0.1778 0.2794)
							(mid 0.249642 0.249642)
							(end 0.2794 0.1778)
						)
						(arc
							(start 0.2794 -0.1778)
							(mid 0.249642 -0.249642)
							(end 0.1778 -0.2794)
						)
					)
					(width 0)
					(fill yes)
				)
			)
		)
		(pad "2" smd custom
			(at 0 0.4445 90)
			(size 0.1397 0.1397)
			(layers "F.Cu" "F.Mask" "F.Paste")
			(net "SW_HDD_N8")
			(options
				(clearance outline)
				(anchor circle)
			)
			(primitives
				(gr_poly
					(pts
						(arc
							(start -0.1778 -0.2794)
							(mid -0.249642 -0.249642)
							(end -0.2794 -0.1778)
						)
						(arc
							(start -0.2794 0.1778)
							(mid -0.249642 0.249642)
							(end -0.1778 0.2794)
						)
						(arc
							(start 0.1778 0.2794)
							(mid 0.249642 0.249642)
							(end 0.2794 0.1778)
						)
						(arc
							(start 0.2794 -0.1778)
							(mid 0.249642 -0.249642)
							(end 0.1778 -0.2794)
						)
					)
					(width 0)
					(fill yes)
				)
			)
		)
	)
	(footprint ""
		(layer "F.Cu")
		(at 464.82 -258.826 90)
		(property "Reference" "C169"
			(at 0 0 90)
			(layer "F.SilkS")
			(hide yes)
			(effects
				(font
					(size 1.27 1.27)
				)
			)
		)
		(property "Value" "SCD033U25V2KX-GP"
			(at 1.1811 -2.7051 90)
			(unlocked yes)
			(layer "F.Fab")
			(hide yes)
			(effects
				(font
					(size 1.016 1.016)
					(thickness 0.1524)
				)
			)
		)
		(property "Device Type" "C402H22"
			(at 1.1811 -4.2291 90)
			(unlocked yes)
			(layer "F.Fab")
			(hide yes)
			(effects
				(font
					(size 1.016 1.016)
					(thickness 0.1524)
				)
			)
		)
		(duplicate_pad_numbers_are_jumpers no)
		(fp_rect
			(start -0.4318 0.9525)
			(end 0.4318 -0.9525)
			(stroke
				(width 0)
				(type default)
			)
			(fill no)
			(layer "F.CrtYd")
		)
		(fp_rect
			(start -0.4318 0.9525)
			(end 0.4318 -0.9525)
			(stroke
				(width 0)
				(type default)
			)
			(fill no)
			(layer "F.Fab")
		)
		(pad "1" smd custom
			(at 0 -0.4445 90)
			(size 0.1524 0.1524)
			(layers "F.Cu" "F.Mask" "F.Paste")
			(net "P12V_B")
			(options
				(clearance outline)
				(anchor circle)
			)
			(primitives
				(gr_poly
					(pts
						(arc
							(start 0.3048 -0.2032)
							(mid 0.275042 -0.275042)
							(end 0.2032 -0.3048)
						)
						(arc
							(start -0.2032 -0.3048)
							(mid -0.275042 -0.275042)
							(end -0.3048 -0.2032)
						)
						(arc
							(start -0.3048 0.2032)
							(mid -0.275042 0.275042)
							(end -0.2032 0.3048)
						)
						(arc
							(start 0.2032 0.3048)
							(mid 0.275042 0.275042)
							(end 0.3048 0.2032)
						)
					)
					(width 0)
					(fill yes)
				)
			)
		)
		(pad "2" smd custom
			(at 0 0.4445 90)
			(size 0.1524 0.1524)
			(layers "F.Cu" "F.Mask" "F.Paste")
			(net "SW_HDD_N10")
			(options
				(clearance outline)
				(anchor circle)
			)
			(primitives
				(gr_poly
					(pts
						(arc
							(start 0.3048 -0.2032)
							(mid 0.275042 -0.275042)
							(end 0.2032 -0.3048)
						)
						(arc
							(start -0.2032 -0.3048)
							(mid -0.275042 -0.275042)
							(end -0.3048 -0.2032)
						)
						(arc
							(start -0.3048 0.2032)
							(mid -0.275042 0.275042)
							(end -0.2032 0.3048)
						)
						(arc
							(start 0.2032 0.3048)
							(mid 0.275042 0.275042)
							(end 0.3048 0.2032)
						)
					)
					(width 0)
					(fill yes)
				)
			)
		)
	)
	(footprint ""
		(layer "F.Cu")
		(at 263.1059 -379.174756 -90)
		(property "Reference" "R1068"
			(at 0 0 270)
			(layer "F.SilkS")
			(hide yes)
			(effects
				(font
					(size 1.27 1.27)
				)
			)
		)
		(property "Value" "1KR2J-1-GP"
			(at 0.064008 -3.993896 270)
			(unlocked yes)
			(layer "F.Fab")
			(hide yes)
			(effects
				(font
					(size 1.016 1.016)
					(thickness 0.1524)
				)
			)
		)
		(property "Device Type" "R402H16"
			(at 0.064008 -5.517896 270)
			(unlocked yes)
			(layer "F.Fab")
			(hide yes)
			(effects
				(font
					(size 1.016 1.016)
					(thickness 0.1524)
				)
			)
		)
		(duplicate_pad_numbers_are_jumpers no)
		(fp_line
			(start -0.508 -0.9398)
			(end -0.508 0.9398)
			(stroke
				(width 0.1524)
				(type default)
			)
			(layer "F.SilkS")
		)
		(fp_line
			(start 0.508 -0.9398)
			(end -0.508 -0.9398)
			(stroke
				(width 0.1524)
				(type default)
			)
			(layer "F.SilkS")
		)
		(fp_rect
			(start -0.508 0.9398)
			(end 0.508 -0.9398)
			(stroke
				(width 0)
				(type default)
			)
			(fill no)
			(layer "F.CrtYd")
		)
		(fp_rect
			(start -0.508 0.9398)
			(end 0.508 -0.9398)
			(stroke
				(width 0)
				(type default)
			)
			(fill no)
			(layer "F.Fab")
		)
		(pad "1" smd custom
			(at 0 -0.4445 270)
			(size 0.1397 0.1397)
			(layers "F.Cu" "F.Mask" "F.Paste")
			(net "DRAWER_OUT_NET")
			(options
				(clearance outline)
				(anchor circle)
			)
			(primitives
				(gr_poly
					(pts
						(arc
							(start -0.1778 -0.2794)
							(mid -0.249642 -0.249642)
							(end -0.2794 -0.1778)
						)
						(arc
							(start -0.2794 0.1778)
							(mid -0.249642 0.249642)
							(end -0.1778 0.2794)
						)
						(arc
							(start 0.1778 0.2794)
							(mid 0.249642 0.249642)
							(end 0.2794 0.1778)
						)
						(arc
							(start 0.2794 -0.1778)
							(mid 0.249642 -0.249642)
							(end 0.1778 -0.2794)
						)
					)
					(width 0)
					(fill yes)
				)
			)
		)
		(pad "2" smd custom
			(at 0 0.4445 270)
			(size 0.1397 0.1397)
			(layers "F.Cu" "F.Mask" "F.Paste")
			(net "DRAWER_OUT_NET_B")
			(options
				(clearance outline)
				(anchor circle)
			)
			(primitives
				(gr_poly
					(pts
						(arc
							(start -0.1778 -0.2794)
							(mid -0.249642 -0.249642)
							(end -0.2794 -0.1778)
						)
						(arc
							(start -0.2794 0.1778)
							(mid -0.249642 0.249642)
							(end -0.1778 0.2794)
						)
						(arc
							(start 0.1778 0.2794)
							(mid 0.249642 0.249642)
							(end 0.2794 0.1778)
						)
						(arc
							(start 0.2794 -0.1778)
							(mid 0.249642 -0.249642)
							(end 0.1778 -0.2794)
						)
					)
					(width 0)
					(fill yes)
				)
			)
		)
	)
	(footprint ""
		(layer "F.Cu")
		(at 14.859 -260.858)
		(property "Reference" "Q192"
			(at 0 0 0)
			(layer "F.SilkS")
			(hide yes)
			(effects
				(font
					(size 1.27 1.27)
				)
			)
		)
		(property "Value" "AO4407AL-GP"
			(at -3.707384 -1.5367 0)
			(unlocked yes)
			(layer "F.Fab")
			(hide yes)
			(effects
				(font
					(size 1.016 1.016)
					(thickness 0.1524)
				)
			)
		)
		(property "Device Type" "SOIC8H69"
			(at -3.707384 -3.0607 0)
			(unlocked yes)
			(layer "F.Fab")
			(hide yes)
			(effects
				(font
					(size 1.016 1.016)
					(thickness 0.1524)
				)
			)
		)
		(duplicate_pad_numbers_are_jumpers no)
		(fp_line
			(start -2.7432 -1.4224)
			(end -2.7432 1.4224)
			(stroke
				(width 0.1524)
				(type default)
			)
			(layer "F.SilkS")
		)
		(fp_line
			(start -2.7432 1.4224)
			(end -2.6416 1.4224)
			(stroke
				(width 0.1524)
				(type default)
			)
			(layer "F.SilkS")
		)
		(fp_line
			(start -2.7432 1.4224)
			(end 2.1336 1.4224)
			(stroke
				(width 0.1524)
				(type default)
			)
			(layer "F.SilkS")
		)
		(fp_line
			(start -2.7178 -0.508)
			(end -2.1844 -0.0508)
			(stroke
				(width 0.1524)
				(type default)
			)
			(layer "F.SilkS")
		)
		(fp_line
			(start -2.6289 3.4417)
			(end -2.6289 1.4732)
			(stroke
				(width 0.381)
				(type default)
			)
			(layer "F.SilkS")
		)
		(fp_line
			(start -2.1844 -0.0508)
			(end -2.7178 0.508)
			(stroke
				(width 0.1524)
				(type default)
			)
			(layer "F.SilkS")
		)
		(fp_line
			(start 2.1336 -1.4224)
			(end -2.7432 -1.4224)
			(stroke
				(width 0.1524)
				(type default)
			)
			(layer "F.SilkS")
		)
		(fp_line
			(start 2.1336 1.4224)
			(end 2.1336 -1.4224)
			(stroke
				(width 0.1524)
				(type default)
			)
			(layer "F.SilkS")
		)
		(fp_poly
			(pts
				(xy -2.2098 -1.4224) (xy -2.2098 1.4224) (xy 2.2098 1.4224) (xy 2.2098 -1.4224)
			)
			(stroke
				(width 0)
				(type default)
			)
			(fill yes)
			(layer "F.SilkS")
		)
		(fp_rect
			(start -2.450084 2.999994)
			(end 2.450084 -2.999994)
			(stroke
				(width 0)
				(type default)
			)
			(fill no)
			(layer "F.CrtYd")
		)
		(fp_poly
			(pts
				(xy -2.8194 3.6322) (xy -2.8194 -3.6322) (xy 2.8194 -3.6322) (xy 2.8194 1.18364) (xy 2.450084 1.18364)
				(xy 2.450084 -2.999994) (xy -2.450084 -2.999994) (xy -2.450084 2.999994) (xy 2.450084 2.999994)
				(xy 2.450084 1.18618) (xy 2.8194 1.18618) (xy 2.8194 3.6322)
			)
			(stroke
				(width 0)
				(type default)
			)
			(fill no)
			(layer "F.CrtYd")
		)
		(fp_rect
			(start -2.8194 3.6322)
			(end 2.8194 -3.6322)
			(stroke
				(width 0)
				(type default)
			)
			(fill no)
			(layer "F.Fab")
		)
		(pad "1" smd rect
			(at -1.905 2.54)
			(size 0.635 1.651)
			(layers "F.Cu" "F.Mask" "F.Paste")
			(net "P12V_B")
		)
		(pad "2" smd rect
			(at -0.635 2.54)
			(size 0.635 1.651)
			(layers "F.Cu" "F.Mask" "F.Paste")
			(net "P12V_B")
		)
		(pad "3" smd rect
			(at 0.635 2.54)
			(size 0.635 1.651)
			(layers "F.Cu" "F.Mask" "F.Paste")
			(net "P12V_B")
		)
		(pad "4" smd rect
			(at 1.905 2.54)
			(size 0.635 1.651)
			(layers "F.Cu" "F.Mask" "F.Paste")
			(net "SW_HDD_N0")
		)
		(pad "5" smd rect
			(at 1.905 -2.54)
			(size 0.635 1.651)
			(layers "F.Cu" "F.Mask" "F.Paste")
			(net "P12V_HDD0")
		)
		(pad "6" smd rect
			(at 0.635 -2.54)
			(size 0.635 1.651)
			(layers "F.Cu" "F.Mask" "F.Paste")
			(net "P12V_HDD0")
		)
		(pad "7" smd rect
			(at -0.635 -2.54)
			(size 0.635 1.651)
			(layers "F.Cu" "F.Mask" "F.Paste")
			(net "P12V_HDD0")
		)
		(pad "8" smd rect
			(at -1.905 -2.54)
			(size 0.635 1.651)
			(layers "F.Cu" "F.Mask" "F.Paste")
			(net "P12V_HDD0")
		)
	)
	(footprint ""
		(layer "F.Cu")
		(at 286.639 -328.0918 -90)
		(property "Reference" "R93"
			(at 0 0 270)
			(layer "F.SilkS")
			(hide yes)
			(effects
				(font
					(size 1.27 1.27)
				)
			)
		)
		(property "Value" "4K7R2F-GP"
			(at 0.064008 -3.993896 270)
			(unlocked yes)
			(layer "F.Fab")
			(hide yes)
			(effects
				(font
					(size 1.016 1.016)
					(thickness 0.1524)
				)
			)
		)
		(property "Device Type" "R402H16"
			(at 0.064008 -5.517896 270)
			(unlocked yes)
			(layer "F.Fab")
			(hide yes)
			(effects
				(font
					(size 1.016 1.016)
					(thickness 0.1524)
				)
			)
		)
		(duplicate_pad_numbers_are_jumpers no)
		(fp_line
			(start -0.508 -0.9398)
			(end -0.508 0.9398)
			(stroke
				(width 0.1524)
				(type default)
			)
			(layer "F.SilkS")
		)
		(fp_line
			(start 0.508 -0.9398)
			(end -0.508 -0.9398)
			(stroke
				(width 0.1524)
				(type default)
			)
			(layer "F.SilkS")
		)
		(fp_rect
			(start -0.508 0.9398)
			(end 0.508 -0.9398)
			(stroke
				(width 0)
				(type default)
			)
			(fill no)
			(layer "F.CrtYd")
		)
		(fp_rect
			(start -0.508 0.9398)
			(end 0.508 -0.9398)
			(stroke
				(width 0)
				(type default)
			)
			(fill no)
			(layer "F.Fab")
		)
		(pad "1" smd custom
			(at 0 -0.4445 270)
			(size 0.1397 0.1397)
			(layers "F.Cu" "F.Mask" "F.Paste")
			(net "P3V3_IN")
			(options
				(clearance outline)
				(anchor circle)
			)
			(primitives
				(gr_poly
					(pts
						(arc
							(start -0.1778 -0.2794)
							(mid -0.249642 -0.249642)
							(end -0.2794 -0.1778)
						)
						(arc
							(start -0.2794 0.1778)
							(mid -0.249642 0.249642)
							(end -0.1778 0.2794)
						)
						(arc
							(start 0.1778 0.2794)
							(mid 0.249642 0.249642)
							(end 0.2794 0.1778)
						)
						(arc
							(start 0.2794 -0.1778)
							(mid 0.249642 -0.249642)
							(end 0.1778 -0.2794)
						)
					)
					(width 0)
					(fill yes)
				)
			)
		)
		(pad "2" smd custom
			(at 0 0.4445 270)
			(size 0.1397 0.1397)
			(layers "F.Cu" "F.Mask" "F.Paste")
			(net "PWM_OUT_FAN3")
			(options
				(clearance outline)
				(anchor circle)
			)
			(primitives
				(gr_poly
					(pts
						(arc
							(start -0.1778 -0.2794)
							(mid -0.249642 -0.249642)
							(end -0.2794 -0.1778)
						)
						(arc
							(start -0.2794 0.1778)
							(mid -0.249642 0.249642)
							(end -0.1778 0.2794)
						)
						(arc
							(start 0.1778 0.2794)
							(mid 0.249642 0.249642)
							(end 0.2794 0.1778)
						)
						(arc
							(start 0.2794 -0.1778)
							(mid 0.249642 -0.249642)
							(end 0.1778 -0.2794)
						)
					)
					(width 0)
					(fill yes)
				)
			)
		)
	)
	(footprint ""
		(layer "F.Cu")
		(at 79.883 -254.127 -90)
		(property "Reference" "C64"
			(at 0 0 270)
			(layer "F.SilkS")
			(hide yes)
			(effects
				(font
					(size 1.27 1.27)
				)
			)
		)
		(property "Value" "SCD033U25V2KX-GP"
			(at 1.1811 -2.7051 270)
			(unlocked yes)
			(layer "F.Fab")
			(hide yes)
			(effects
				(font
					(size 1.016 1.016)
					(thickness 0.1524)
				)
			)
		)
		(property "Device Type" "C402H22"
			(at 1.1811 -4.2291 270)
			(unlocked yes)
			(layer "F.Fab")
			(hide yes)
			(effects
				(font
					(size 1.016 1.016)
					(thickness 0.1524)
				)
			)
		)
		(duplicate_pad_numbers_are_jumpers no)
		(fp_rect
			(start -0.4318 0.9525)
			(end 0.4318 -0.9525)
			(stroke
				(width 0)
				(type default)
			)
			(fill no)
			(layer "F.CrtYd")
		)
		(fp_rect
			(start -0.4318 0.9525)
			(end 0.4318 -0.9525)
			(stroke
				(width 0)
				(type default)
			)
			(fill no)
			(layer "F.Fab")
		)
		(pad "1" smd custom
			(at 0 -0.4445 270)
			(size 0.1524 0.1524)
			(layers "F.Cu" "F.Mask" "F.Paste")
			(net "SW_HDD_P2")
			(options
				(clearance outline)
				(anchor circle)
			)
			(primitives
				(gr_poly
					(pts
						(arc
							(start 0.3048 -0.2032)
							(mid 0.275042 -0.275042)
							(end 0.2032 -0.3048)
						)
						(arc
							(start -0.2032 -0.3048)
							(mid -0.275042 -0.275042)
							(end -0.3048 -0.2032)
						)
						(arc
							(start -0.3048 0.2032)
							(mid -0.275042 0.275042)
							(end -0.2032 0.3048)
						)
						(arc
							(start 0.2032 0.3048)
							(mid 0.275042 0.275042)
							(end 0.3048 0.2032)
						)
					)
					(width 0)
					(fill yes)
				)
			)
		)
		(pad "2" smd custom
			(at 0 0.4445 270)
			(size 0.1524 0.1524)
			(layers "F.Cu" "F.Mask" "F.Paste")
			(net "GND")
			(options
				(clearance outline)
				(anchor circle)
			)
			(primitives
				(gr_poly
					(pts
						(arc
							(start 0.3048 -0.2032)
							(mid 0.275042 -0.275042)
							(end 0.2032 -0.3048)
						)
						(arc
							(start -0.2032 -0.3048)
							(mid -0.275042 -0.275042)
							(end -0.3048 -0.2032)
						)
						(arc
							(start -0.3048 0.2032)
							(mid -0.275042 0.275042)
							(end -0.2032 0.3048)
						)
						(arc
							(start 0.2032 0.3048)
							(mid 0.275042 0.275042)
							(end 0.3048 0.2032)
						)
					)
					(width 0)
					(fill yes)
				)
			)
		)
	)
	(footprint ""
		(layer "F.Cu")
		(at 327.373996 -365.379 -90)
		(property "Reference" "R950"
			(at 0 0 270)
			(layer "F.SilkS")
			(hide yes)
			(effects
				(font
					(size 1.27 1.27)
				)
			)
		)
		(property "Value" "27KR3F-GP"
			(at -0.0254 -2.5146 270)
			(unlocked yes)
			(layer "F.Fab")
			(hide yes)
			(effects
				(font
					(size 1.016 1.016)
					(thickness 0.1524)
				)
			)
		)
		(property "Device Type" "R603H22"
			(at -0.0254 -4.0386 270)
			(unlocked yes)
			(layer "F.Fab")
			(hide yes)
			(effects
				(font
					(size 1.016 1.016)
					(thickness 0.1524)
				)
			)
		)
		(duplicate_pad_numbers_are_jumpers no)
		(fp_line
			(start -0.4826 0)
			(end -0.2032 0)
			(stroke
				(width 0.2032)
				(type default)
			)
			(layer "F.SilkS")
		)
		(fp_line
			(start 0.2032 0)
			(end 0.4826 0)
			(stroke
				(width 0.2032)
				(type default)
			)
			(layer "F.SilkS")
		)
		(fp_rect
			(start -0.5842 1.3335)
			(end 0.5842 -1.3335)
			(stroke
				(width 0)
				(type default)
			)
			(fill no)
			(layer "F.CrtYd")
		)
		(fp_rect
			(start -0.5842 1.3335)
			(end 0.5842 -1.3335)
			(stroke
				(width 0)
				(type default)
			)
			(fill no)
			(layer "F.Fab")
		)
		(pad "1" smd custom
			(at 0 -0.762 270)
			(size 0.2159 0.2159)
			(layers "F.Cu" "F.Mask" "F.Paste")
			(net "FAN_2_TACH1")
			(options
				(clearance outline)
				(anchor circle)
			)
			(primitives
				(gr_poly
					(pts
						(arc
							(start -0.3302 -0.4318)
							(mid -0.402042 -0.402042)
							(end -0.4318 -0.3302)
						)
						(arc
							(start -0.4318 0.3302)
							(mid -0.402042 0.402042)
							(end -0.3302 0.4318)
						)
						(arc
							(start 0.3302 0.4318)
							(mid 0.402042 0.402042)
							(end 0.4318 0.3302)
						)
						(arc
							(start 0.4318 -0.3302)
							(mid 0.402042 -0.402042)
							(end 0.3302 -0.4318)
						)
					)
					(width 0)
					(fill yes)
				)
			)
		)
		(pad "2" smd custom
			(at 0 0.762 270)
			(size 0.2159 0.2159)
			(layers "F.Cu" "F.Mask" "F.Paste")
			(net "FANTACH_F2")
			(options
				(clearance outline)
				(anchor circle)
			)
			(primitives
				(gr_poly
					(pts
						(arc
							(start -0.3302 -0.4318)
							(mid -0.402042 -0.402042)
							(end -0.4318 -0.3302)
						)
						(arc
							(start -0.4318 0.3302)
							(mid -0.402042 0.402042)
							(end -0.3302 0.4318)
						)
						(arc
							(start 0.3302 0.4318)
							(mid 0.402042 0.402042)
							(end 0.4318 0.3302)
						)
						(arc
							(start 0.4318 -0.3302)
							(mid 0.402042 -0.402042)
							(end 0.3302 -0.4318)
						)
					)
					(width 0)
					(fill yes)
				)
			)
		)
	)
	(footprint ""
		(layer "F.Cu")
		(at 269.269972 -351.304606)
		(property "Reference" "R1055"
			(at 0 0 0)
			(layer "F.SilkS")
			(hide yes)
			(effects
				(font
					(size 1.27 1.27)
				)
			)
		)
		(property "Value" "1KR2J-1-GP"
			(at 0.064008 -3.993896 0)
			(unlocked yes)
			(layer "F.Fab")
			(hide yes)
			(effects
				(font
					(size 1.016 1.016)
					(thickness 0.1524)
				)
			)
		)
		(property "Device Type" "R402H16"
			(at 0.064008 -5.517896 0)
			(unlocked yes)
			(layer "F.Fab")
			(hide yes)
			(effects
				(font
					(size 1.016 1.016)
					(thickness 0.1524)
				)
			)
		)
		(duplicate_pad_numbers_are_jumpers no)
		(fp_line
			(start -0.508 -0.9398)
			(end -0.508 0.9398)
			(stroke
				(width 0.1524)
				(type default)
			)
			(layer "F.SilkS")
		)
		(fp_line
			(start 0.508 -0.9398)
			(end -0.508 -0.9398)
			(stroke
				(width 0.1524)
				(type default)
			)
			(layer "F.SilkS")
		)
		(fp_rect
			(start -0.508 0.9398)
			(end 0.508 -0.9398)
			(stroke
				(width 0)
				(type default)
			)
			(fill no)
			(layer "F.CrtYd")
		)
		(fp_rect
			(start -0.508 0.9398)
			(end 0.508 -0.9398)
			(stroke
				(width 0)
				(type default)
			)
			(fill no)
			(layer "F.Fab")
		)
		(pad "1" smd custom
			(at 0 -0.4445)
			(size 0.1397 0.1397)
			(layers "F.Cu" "F.Mask" "F.Paste")
			(net "MB3_CM_VOUT_R")
			(options
				(clearance outline)
				(anchor circle)
			)
			(primitives
				(gr_poly
					(pts
						(arc
							(start -0.1778 -0.2794)
							(mid -0.249642 -0.249642)
							(end -0.2794 -0.1778)
						)
						(arc
							(start -0.2794 0.1778)
							(mid -0.249642 0.249642)
							(end -0.1778 0.2794)
						)
						(arc
							(start 0.1778 0.2794)
							(mid 0.249642 0.249642)
							(end 0.2794 0.1778)
						)
						(arc
							(start 0.2794 -0.1778)
							(mid 0.249642 -0.249642)
							(end 0.1778 -0.2794)
						)
					)
					(width 0)
					(fill yes)
				)
			)
		)
		(pad "2" smd custom
			(at 0 0.4445)
			(size 0.1397 0.1397)
			(layers "F.Cu" "F.Mask" "F.Paste")
			(net "P12V_B")
			(options
				(clearance outline)
				(anchor circle)
			)
			(primitives
				(gr_poly
					(pts
						(arc
							(start -0.1778 -0.2794)
							(mid -0.249642 -0.249642)
							(end -0.2794 -0.1778)
						)
						(arc
							(start -0.2794 0.1778)
							(mid -0.249642 0.249642)
							(end -0.1778 0.2794)
						)
						(arc
							(start 0.1778 0.2794)
							(mid 0.249642 0.249642)
							(end 0.2794 0.1778)
						)
						(arc
							(start 0.2794 -0.1778)
							(mid 0.249642 -0.249642)
							(end 0.1778 -0.2794)
						)
					)
					(width 0)
					(fill yes)
				)
			)
		)
	)
	(footprint ""
		(layer "F.Cu")
		(at 77.978 -260.858)
		(property "Reference" "Q8"
			(at 0 0 0)
			(layer "F.SilkS")
			(hide yes)
			(effects
				(font
					(size 1.27 1.27)
				)
			)
		)
		(property "Value" "AO4407AL-GP"
			(at -3.707384 -1.5367 0)
			(unlocked yes)
			(layer "F.Fab")
			(hide yes)
			(effects
				(font
					(size 1.016 1.016)
					(thickness 0.1524)
				)
			)
		)
		(property "Device Type" "SOIC8H69"
			(at -3.707384 -3.0607 0)
			(unlocked yes)
			(layer "F.Fab")
			(hide yes)
			(effects
				(font
					(size 1.016 1.016)
					(thickness 0.1524)
				)
			)
		)
		(duplicate_pad_numbers_are_jumpers no)
		(fp_line
			(start -2.7432 -1.4224)
			(end -2.7432 1.4224)
			(stroke
				(width 0.1524)
				(type default)
			)
			(layer "F.SilkS")
		)
		(fp_line
			(start -2.7432 1.4224)
			(end -2.6416 1.4224)
			(stroke
				(width 0.1524)
				(type default)
			)
			(layer "F.SilkS")
		)
		(fp_line
			(start -2.7432 1.4224)
			(end 2.1336 1.4224)
			(stroke
				(width 0.1524)
				(type default)
			)
			(layer "F.SilkS")
		)
		(fp_line
			(start -2.7178 -0.508)
			(end -2.1844 -0.0508)
			(stroke
				(width 0.1524)
				(type default)
			)
			(layer "F.SilkS")
		)
		(fp_line
			(start -2.6289 3.4417)
			(end -2.6289 1.4732)
			(stroke
				(width 0.381)
				(type default)
			)
			(layer "F.SilkS")
		)
		(fp_line
			(start -2.1844 -0.0508)
			(end -2.7178 0.508)
			(stroke
				(width 0.1524)
				(type default)
			)
			(layer "F.SilkS")
		)
		(fp_line
			(start 2.1336 -1.4224)
			(end -2.7432 -1.4224)
			(stroke
				(width 0.1524)
				(type default)
			)
			(layer "F.SilkS")
		)
		(fp_line
			(start 2.1336 1.4224)
			(end 2.1336 -1.4224)
			(stroke
				(width 0.1524)
				(type default)
			)
			(layer "F.SilkS")
		)
		(fp_poly
			(pts
				(xy -2.2098 -1.4224) (xy -2.2098 1.4224) (xy 2.2098 1.4224) (xy 2.2098 -1.4224)
			)
			(stroke
				(width 0)
				(type default)
			)
			(fill yes)
			(layer "F.SilkS")
		)
		(fp_rect
			(start -2.450084 2.999994)
			(end 2.450084 -2.999994)
			(stroke
				(width 0)
				(type default)
			)
			(fill no)
			(layer "F.CrtYd")
		)
		(fp_poly
			(pts
				(xy -2.8194 3.6322) (xy -2.8194 -3.6322) (xy 2.8194 -3.6322) (xy 2.8194 1.18364) (xy 2.450084 1.18364)
				(xy 2.450084 -2.999994) (xy -2.450084 -2.999994) (xy -2.450084 2.999994) (xy 2.450084 2.999994)
				(xy 2.450084 1.18618) (xy 2.8194 1.18618) (xy 2.8194 3.6322)
			)
			(stroke
				(width 0)
				(type default)
			)
			(fill no)
			(layer "F.CrtYd")
		)
		(fp_rect
			(start -2.8194 3.6322)
			(end 2.8194 -3.6322)
			(stroke
				(width 0)
				(type default)
			)
			(fill no)
			(layer "F.Fab")
		)
		(pad "1" smd rect
			(at -1.905 2.54)
			(size 0.635 1.651)
			(layers "F.Cu" "F.Mask" "F.Paste")
			(net "P12V_B")
		)
		(pad "2" smd rect
			(at -0.635 2.54)
			(size 0.635 1.651)
			(layers "F.Cu" "F.Mask" "F.Paste")
			(net "P12V_B")
		)
		(pad "3" smd rect
			(at 0.635 2.54)
			(size 0.635 1.651)
			(layers "F.Cu" "F.Mask" "F.Paste")
			(net "P12V_B")
		)
		(pad "4" smd rect
			(at 1.905 2.54)
			(size 0.635 1.651)
			(layers "F.Cu" "F.Mask" "F.Paste")
			(net "SW_HDD_N2")
		)
		(pad "5" smd rect
			(at 1.905 -2.54)
			(size 0.635 1.651)
			(layers "F.Cu" "F.Mask" "F.Paste")
			(net "P12V_HDD2")
		)
		(pad "6" smd rect
			(at 0.635 -2.54)
			(size 0.635 1.651)
			(layers "F.Cu" "F.Mask" "F.Paste")
			(net "P12V_HDD2")
		)
		(pad "7" smd rect
			(at -0.635 -2.54)
			(size 0.635 1.651)
			(layers "F.Cu" "F.Mask" "F.Paste")
			(net "P12V_HDD2")
		)
		(pad "8" smd rect
			(at -1.905 -2.54)
			(size 0.635 1.651)
			(layers "F.Cu" "F.Mask" "F.Paste")
			(net "P12V_HDD2")
		)
	)
	(footprint ""
		(layer "F.Cu")
		(at 394.716 -249.5804 90)
		(property "Reference" "R291"
			(at 0 0 90)
			(layer "F.SilkS")
			(hide yes)
			(effects
				(font
					(size 1.27 1.27)
				)
			)
		)
		(property "Value" "4K7R2J-2-GP"
			(at 0.064008 -3.993896 90)
			(unlocked yes)
			(layer "F.Fab")
			(hide yes)
			(effects
				(font
					(size 1.016 1.016)
					(thickness 0.1524)
				)
			)
		)
		(property "Device Type" "R402H16"
			(at 0.064008 -5.517896 90)
			(unlocked yes)
			(layer "F.Fab")
			(hide yes)
			(effects
				(font
					(size 1.016 1.016)
					(thickness 0.1524)
				)
			)
		)
		(duplicate_pad_numbers_are_jumpers no)
		(fp_line
			(start 0.508 -0.9398)
			(end -0.508 -0.9398)
			(stroke
				(width 0.1524)
				(type default)
			)
			(layer "F.SilkS")
		)
		(fp_line
			(start -0.508 -0.9398)
			(end -0.508 0.9398)
			(stroke
				(width 0.1524)
				(type default)
			)
			(layer "F.SilkS")
		)
		(fp_rect
			(start -0.508 0.9398)
			(end 0.508 -0.9398)
			(stroke
				(width 0)
				(type default)
			)
			(fill no)
			(layer "F.CrtYd")
		)
		(fp_rect
			(start -0.508 0.9398)
			(end 0.508 -0.9398)
			(stroke
				(width 0)
				(type default)
			)
			(fill no)
			(layer "F.Fab")
		)
		(pad "1" smd custom
			(at 0 -0.4445 90)
			(size 0.1397 0.1397)
			(layers "F.Cu" "F.Mask" "F.Paste")
			(net "P12V_B")
			(options
				(clearance outline)
				(anchor circle)
			)
			(primitives
				(gr_poly
					(pts
						(arc
							(start -0.1778 -0.2794)
							(mid -0.249642 -0.249642)
							(end -0.2794 -0.1778)
						)
						(arc
							(start -0.2794 0.1778)
							(mid -0.249642 0.249642)
							(end -0.1778 0.2794)
						)
						(arc
							(start 0.1778 0.2794)
							(mid 0.249642 0.249642)
							(end 0.2794 0.1778)
						)
						(arc
							(start 0.2794 -0.1778)
							(mid 0.249642 -0.249642)
							(end 0.1778 -0.2794)
						)
					)
					(width 0)
					(fill yes)
				)
			)
		)
		(pad "2" smd custom
			(at 0 0.4445 90)
			(size 0.1397 0.1397)
			(layers "F.Cu" "F.Mask" "F.Paste")
			(net "SW_HDD_P8")
			(options
				(clearance outline)
				(anchor circle)
			)
			(primitives
				(gr_poly
					(pts
						(arc
							(start -0.1778 -0.2794)
							(mid -0.249642 -0.249642)
							(end -0.2794 -0.1778)
						)
						(arc
							(start -0.2794 0.1778)
							(mid -0.249642 0.249642)
							(end -0.1778 0.2794)
						)
						(arc
							(start 0.1778 0.2794)
							(mid 0.249642 0.249642)
							(end 0.2794 0.1778)
						)
						(arc
							(start 0.2794 -0.1778)
							(mid 0.249642 -0.249642)
							(end 0.1778 -0.2794)
						)
					)
					(width 0)
					(fill yes)
				)
			)
		)
	)
	(footprint ""
		(layer "F.Cu")
		(at 473.8878 -9.6774 -90)
		(property "Reference" "R890"
			(at 0 0 270)
			(layer "F.SilkS")
			(hide yes)
			(effects
				(font
					(size 1.27 1.27)
				)
			)
		)
		(property "Value" "300KR2F-GP"
			(at 0.064008 -3.993896 270)
			(unlocked yes)
			(layer "F.Fab")
			(hide yes)
			(effects
				(font
					(size 1.016 1.016)
					(thickness 0.1524)
				)
			)
		)
		(property "Device Type" "R402H16"
			(at 0.064008 -5.517896 270)
			(unlocked yes)
			(layer "F.Fab")
			(hide yes)
			(effects
				(font
					(size 1.016 1.016)
					(thickness 0.1524)
				)
			)
		)
		(duplicate_pad_numbers_are_jumpers no)
		(fp_line
			(start -0.508 -0.9398)
			(end -0.508 0.9398)
			(stroke
				(width 0.1524)
				(type default)
			)
			(layer "F.SilkS")
		)
		(fp_line
			(start 0.508 -0.9398)
			(end -0.508 -0.9398)
			(stroke
				(width 0.1524)
				(type default)
			)
			(layer "F.SilkS")
		)
		(fp_rect
			(start -0.508 0.9398)
			(end 0.508 -0.9398)
			(stroke
				(width 0)
				(type default)
			)
			(fill no)
			(layer "F.CrtYd")
		)
		(fp_rect
			(start -0.508 0.9398)
			(end 0.508 -0.9398)
			(stroke
				(width 0)
				(type default)
			)
			(fill no)
			(layer "F.Fab")
		)
		(pad "1" smd custom
			(at 0 -0.4445 270)
			(size 0.1397 0.1397)
			(layers "F.Cu" "F.Mask" "F.Paste")
			(net "SW_HDD_N35")
			(options
				(clearance outline)
				(anchor circle)
			)
			(primitives
				(gr_poly
					(pts
						(arc
							(start -0.1778 -0.2794)
							(mid -0.249642 -0.249642)
							(end -0.2794 -0.1778)
						)
						(arc
							(start -0.2794 0.1778)
							(mid -0.249642 0.249642)
							(end -0.1778 0.2794)
						)
						(arc
							(start 0.1778 0.2794)
							(mid 0.249642 0.249642)
							(end 0.2794 0.1778)
						)
						(arc
							(start 0.2794 -0.1778)
							(mid 0.249642 -0.249642)
							(end 0.1778 -0.2794)
						)
					)
					(width 0)
					(fill yes)
				)
			)
		)
		(pad "2" smd custom
			(at 0 0.4445 270)
			(size 0.1397 0.1397)
			(layers "F.Cu" "F.Mask" "F.Paste")
			(net "P12V_B")
			(options
				(clearance outline)
				(anchor circle)
			)
			(primitives
				(gr_poly
					(pts
						(arc
							(start -0.1778 -0.2794)
							(mid -0.249642 -0.249642)
							(end -0.2794 -0.1778)
						)
						(arc
							(start -0.2794 0.1778)
							(mid -0.249642 0.249642)
							(end -0.1778 0.2794)
						)
						(arc
							(start 0.1778 0.2794)
							(mid 0.249642 0.249642)
							(end 0.2794 0.1778)
						)
						(arc
							(start 0.2794 -0.1778)
							(mid 0.249642 -0.249642)
							(end 0.1778 -0.2794)
						)
					)
					(width 0)
					(fill yes)
				)
			)
		)
	)
	(footprint ""
		(layer "F.Cu")
		(at 243.519452 -359.617772 180)
		(property "Reference" "C564"
			(at 0 0 180)
			(layer "F.SilkS")
			(hide yes)
			(effects
				(font
					(size 1.27 1.27)
				)
			)
		)
		(property "Value" "SC1U16V3KX-5GP"
			(at 0 -2.8194 180)
			(unlocked yes)
			(layer "F.Fab")
			(hide yes)
			(effects
				(font
					(size 1.016 1.016)
					(thickness 0.1524)
				)
			)
		)
		(property "Device Type" "C603H36"
			(at 0 -4.3434 180)
			(unlocked yes)
			(layer "F.Fab")
			(hide yes)
			(effects
				(font
					(size 1.016 1.016)
					(thickness 0.1524)
				)
			)
		)
		(duplicate_pad_numbers_are_jumpers no)
		(fp_line
			(start 0.508 0)
			(end -0.508 0)
			(stroke
				(width 0.2032)
				(type default)
			)
			(layer "F.SilkS")
		)
		(fp_rect
			(start -0.5842 1.3335)
			(end 0.5842 -1.3335)
			(stroke
				(width 0)
				(type default)
			)
			(fill no)
			(layer "F.CrtYd")
		)
		(fp_rect
			(start -0.5842 1.3335)
			(end 0.5842 -1.3335)
			(stroke
				(width 0)
				(type default)
			)
			(fill no)
			(layer "F.Fab")
		)
		(pad "1" smd custom
			(at 0 -0.762 180)
			(size 0.2159 0.2159)
			(layers "F.Cu" "F.Mask" "F.Paste")
			(net "MB3_CM_OV_R")
			(options
				(clearance outline)
				(anchor circle)
			)
			(primitives
				(gr_poly
					(pts
						(arc
							(start -0.3302 -0.4318)
							(mid -0.402042 -0.402042)
							(end -0.4318 -0.3302)
						)
						(arc
							(start -0.4318 0.3302)
							(mid -0.402042 0.402042)
							(end -0.3302 0.4318)
						)
						(arc
							(start 0.3302 0.4318)
							(mid 0.402042 0.402042)
							(end 0.4318 0.3302)
						)
						(arc
							(start 0.4318 -0.3302)
							(mid 0.402042 -0.402042)
							(end 0.3302 -0.4318)
						)
					)
					(width 0)
					(fill yes)
				)
			)
		)
		(pad "2" smd custom
			(at 0 0.762 180)
			(size 0.2159 0.2159)
			(layers "F.Cu" "F.Mask" "F.Paste")
			(net "AGND_CURRENT_DPB")
			(options
				(clearance outline)
				(anchor circle)
			)
			(primitives
				(gr_poly
					(pts
						(arc
							(start -0.3302 -0.4318)
							(mid -0.402042 -0.402042)
							(end -0.4318 -0.3302)
						)
						(arc
							(start -0.4318 0.3302)
							(mid -0.402042 0.402042)
							(end -0.3302 0.4318)
						)
						(arc
							(start 0.3302 0.4318)
							(mid 0.402042 0.402042)
							(end 0.4318 0.3302)
						)
						(arc
							(start 0.4318 -0.3302)
							(mid 0.402042 -0.402042)
							(end 0.3302 -0.4318)
						)
					)
					(width 0)
					(fill yes)
				)
			)
		)
	)
	(footprint ""
		(layer "F.Cu")
		(at 98.806 -32.8676 180)
		(property "Reference" "R672"
			(at 0 0 180)
			(layer "F.SilkS")
			(hide yes)
			(effects
				(font
					(size 1.27 1.27)
				)
			)
		)
		(property "Value" "220R3F-1-GP"
			(at -0.0254 -2.5146 180)
			(unlocked yes)
			(layer "F.Fab")
			(hide yes)
			(effects
				(font
					(size 1.016 1.016)
					(thickness 0.1524)
				)
			)
		)
		(property "Device Type" "R603H22"
			(at -0.0254 -4.0386 180)
			(unlocked yes)
			(layer "F.Fab")
			(hide yes)
			(effects
				(font
					(size 1.016 1.016)
					(thickness 0.1524)
				)
			)
		)
		(duplicate_pad_numbers_are_jumpers no)
		(fp_line
			(start 0.2032 0)
			(end 0.4826 0)
			(stroke
				(width 0.2032)
				(type default)
			)
			(layer "F.SilkS")
		)
		(fp_line
			(start -0.4826 0)
			(end -0.2032 0)
			(stroke
				(width 0.2032)
				(type default)
			)
			(layer "F.SilkS")
		)
		(fp_rect
			(start -0.5842 1.3335)
			(end 0.5842 -1.3335)
			(stroke
				(width 0)
				(type default)
			)
			(fill no)
			(layer "F.CrtYd")
		)
		(fp_rect
			(start -0.5842 1.3335)
			(end 0.5842 -1.3335)
			(stroke
				(width 0)
				(type default)
			)
			(fill no)
			(layer "F.Fab")
		)
		(pad "1" smd custom
			(at 0 -0.762 180)
			(size 0.2159 0.2159)
			(layers "F.Cu" "F.Mask" "F.Paste")
			(net "HDD_PRSNT_26")
			(options
				(clearance outline)
				(anchor circle)
			)
			(primitives
				(gr_poly
					(pts
						(arc
							(start -0.3302 -0.4318)
							(mid -0.402042 -0.402042)
							(end -0.4318 -0.3302)
						)
						(arc
							(start -0.4318 0.3302)
							(mid -0.402042 0.402042)
							(end -0.3302 0.4318)
						)
						(arc
							(start 0.3302 0.4318)
							(mid 0.402042 0.402042)
							(end 0.4318 0.3302)
						)
						(arc
							(start 0.4318 -0.3302)
							(mid 0.402042 -0.402042)
							(end 0.3302 -0.4318)
						)
					)
					(width 0)
					(fill yes)
				)
			)
		)
		(pad "2" smd custom
			(at 0 0.762 180)
			(size 0.2159 0.2159)
			(layers "F.Cu" "F.Mask" "F.Paste")
			(net "DRIVE_B_26_INS")
			(options
				(clearance outline)
				(anchor circle)
			)
			(primitives
				(gr_poly
					(pts
						(arc
							(start -0.3302 -0.4318)
							(mid -0.402042 -0.402042)
							(end -0.4318 -0.3302)
						)
						(arc
							(start -0.4318 0.3302)
							(mid -0.402042 0.402042)
							(end -0.3302 0.4318)
						)
						(arc
							(start 0.3302 0.4318)
							(mid 0.402042 0.402042)
							(end 0.4318 0.3302)
						)
						(arc
							(start 0.4318 -0.3302)
							(mid 0.402042 -0.402042)
							(end 0.3302 -0.4318)
						)
					)
					(width 0)
					(fill yes)
				)
			)
		)
	)
	(footprint ""
		(layer "F.Cu")
		(at 233.26852 -233.023156 180)
		(property "Reference" "R69"
			(at 0 0 180)
			(layer "F.SilkS")
			(hide yes)
			(effects
				(font
					(size 1.27 1.27)
				)
			)
		)
		(property "Value" "4K7R2F-GP"
			(at 0.064008 -3.993896 180)
			(unlocked yes)
			(layer "F.Fab")
			(hide yes)
			(effects
				(font
					(size 1.016 1.016)
					(thickness 0.1524)
				)
			)
		)
		(property "Device Type" "R402H16"
			(at 0.064008 -5.517896 180)
			(unlocked yes)
			(layer "F.Fab")
			(hide yes)
			(effects
				(font
					(size 1.016 1.016)
					(thickness 0.1524)
				)
			)
		)
		(duplicate_pad_numbers_are_jumpers no)
		(fp_line
			(start 0.508 -0.9398)
			(end -0.508 -0.9398)
			(stroke
				(width 0.1524)
				(type default)
			)
			(layer "F.SilkS")
		)
		(fp_line
			(start -0.508 -0.9398)
			(end -0.508 0.9398)
			(stroke
				(width 0.1524)
				(type default)
			)
			(layer "F.SilkS")
		)
		(fp_rect
			(start -0.508 0.9398)
			(end 0.508 -0.9398)
			(stroke
				(width 0)
				(type default)
			)
			(fill no)
			(layer "F.CrtYd")
		)
		(fp_rect
			(start -0.508 0.9398)
			(end 0.508 -0.9398)
			(stroke
				(width 0)
				(type default)
			)
			(fill no)
			(layer "F.Fab")
		)
		(pad "1" smd custom
			(at 0 -0.4445 180)
			(size 0.1397 0.1397)
			(layers "F.Cu" "F.Mask" "F.Paste")
			(net "IO_EXP1_A1")
			(options
				(clearance outline)
				(anchor circle)
			)
			(primitives
				(gr_poly
					(pts
						(arc
							(start -0.1778 -0.2794)
							(mid -0.249642 -0.249642)
							(end -0.2794 -0.1778)
						)
						(arc
							(start -0.2794 0.1778)
							(mid -0.249642 0.249642)
							(end -0.1778 0.2794)
						)
						(arc
							(start 0.1778 0.2794)
							(mid 0.249642 0.249642)
							(end 0.2794 0.1778)
						)
						(arc
							(start 0.2794 -0.1778)
							(mid 0.249642 -0.249642)
							(end 0.1778 -0.2794)
						)
					)
					(width 0)
					(fill yes)
				)
			)
		)
		(pad "2" smd custom
			(at 0 0.4445 180)
			(size 0.1397 0.1397)
			(layers "F.Cu" "F.Mask" "F.Paste")
			(net "GND")
			(options
				(clearance outline)
				(anchor circle)
			)
			(primitives
				(gr_poly
					(pts
						(arc
							(start -0.1778 -0.2794)
							(mid -0.249642 -0.249642)
							(end -0.2794 -0.1778)
						)
						(arc
							(start -0.2794 0.1778)
							(mid -0.249642 0.249642)
							(end -0.1778 0.2794)
						)
						(arc
							(start 0.1778 0.2794)
							(mid 0.249642 0.249642)
							(end 0.2794 0.1778)
						)
						(arc
							(start 0.2794 -0.1778)
							(mid 0.249642 -0.249642)
							(end 0.1778 -0.2794)
						)
					)
					(width 0)
					(fill yes)
				)
			)
		)
	)
	(footprint ""
		(layer "F.Cu")
		(at 382.49225 -244.874034 90)
		(property "Reference" "VIA17"
			(at 0 0 90)
			(layer "F.SilkS")
			(hide yes)
			(effects
				(font
					(size 1.27 1.27)
				)
			)
		)
		(property "Value" "100OHM-8L-2D36MM-L18-GP"
			(at 3.8989 0.5715 90)
			(unlocked yes)
			(layer "F.Fab")
			(hide yes)
			(effects
				(font
					(size 1.016 1.016)
					(thickness 0.1524)
				)
			)
		)
		(property "Device Type" "VIA-PCIE-4P-414097"
			(at 3.8989 -0.9525 90)
			(unlocked yes)
			(layer "F.Fab")
			(hide yes)
			(effects
				(font
					(size 1.016 1.016)
					(thickness 0.1524)
				)
			)
		)
		(duplicate_pad_numbers_are_jumpers no)
		(fp_rect
			(start -2.0701 0.4826)
			(end 2.0701 -0.4826)
			(stroke
				(width 0)
				(type default)
			)
			(fill no)
			(layer "F.CrtYd")
		)
		(fp_rect
			(start -2.0701 0.4826)
			(end 2.0701 -0.4826)
			(stroke
				(width 0)
				(type default)
			)
			(fill no)
			(layer "F.Fab")
		)
		(pad "1" thru_hole circle
			(at -1.5875 0 90)
			(size 0.508 0.508)
			(drill 0.254)
			(layers "*.Cu" "*.Mask")
			(remove_unused_layers no)
			(net "GND")
			(clearance 0.2286)
			(thermal_gap 0.2286)
		)
		(pad "2" thru_hole circle
			(at -0.5715 0 90)
			(size 0.508 0.508)
			(drill 0.254)
			(layers "*.Cu" "*.Mask")
			(remove_unused_layers no)
			(net "PHY_SCC_B_TO_DRV_B_8_DP")
			(clearance 0.2286)
			(thermal_gap 0.2286)
		)
		(pad "3" thru_hole circle
			(at 0.5715 0 90)
			(size 0.508 0.508)
			(drill 0.254)
			(layers "*.Cu" "*.Mask")
			(remove_unused_layers no)
			(net "PHY_SCC_B_TO_DRV_B_8_DN")
			(clearance 0.2286)
			(thermal_gap 0.2286)
		)
		(pad "4" thru_hole circle
			(at 1.5875 0 90)
			(size 0.508 0.508)
			(drill 0.254)
			(layers "*.Cu" "*.Mask")
			(remove_unused_layers no)
			(net "GND")
			(clearance 0.2286)
			(thermal_gap 0.2286)
		)
	)
	(footprint ""
		(layer "F.Cu")
		(at 48.537368 -97.328228 -90)
		(property "Reference" "R366"
			(at 0 0 270)
			(layer "F.SilkS")
			(hide yes)
			(effects
				(font
					(size 1.27 1.27)
				)
			)
		)
		(property "Value" "4K7R2F-GP"
			(at 0.064008 -3.993896 270)
			(unlocked yes)
			(layer "F.Fab")
			(hide yes)
			(effects
				(font
					(size 1.016 1.016)
					(thickness 0.1524)
				)
			)
		)
		(property "Device Type" "R402H16"
			(at 0.064008 -5.517896 270)
			(unlocked yes)
			(layer "F.Fab")
			(hide yes)
			(effects
				(font
					(size 1.016 1.016)
					(thickness 0.1524)
				)
			)
		)
		(duplicate_pad_numbers_are_jumpers no)
		(fp_line
			(start -0.508 -0.9398)
			(end -0.508 0.9398)
			(stroke
				(width 0.1524)
				(type default)
			)
			(layer "F.SilkS")
		)
		(fp_line
			(start 0.508 -0.9398)
			(end -0.508 -0.9398)
			(stroke
				(width 0.1524)
				(type default)
			)
			(layer "F.SilkS")
		)
		(fp_rect
			(start -0.508 0.9398)
			(end 0.508 -0.9398)
			(stroke
				(width 0)
				(type default)
			)
			(fill no)
			(layer "F.CrtYd")
		)
		(fp_rect
			(start -0.508 0.9398)
			(end 0.508 -0.9398)
			(stroke
				(width 0)
				(type default)
			)
			(fill no)
			(layer "F.Fab")
		)
		(pad "1" smd custom
			(at 0 -0.4445 270)
			(size 0.1397 0.1397)
			(layers "F.Cu" "F.Mask" "F.Paste")
			(net "DRIVE_B_13_ACT")
			(options
				(clearance outline)
				(anchor circle)
			)
			(primitives
				(gr_poly
					(pts
						(arc
							(start -0.1778 -0.2794)
							(mid -0.249642 -0.249642)
							(end -0.2794 -0.1778)
						)
						(arc
							(start -0.2794 0.1778)
							(mid -0.249642 0.249642)
							(end -0.1778 0.2794)
						)
						(arc
							(start 0.1778 0.2794)
							(mid 0.249642 0.249642)
							(end 0.2794 0.1778)
						)
						(arc
							(start 0.2794 -0.1778)
							(mid 0.249642 -0.249642)
							(end 0.1778 -0.2794)
						)
					)
					(width 0)
					(fill yes)
				)
			)
		)
		(pad "2" smd custom
			(at 0 0.4445 270)
			(size 0.1397 0.1397)
			(layers "F.Cu" "F.Mask" "F.Paste")
			(net "GND")
			(options
				(clearance outline)
				(anchor circle)
			)
			(primitives
				(gr_poly
					(pts
						(arc
							(start -0.1778 -0.2794)
							(mid -0.249642 -0.249642)
							(end -0.2794 -0.1778)
						)
						(arc
							(start -0.2794 0.1778)
							(mid -0.249642 0.249642)
							(end -0.1778 0.2794)
						)
						(arc
							(start 0.1778 0.2794)
							(mid 0.249642 0.249642)
							(end 0.2794 0.1778)
						)
						(arc
							(start 0.2794 -0.1778)
							(mid 0.249642 -0.249642)
							(end 0.1778 -0.2794)
						)
					)
					(width 0)
					(fill yes)
				)
			)
		)
	)
	(footprint ""
		(layer "F.Cu")
		(at 109.855 -133.096 180)
		(property "Reference" "R431"
			(at 0 0 180)
			(layer "F.SilkS")
			(hide yes)
			(effects
				(font
					(size 1.27 1.27)
				)
			)
		)
		(property "Value" "200KR2F-L-GP"
			(at 0.064008 -3.993896 180)
			(unlocked yes)
			(layer "F.Fab")
			(hide yes)
			(effects
				(font
					(size 1.016 1.016)
					(thickness 0.1524)
				)
			)
		)
		(property "Device Type" "R402H16"
			(at 0.064008 -5.517896 180)
			(unlocked yes)
			(layer "F.Fab")
			(hide yes)
			(effects
				(font
					(size 1.016 1.016)
					(thickness 0.1524)
				)
			)
		)
		(duplicate_pad_numbers_are_jumpers no)
		(fp_line
			(start 0.508 -0.9398)
			(end -0.508 -0.9398)
			(stroke
				(width 0.1524)
				(type default)
			)
			(layer "F.SilkS")
		)
		(fp_line
			(start -0.508 -0.9398)
			(end -0.508 0.9398)
			(stroke
				(width 0.1524)
				(type default)
			)
			(layer "F.SilkS")
		)
		(fp_rect
			(start -0.508 0.9398)
			(end 0.508 -0.9398)
			(stroke
				(width 0)
				(type default)
			)
			(fill no)
			(layer "F.CrtYd")
		)
		(fp_rect
			(start -0.508 0.9398)
			(end 0.508 -0.9398)
			(stroke
				(width 0)
				(type default)
			)
			(fill no)
			(layer "F.Fab")
		)
		(pad "1" smd custom
			(at 0 -0.4445 180)
			(size 0.1397 0.1397)
			(layers "F.Cu" "F.Mask" "F.Paste")
			(net "SW_HDD_R15")
			(options
				(clearance outline)
				(anchor circle)
			)
			(primitives
				(gr_poly
					(pts
						(arc
							(start -0.1778 -0.2794)
							(mid -0.249642 -0.249642)
							(end -0.2794 -0.1778)
						)
						(arc
							(start -0.2794 0.1778)
							(mid -0.249642 0.249642)
							(end -0.1778 0.2794)
						)
						(arc
							(start 0.1778 0.2794)
							(mid 0.249642 0.249642)
							(end 0.2794 0.1778)
						)
						(arc
							(start 0.2794 -0.1778)
							(mid 0.249642 -0.249642)
							(end 0.1778 -0.2794)
						)
					)
					(width 0)
					(fill yes)
				)
			)
		)
		(pad "2" smd custom
			(at 0 0.4445 180)
			(size 0.1397 0.1397)
			(layers "F.Cu" "F.Mask" "F.Paste")
			(net "SW_HDD_N15")
			(options
				(clearance outline)
				(anchor circle)
			)
			(primitives
				(gr_poly
					(pts
						(arc
							(start -0.1778 -0.2794)
							(mid -0.249642 -0.249642)
							(end -0.2794 -0.1778)
						)
						(arc
							(start -0.2794 0.1778)
							(mid -0.249642 0.249642)
							(end -0.1778 0.2794)
						)
						(arc
							(start 0.1778 0.2794)
							(mid 0.249642 0.249642)
							(end 0.2794 0.1778)
						)
						(arc
							(start 0.2794 -0.1778)
							(mid 0.249642 -0.249642)
							(end 0.1778 -0.2794)
						)
					)
					(width 0)
					(fill yes)
				)
			)
		)
	)
	(footprint ""
		(layer "F.Cu")
		(at 253.57455 -372.347236 180)
		(property "Reference" "R1039"
			(at 0 0 180)
			(layer "F.SilkS")
			(hide yes)
			(effects
				(font
					(size 1.27 1.27)
				)
			)
		)
		(property "Value" "11KR2F-L-GP"
			(at 0.064008 -3.993896 180)
			(unlocked yes)
			(layer "F.Fab")
			(hide yes)
			(effects
				(font
					(size 1.016 1.016)
					(thickness 0.1524)
				)
			)
		)
		(property "Device Type" "R402H16"
			(at 0.064008 -5.517896 180)
			(unlocked yes)
			(layer "F.Fab")
			(hide yes)
			(effects
				(font
					(size 1.016 1.016)
					(thickness 0.1524)
				)
			)
		)
		(duplicate_pad_numbers_are_jumpers no)
		(fp_line
			(start 0.508 -0.9398)
			(end -0.508 -0.9398)
			(stroke
				(width 0.1524)
				(type default)
			)
			(layer "F.SilkS")
		)
		(fp_line
			(start -0.508 -0.9398)
			(end -0.508 0.9398)
			(stroke
				(width 0.1524)
				(type default)
			)
			(layer "F.SilkS")
		)
		(fp_rect
			(start -0.508 0.9398)
			(end 0.508 -0.9398)
			(stroke
				(width 0)
				(type default)
			)
			(fill no)
			(layer "F.CrtYd")
		)
		(fp_rect
			(start -0.508 0.9398)
			(end 0.508 -0.9398)
			(stroke
				(width 0)
				(type default)
			)
			(fill no)
			(layer "F.Fab")
		)
		(pad "1" smd custom
			(at 0 -0.4445 180)
			(size 0.1397 0.1397)
			(layers "F.Cu" "F.Mask" "F.Paste")
			(net "MB3_P12V_PWGIN_R")
			(options
				(clearance outline)
				(anchor circle)
			)
			(primitives
				(gr_poly
					(pts
						(arc
							(start -0.1778 -0.2794)
							(mid -0.249642 -0.249642)
							(end -0.2794 -0.1778)
						)
						(arc
							(start -0.2794 0.1778)
							(mid -0.249642 0.249642)
							(end -0.1778 0.2794)
						)
						(arc
							(start 0.1778 0.2794)
							(mid 0.249642 0.249642)
							(end 0.2794 0.1778)
						)
						(arc
							(start 0.2794 -0.1778)
							(mid 0.249642 -0.249642)
							(end 0.1778 -0.2794)
						)
					)
					(width 0)
					(fill yes)
				)
			)
		)
		(pad "2" smd custom
			(at 0 0.4445 180)
			(size 0.1397 0.1397)
			(layers "F.Cu" "F.Mask" "F.Paste")
			(net "AGND_CURRENT_DPB")
			(options
				(clearance outline)
				(anchor circle)
			)
			(primitives
				(gr_poly
					(pts
						(arc
							(start -0.1778 -0.2794)
							(mid -0.249642 -0.249642)
							(end -0.2794 -0.1778)
						)
						(arc
							(start -0.2794 0.1778)
							(mid -0.249642 0.249642)
							(end -0.1778 0.2794)
						)
						(arc
							(start 0.1778 0.2794)
							(mid 0.249642 0.249642)
							(end 0.2794 0.1778)
						)
						(arc
							(start 0.2794 -0.1778)
							(mid 0.249642 -0.249642)
							(end 0.1778 -0.2794)
						)
					)
					(width 0)
					(fill yes)
				)
			)
		)
	)
	(footprint ""
		(layer "F.Cu")
		(at 178.181 -134.493 180)
		(property "Reference" "Q77"
			(at 0 0 180)
			(layer "F.SilkS")
			(hide yes)
			(effects
				(font
					(size 1.27 1.27)
				)
			)
		)
		(property "Value" "2N7002KDW-GP"
			(at -2.3622 -8.2042 180)
			(unlocked yes)
			(layer "F.Fab")
			(hide yes)
			(effects
				(font
					(size 1.016 1.016)
					(thickness 0.1524)
				)
			)
		)
		(property "Device Type" "SOT-363H44"
			(at -2.3622 -10.1092 180)
			(unlocked yes)
			(layer "F.Fab")
			(hide yes)
			(effects
				(font
					(size 1.016 1.016)
					(thickness 0.1524)
				)
			)
		)
		(duplicate_pad_numbers_are_jumpers no)
		(fp_line
			(start 1.4478 1.7018)
			(end 1.4478 -1.7018)
			(stroke
				(width 0.1524)
				(type default)
			)
			(layer "F.SilkS")
		)
		(fp_line
			(start 1.4478 -1.7018)
			(end -1.4478 -1.7018)
			(stroke
				(width 0.1524)
				(type default)
			)
			(layer "F.SilkS")
		)
		(fp_line
			(start -1.27 1.524)
			(end -1.27 0.6604)
			(stroke
				(width 0.4826)
				(type default)
			)
			(layer "F.SilkS")
		)
		(fp_line
			(start -1.4478 1.7018)
			(end 1.4478 1.7018)
			(stroke
				(width 0.1524)
				(type default)
			)
			(layer "F.SilkS")
		)
		(fp_line
			(start -1.4478 -1.7018)
			(end -1.4478 1.7018)
			(stroke
				(width 0.1524)
				(type default)
			)
			(layer "F.SilkS")
		)
		(fp_poly
			(pts
				(xy -1.524 -1.778) (xy 1.524 -1.778) (xy 1.524 1.778) (xy -1.524 1.778)
			)
			(stroke
				(width 0)
				(type default)
			)
			(fill no)
			(layer "F.CrtYd")
		)
		(fp_poly
			(pts
				(xy -1.524 -1.778) (xy 1.524 -1.778) (xy 1.524 1.778) (xy -1.524 1.778)
			)
			(stroke
				(width 0)
				(type default)
			)
			(fill no)
			(layer "F.Fab")
		)
		(pad "1" smd rect
			(at -0.65024 0.9398 180)
			(size 0.4064 1.016)
			(layers "F.Cu" "F.Mask" "F.Paste")
			(net "GND")
		)
		(pad "2" smd rect
			(at 0 0.9398 180)
			(size 0.4064 1.016)
			(layers "F.Cu" "F.Mask" "F.Paste")
			(net "SW_PWR_R_HDD17")
		)
		(pad "3" smd rect
			(at 0.65024 0.9398 180)
			(size 0.4064 1.016)
			(layers "F.Cu" "F.Mask" "F.Paste")
			(net "SW_HDD_P17")
		)
		(pad "4" smd rect
			(at 0.65024 -0.9398 180)
			(size 0.4064 1.016)
			(layers "F.Cu" "F.Mask" "F.Paste")
			(net "GND")
		)
		(pad "5" smd rect
			(at 0 -0.9398 180)
			(size 0.4064 1.016)
			(layers "F.Cu" "F.Mask" "F.Paste")
			(net "SW_HDD_G17")
		)
		(pad "6" smd rect
			(at -0.65024 -0.9398 180)
			(size 0.4064 1.016)
			(layers "F.Cu" "F.Mask" "F.Paste")
			(net "SW_HDD_R17")
		)
	)
	(footprint ""
		(layer "F.Cu")
		(at 172.212 -24.384)
		(property "Reference" "Q150"
			(at 0 0 0)
			(layer "F.SilkS")
			(hide yes)
			(effects
				(font
					(size 1.27 1.27)
				)
			)
		)
		(property "Value" "AO4407AL-GP"
			(at -3.707384 -1.5367 0)
			(unlocked yes)
			(layer "F.Fab")
			(hide yes)
			(effects
				(font
					(size 1.016 1.016)
					(thickness 0.1524)
				)
			)
		)
		(property "Device Type" "SOIC8H69"
			(at -3.707384 -3.0607 0)
			(unlocked yes)
			(layer "F.Fab")
			(hide yes)
			(effects
				(font
					(size 1.016 1.016)
					(thickness 0.1524)
				)
			)
		)
		(duplicate_pad_numbers_are_jumpers no)
		(fp_line
			(start -2.7432 -1.4224)
			(end -2.7432 1.4224)
			(stroke
				(width 0.1524)
				(type default)
			)
			(layer "F.SilkS")
		)
		(fp_line
			(start -2.7432 1.4224)
			(end -2.6416 1.4224)
			(stroke
				(width 0.1524)
				(type default)
			)
			(layer "F.SilkS")
		)
		(fp_line
			(start -2.7432 1.4224)
			(end 2.1336 1.4224)
			(stroke
				(width 0.1524)
				(type default)
			)
			(layer "F.SilkS")
		)
		(fp_line
			(start -2.7178 -0.508)
			(end -2.1844 -0.0508)
			(stroke
				(width 0.1524)
				(type default)
			)
			(layer "F.SilkS")
		)
		(fp_line
			(start -2.6289 3.4417)
			(end -2.6289 1.4732)
			(stroke
				(width 0.381)
				(type default)
			)
			(layer "F.SilkS")
		)
		(fp_line
			(start -2.1844 -0.0508)
			(end -2.7178 0.508)
			(stroke
				(width 0.1524)
				(type default)
			)
			(layer "F.SilkS")
		)
		(fp_line
			(start 2.1336 -1.4224)
			(end -2.7432 -1.4224)
			(stroke
				(width 0.1524)
				(type default)
			)
			(layer "F.SilkS")
		)
		(fp_line
			(start 2.1336 1.4224)
			(end 2.1336 -1.4224)
			(stroke
				(width 0.1524)
				(type default)
			)
			(layer "F.SilkS")
		)
		(fp_poly
			(pts
				(xy -2.2098 -1.4224) (xy -2.2098 1.4224) (xy 2.2098 1.4224) (xy 2.2098 -1.4224)
			)
			(stroke
				(width 0)
				(type default)
			)
			(fill yes)
			(layer "F.SilkS")
		)
		(fp_rect
			(start -2.450084 2.999994)
			(end 2.450084 -2.999994)
			(stroke
				(width 0)
				(type default)
			)
			(fill no)
			(layer "F.CrtYd")
		)
		(fp_poly
			(pts
				(xy -2.8194 3.6322) (xy -2.8194 -3.6322) (xy 2.8194 -3.6322) (xy 2.8194 1.18364) (xy 2.450084 1.18364)
				(xy 2.450084 -2.999994) (xy -2.450084 -2.999994) (xy -2.450084 2.999994) (xy 2.450084 2.999994)
				(xy 2.450084 1.18618) (xy 2.8194 1.18618) (xy 2.8194 3.6322)
			)
			(stroke
				(width 0)
				(type default)
			)
			(fill no)
			(layer "F.CrtYd")
		)
		(fp_rect
			(start -2.8194 3.6322)
			(end 2.8194 -3.6322)
			(stroke
				(width 0)
				(type default)
			)
			(fill no)
			(layer "F.Fab")
		)
		(pad "1" smd rect
			(at -1.905 2.54)
			(size 0.635 1.651)
			(layers "F.Cu" "F.Mask" "F.Paste")
			(net "P12V_B")
		)
		(pad "2" smd rect
			(at -0.635 2.54)
			(size 0.635 1.651)
			(layers "F.Cu" "F.Mask" "F.Paste")
			(net "P12V_B")
		)
		(pad "3" smd rect
			(at 0.635 2.54)
			(size 0.635 1.651)
			(layers "F.Cu" "F.Mask" "F.Paste")
			(net "P12V_B")
		)
		(pad "4" smd rect
			(at 1.905 2.54)
			(size 0.635 1.651)
			(layers "F.Cu" "F.Mask" "F.Paste")
			(net "SW_HDD_N29")
		)
		(pad "5" smd rect
			(at 1.905 -2.54)
			(size 0.635 1.651)
			(layers "F.Cu" "F.Mask" "F.Paste")
			(net "P12V_HDD29")
		)
		(pad "6" smd rect
			(at 0.635 -2.54)
			(size 0.635 1.651)
			(layers "F.Cu" "F.Mask" "F.Paste")
			(net "P12V_HDD29")
		)
		(pad "7" smd rect
			(at -0.635 -2.54)
			(size 0.635 1.651)
			(layers "F.Cu" "F.Mask" "F.Paste")
			(net "P12V_HDD29")
		)
		(pad "8" smd rect
			(at -1.905 -2.54)
			(size 0.635 1.651)
			(layers "F.Cu" "F.Mask" "F.Paste")
			(net "P12V_HDD29")
		)
	)
	(footprint ""
		(layer "F.Cu")
		(at 350.766126 -39.705026)
		(property "Reference" "TP176"
			(at 0 0 0)
			(layer "F.SilkS")
			(hide yes)
			(effects
				(font
					(size 1.27 1.27)
				)
			)
		)
		(property "Value" "*"
			(at -0.0508 -1.6764 0)
			(unlocked yes)
			(layer "F.Fab")
			(hide yes)
			(effects
				(font
					(size 1.016 1.016)
					(thickness 0.1524)
				)
			)
		)
		(property "Device Type" "TPAD32"
			(at -0.0508 -3.2004 0)
			(unlocked yes)
			(layer "F.Fab")
			(hide yes)
			(effects
				(font
					(size 1.016 1.016)
					(thickness 0.1524)
				)
			)
		)
		(duplicate_pad_numbers_are_jumpers no)
		(fp_poly
			(pts
				(arc
					(start 0.4064 0)
					(mid -0.4064 0)
					(end 0.4064 0)
				)
			)
			(stroke
				(width 0)
				(type default)
			)
			(fill no)
			(layer "F.CrtYd")
		)
		(fp_poly
			(pts
				(arc
					(start 0.7112 0)
					(mid -0.7112 0)
					(end 0.7112 0)
				)
			)
			(stroke
				(width 0)
				(type default)
			)
			(fill no)
			(layer "F.Fab")
		)
		(pad "1" smd circle
			(at 0 0)
			(size 0.8128 0.8128)
			(layers "F.Cu" "F.Mask" "F.Paste")
			(net "ACT_HDD_31")
		)
	)
	(footprint ""
		(layer "F.Cu")
		(at 173.482 -363.22 90)
		(property "Reference" "R1005"
			(at 0 0 90)
			(layer "F.SilkS")
			(hide yes)
			(effects
				(font
					(size 1.27 1.27)
				)
			)
		)
		(property "Value" "100KR2F-L1-GP"
			(at 0.064008 -3.993896 90)
			(unlocked yes)
			(layer "F.Fab")
			(hide yes)
			(effects
				(font
					(size 1.016 1.016)
					(thickness 0.1524)
				)
			)
		)
		(property "Device Type" "R402H16"
			(at 0.064008 -5.517896 90)
			(unlocked yes)
			(layer "F.Fab")
			(hide yes)
			(effects
				(font
					(size 1.016 1.016)
					(thickness 0.1524)
				)
			)
		)
		(duplicate_pad_numbers_are_jumpers no)
		(fp_line
			(start 0.508 -0.9398)
			(end -0.508 -0.9398)
			(stroke
				(width 0.1524)
				(type default)
			)
			(layer "F.SilkS")
		)
		(fp_line
			(start -0.508 -0.9398)
			(end -0.508 0.9398)
			(stroke
				(width 0.1524)
				(type default)
			)
			(layer "F.SilkS")
		)
		(fp_rect
			(start -0.508 0.9398)
			(end 0.508 -0.9398)
			(stroke
				(width 0)
				(type default)
			)
			(fill no)
			(layer "F.CrtYd")
		)
		(fp_rect
			(start -0.508 0.9398)
			(end 0.508 -0.9398)
			(stroke
				(width 0)
				(type default)
			)
			(fill no)
			(layer "F.Fab")
		)
		(pad "1" smd custom
			(at 0 -0.4445 90)
			(size 0.1397 0.1397)
			(layers "F.Cu" "F.Mask" "F.Paste")
			(net "MB0_VCAP_R")
			(options
				(clearance outline)
				(anchor circle)
			)
			(primitives
				(gr_poly
					(pts
						(arc
							(start -0.1778 -0.2794)
							(mid -0.249642 -0.249642)
							(end -0.2794 -0.1778)
						)
						(arc
							(start -0.2794 0.1778)
							(mid -0.249642 0.249642)
							(end -0.1778 0.2794)
						)
						(arc
							(start 0.1778 0.2794)
							(mid 0.249642 0.249642)
							(end 0.2794 0.1778)
						)
						(arc
							(start 0.2794 -0.1778)
							(mid 0.249642 -0.249642)
							(end 0.1778 -0.2794)
						)
					)
					(width 0)
					(fill yes)
				)
			)
		)
		(pad "2" smd custom
			(at 0 0.4445 90)
			(size 0.1397 0.1397)
			(layers "F.Cu" "F.Mask" "F.Paste")
			(net "MB0_ISET_R")
			(options
				(clearance outline)
				(anchor circle)
			)
			(primitives
				(gr_poly
					(pts
						(arc
							(start -0.1778 -0.2794)
							(mid -0.249642 -0.249642)
							(end -0.2794 -0.1778)
						)
						(arc
							(start -0.2794 0.1778)
							(mid -0.249642 0.249642)
							(end -0.1778 0.2794)
						)
						(arc
							(start 0.1778 0.2794)
							(mid 0.249642 0.249642)
							(end 0.2794 0.1778)
						)
						(arc
							(start 0.2794 -0.1778)
							(mid 0.249642 -0.249642)
							(end 0.1778 -0.2794)
						)
					)
					(width 0)
					(fill yes)
				)
			)
		)
	)
	(footprint ""
		(layer "F.Cu")
		(at 22.967696 -372.3259 -90)
		(property "Reference" "R962"
			(at 0 0 270)
			(layer "F.SilkS")
			(hide yes)
			(effects
				(font
					(size 1.27 1.27)
				)
			)
		)
		(property "Value" "1KR5F-1-GP"
			(at 0 -8.9535 270)
			(unlocked yes)
			(layer "F.Fab")
			(hide yes)
			(effects
				(font
					(size 1.27 1.016)
					(thickness 0.1524)
				)
			)
		)
		(property "Device Type" "R805H24"
			(at 0 -10.6299 270)
			(unlocked yes)
			(layer "F.Fab")
			(hide yes)
			(effects
				(font
					(size 1.27 1.016)
					(thickness 0.1524)
				)
			)
		)
		(duplicate_pad_numbers_are_jumpers no)
		(fp_line
			(start -0.889 1.7018)
			(end 0.889 1.7018)
			(stroke
				(width 0.1524)
				(type default)
			)
			(layer "F.SilkS")
		)
		(fp_line
			(start 0.889 1.7018)
			(end 0.889 -0.508)
			(stroke
				(width 0.1524)
				(type default)
			)
			(layer "F.SilkS")
		)
		(fp_line
			(start -0.889 0.0762)
			(end -0.889 1.7018)
			(stroke
				(width 0.1524)
				(type default)
			)
			(layer "F.SilkS")
		)
		(fp_line
			(start -0.889 -1.7018)
			(end -0.889 0.2794)
			(stroke
				(width 0.1524)
				(type default)
			)
			(layer "F.SilkS")
		)
		(fp_line
			(start 0.889 -1.7018)
			(end 0.889 -0.381)
			(stroke
				(width 0.1524)
				(type default)
			)
			(layer "F.SilkS")
		)
		(fp_line
			(start 0.889 -1.7018)
			(end -0.889 -1.7018)
			(stroke
				(width 0.1524)
				(type default)
			)
			(layer "F.SilkS")
		)
		(fp_poly
			(pts
				(xy 0.9652 -1.778) (xy 0.9652 1.778) (xy -0.9652 1.778) (xy -0.9652 -1.778)
			)
			(stroke
				(width 0)
				(type default)
			)
			(fill no)
			(layer "F.CrtYd")
		)
		(fp_rect
			(start -0.9652 1.778)
			(end 0.9652 -1.778)
			(stroke
				(width 0)
				(type default)
			)
			(fill no)
			(layer "F.Fab")
		)
		(pad "1" smd rect
			(at 0 -0.9652 270)
			(size 1.397 1.143)
			(layers "F.Cu" "F.Mask" "F.Paste")
			(net "FAN_YELLOW_0")
		)
		(pad "2" smd rect
			(at 0 0.9652 270)
			(size 1.397 1.143)
			(layers "F.Cu" "F.Mask" "F.Paste")
			(net "FAN_LED_YELLOW_0")
		)
	)
	(footprint ""
		(layer "F.Cu")
		(at 476.9866 -134.7724 -90)
		(property "Reference" "R599"
			(at 0 0 270)
			(layer "F.SilkS")
			(hide yes)
			(effects
				(font
					(size 1.27 1.27)
				)
			)
		)
		(property "Value" "10KR2F-2-GP"
			(at 0.064008 -3.993896 270)
			(unlocked yes)
			(layer "F.Fab")
			(hide yes)
			(effects
				(font
					(size 1.016 1.016)
					(thickness 0.1524)
				)
			)
		)
		(property "Device Type" "R402H16"
			(at 0.064008 -5.517896 270)
			(unlocked yes)
			(layer "F.Fab")
			(hide yes)
			(effects
				(font
					(size 1.016 1.016)
					(thickness 0.1524)
				)
			)
		)
		(duplicate_pad_numbers_are_jumpers no)
		(fp_line
			(start -0.508 -0.9398)
			(end -0.508 0.9398)
			(stroke
				(width 0.1524)
				(type default)
			)
			(layer "F.SilkS")
		)
		(fp_line
			(start 0.508 -0.9398)
			(end -0.508 -0.9398)
			(stroke
				(width 0.1524)
				(type default)
			)
			(layer "F.SilkS")
		)
		(fp_rect
			(start -0.508 0.9398)
			(end 0.508 -0.9398)
			(stroke
				(width 0)
				(type default)
			)
			(fill no)
			(layer "F.CrtYd")
		)
		(fp_rect
			(start -0.508 0.9398)
			(end 0.508 -0.9398)
			(stroke
				(width 0)
				(type default)
			)
			(fill no)
			(layer "F.Fab")
		)
		(pad "1" smd custom
			(at 0 -0.4445 270)
			(size 0.1397 0.1397)
			(layers "F.Cu" "F.Mask" "F.Paste")
			(net "P3V3_STBY_B")
			(options
				(clearance outline)
				(anchor circle)
			)
			(primitives
				(gr_poly
					(pts
						(arc
							(start -0.1778 -0.2794)
							(mid -0.249642 -0.249642)
							(end -0.2794 -0.1778)
						)
						(arc
							(start -0.2794 0.1778)
							(mid -0.249642 0.249642)
							(end -0.1778 0.2794)
						)
						(arc
							(start 0.1778 0.2794)
							(mid 0.249642 0.249642)
							(end 0.2794 0.1778)
						)
						(arc
							(start 0.2794 -0.1778)
							(mid 0.249642 -0.249642)
							(end 0.1778 -0.2794)
						)
					)
					(width 0)
					(fill yes)
				)
			)
		)
		(pad "2" smd custom
			(at 0 0.4445 270)
			(size 0.1397 0.1397)
			(layers "F.Cu" "F.Mask" "F.Paste")
			(net "HDD_PRSNT_23")
			(options
				(clearance outline)
				(anchor circle)
			)
			(primitives
				(gr_poly
					(pts
						(arc
							(start -0.1778 -0.2794)
							(mid -0.249642 -0.249642)
							(end -0.2794 -0.1778)
						)
						(arc
							(start -0.2794 0.1778)
							(mid -0.249642 0.249642)
							(end -0.1778 0.2794)
						)
						(arc
							(start 0.1778 0.2794)
							(mid 0.249642 0.249642)
							(end 0.2794 0.1778)
						)
						(arc
							(start 0.2794 -0.1778)
							(mid 0.249642 -0.249642)
							(end 0.1778 -0.2794)
						)
					)
					(width 0)
					(fill yes)
				)
			)
		)
	)
	(footprint ""
		(layer "F.Cu")
		(at 371.293644 -214.860378 90)
		(property "Reference" "Q251"
			(at 0 0 90)
			(layer "F.SilkS")
			(hide yes)
			(effects
				(font
					(size 1.27 1.27)
				)
			)
		)
		(property "Value" "SSM3K324R-GP"
			(at 0.127 -8.9662 90)
			(unlocked yes)
			(layer "F.Fab")
			(hide yes)
			(effects
				(font
					(size 1.016 1.016)
					(thickness 0.1524)
				)
			)
		)
		(property "Device Type" "SOT23DGS2D4H35"
			(at 0.127 -10.4902 90)
			(unlocked yes)
			(layer "F.Fab")
			(hide yes)
			(effects
				(font
					(size 1.016 1.016)
					(thickness 0.1524)
				)
			)
		)
		(duplicate_pad_numbers_are_jumpers no)
		(fp_line
			(start 1.651 -1.778)
			(end -1.651 -1.778)
			(stroke
				(width 0.1524)
				(type default)
			)
			(layer "F.SilkS")
		)
		(fp_line
			(start -1.651 -1.778)
			(end -1.651 1.778)
			(stroke
				(width 0.1524)
				(type default)
			)
			(layer "F.SilkS")
		)
		(fp_line
			(start 1.651 1.778)
			(end 1.651 -1.778)
			(stroke
				(width 0.1524)
				(type default)
			)
			(layer "F.SilkS")
		)
		(fp_line
			(start -1.651 1.778)
			(end 1.651 1.778)
			(stroke
				(width 0.1524)
				(type default)
			)
			(layer "F.SilkS")
		)
		(fp_poly
			(pts
				(xy -1.778 1.8796) (xy -1.778 -1.8796) (xy 1.778 -1.8796) (xy 1.778 1.8796)
			)
			(stroke
				(width 0)
				(type default)
			)
			(fill no)
			(layer "F.CrtYd")
		)
		(fp_poly
			(pts
				(xy -1.778 1.8796) (xy -1.778 -1.8796) (xy 1.778 -1.8796) (xy 1.778 1.8796)
			)
			(stroke
				(width 0)
				(type default)
			)
			(fill no)
			(layer "F.Fab")
		)
		(pad "D" smd custom
			(at 0 -0.9525 90)
			(size 0.1905 0.1905)
			(layers "F.Cu" "F.Mask" "F.Paste")
			(net "DRV_ACT_8_N")
			(options
				(clearance outline)
				(anchor circle)
			)
			(primitives
				(gr_poly
					(pts
						(arc
							(start -0.1778 0.5715)
							(mid -0.321484 0.511984)
							(end -0.381 0.3683)
						)
						(arc
							(start -0.381 -0.3683)
							(mid -0.321484 -0.511984)
							(end -0.1778 -0.5715)
						)
						(arc
							(start 0.1778 -0.5715)
							(mid 0.321484 -0.511984)
							(end 0.381 -0.3683)
						)
						(arc
							(start 0.381 0.3683)
							(mid 0.321484 0.511984)
							(end 0.1778 0.5715)
						)
					)
					(width 0)
					(fill yes)
				)
			)
		)
		(pad "G" smd custom
			(at -0.98425 0.9525 90)
			(size 0.1905 0.1905)
			(layers "F.Cu" "F.Mask" "F.Paste")
			(net "DRIVE_B_8_ACT")
			(options
				(clearance outline)
				(anchor circle)
			)
			(primitives
				(gr_poly
					(pts
						(arc
							(start -0.1778 0.5715)
							(mid -0.321484 0.511984)
							(end -0.381 0.3683)
						)
						(arc
							(start -0.381 -0.3683)
							(mid -0.321484 -0.511984)
							(end -0.1778 -0.5715)
						)
						(arc
							(start 0.1778 -0.5715)
							(mid 0.321484 -0.511984)
							(end 0.381 -0.3683)
						)
						(arc
							(start 0.381 0.3683)
							(mid 0.321484 0.511984)
							(end 0.1778 0.5715)
						)
					)
					(width 0)
					(fill yes)
				)
			)
		)
		(pad "S" smd custom
			(at 0.98425 0.9525 90)
			(size 0.1905 0.1905)
			(layers "F.Cu" "F.Mask" "F.Paste")
			(net "GND")
			(options
				(clearance outline)
				(anchor circle)
			)
			(primitives
				(gr_poly
					(pts
						(arc
							(start -0.1778 0.5715)
							(mid -0.321484 0.511984)
							(end -0.381 0.3683)
						)
						(arc
							(start -0.381 -0.3683)
							(mid -0.321484 -0.511984)
							(end -0.1778 -0.5715)
						)
						(arc
							(start 0.1778 -0.5715)
							(mid 0.321484 -0.511984)
							(end 0.381 -0.3683)
						)
						(arc
							(start 0.381 0.3683)
							(mid 0.321484 0.511984)
							(end 0.1778 0.5715)
						)
					)
					(width 0)
					(fill yes)
				)
			)
		)
	)
	(footprint ""
		(layer "F.Cu")
		(at 77.978 -255.524 90)
		(property "Reference" "C65"
			(at 0 0 90)
			(layer "F.SilkS")
			(hide yes)
			(effects
				(font
					(size 1.27 1.27)
				)
			)
		)
		(property "Value" "SCD033U25V2KX-GP"
			(at 1.1811 -2.7051 90)
			(unlocked yes)
			(layer "F.Fab")
			(hide yes)
			(effects
				(font
					(size 1.016 1.016)
					(thickness 0.1524)
				)
			)
		)
		(property "Device Type" "C402H22"
			(at 1.1811 -4.2291 90)
			(unlocked yes)
			(layer "F.Fab")
			(hide yes)
			(effects
				(font
					(size 1.016 1.016)
					(thickness 0.1524)
				)
			)
		)
		(duplicate_pad_numbers_are_jumpers no)
		(fp_rect
			(start -0.4318 0.9525)
			(end 0.4318 -0.9525)
			(stroke
				(width 0)
				(type default)
			)
			(fill no)
			(layer "F.CrtYd")
		)
		(fp_rect
			(start -0.4318 0.9525)
			(end 0.4318 -0.9525)
			(stroke
				(width 0)
				(type default)
			)
			(fill no)
			(layer "F.Fab")
		)
		(pad "1" smd custom
			(at 0 -0.4445 90)
			(size 0.1524 0.1524)
			(layers "F.Cu" "F.Mask" "F.Paste")
			(net "P12V_B")
			(options
				(clearance outline)
				(anchor circle)
			)
			(primitives
				(gr_poly
					(pts
						(arc
							(start 0.3048 -0.2032)
							(mid 0.275042 -0.275042)
							(end 0.2032 -0.3048)
						)
						(arc
							(start -0.2032 -0.3048)
							(mid -0.275042 -0.275042)
							(end -0.3048 -0.2032)
						)
						(arc
							(start -0.3048 0.2032)
							(mid -0.275042 0.275042)
							(end -0.2032 0.3048)
						)
						(arc
							(start 0.2032 0.3048)
							(mid 0.275042 0.275042)
							(end 0.3048 0.2032)
						)
					)
					(width 0)
					(fill yes)
				)
			)
		)
		(pad "2" smd custom
			(at 0 0.4445 90)
			(size 0.1524 0.1524)
			(layers "F.Cu" "F.Mask" "F.Paste")
			(net "SW_HDD_N2")
			(options
				(clearance outline)
				(anchor circle)
			)
			(primitives
				(gr_poly
					(pts
						(arc
							(start 0.3048 -0.2032)
							(mid 0.275042 -0.275042)
							(end 0.2032 -0.3048)
						)
						(arc
							(start -0.2032 -0.3048)
							(mid -0.275042 -0.275042)
							(end -0.3048 -0.2032)
						)
						(arc
							(start -0.3048 0.2032)
							(mid -0.275042 0.275042)
							(end -0.2032 0.3048)
						)
						(arc
							(start 0.2032 0.3048)
							(mid 0.275042 0.275042)
							(end 0.3048 0.2032)
						)
					)
					(width 0)
					(fill yes)
				)
			)
		)
	)
	(footprint ""
		(layer "F.Cu")
		(at 469.9 -140.462 90)
		(property "Reference" "C338"
			(at 0 0 90)
			(layer "F.SilkS")
			(hide yes)
			(effects
				(font
					(size 1.27 1.27)
				)
			)
		)
		(property "Value" "SCD033U25V2KX-GP"
			(at 1.1811 -2.7051 90)
			(unlocked yes)
			(layer "F.Fab")
			(hide yes)
			(effects
				(font
					(size 1.016 1.016)
					(thickness 0.1524)
				)
			)
		)
		(property "Device Type" "C402H22"
			(at 1.1811 -4.2291 90)
			(unlocked yes)
			(layer "F.Fab")
			(hide yes)
			(effects
				(font
					(size 1.016 1.016)
					(thickness 0.1524)
				)
			)
		)
		(duplicate_pad_numbers_are_jumpers no)
		(fp_rect
			(start -0.4318 0.9525)
			(end 0.4318 -0.9525)
			(stroke
				(width 0)
				(type default)
			)
			(fill no)
			(layer "F.CrtYd")
		)
		(fp_rect
			(start -0.4318 0.9525)
			(end 0.4318 -0.9525)
			(stroke
				(width 0)
				(type default)
			)
			(fill no)
			(layer "F.Fab")
		)
		(pad "1" smd custom
			(at 0 -0.4445 90)
			(size 0.1524 0.1524)
			(layers "F.Cu" "F.Mask" "F.Paste")
			(net "P12V_B")
			(options
				(clearance outline)
				(anchor circle)
			)
			(primitives
				(gr_poly
					(pts
						(arc
							(start 0.3048 -0.2032)
							(mid 0.275042 -0.275042)
							(end 0.2032 -0.3048)
						)
						(arc
							(start -0.2032 -0.3048)
							(mid -0.275042 -0.275042)
							(end -0.3048 -0.2032)
						)
						(arc
							(start -0.3048 0.2032)
							(mid -0.275042 0.275042)
							(end -0.2032 0.3048)
						)
						(arc
							(start 0.2032 0.3048)
							(mid 0.275042 0.275042)
							(end 0.3048 0.2032)
						)
					)
					(width 0)
					(fill yes)
				)
			)
		)
		(pad "2" smd custom
			(at 0 0.4445 90)
			(size 0.1524 0.1524)
			(layers "F.Cu" "F.Mask" "F.Paste")
			(net "SW_HDD_N23")
			(options
				(clearance outline)
				(anchor circle)
			)
			(primitives
				(gr_poly
					(pts
						(arc
							(start 0.3048 -0.2032)
							(mid 0.275042 -0.275042)
							(end 0.2032 -0.3048)
						)
						(arc
							(start -0.2032 -0.3048)
							(mid -0.275042 -0.275042)
							(end -0.3048 -0.2032)
						)
						(arc
							(start -0.3048 0.2032)
							(mid -0.275042 0.275042)
							(end -0.2032 0.3048)
						)
						(arc
							(start 0.2032 0.3048)
							(mid 0.275042 0.275042)
							(end 0.3048 0.2032)
						)
					)
					(width 0)
					(fill yes)
				)
			)
		)
	)
	(footprint ""
		(layer "F.Cu")
		(at 301.371 -230.1494 -90)
		(property "Reference" "R5"
			(at 0 0 270)
			(layer "F.SilkS")
			(hide yes)
			(effects
				(font
					(size 1.27 1.27)
				)
			)
		)
		(property "Value" "10KR2F-2-GP"
			(at 0.064008 -3.993896 270)
			(unlocked yes)
			(layer "F.Fab")
			(hide yes)
			(effects
				(font
					(size 1.016 1.016)
					(thickness 0.1524)
				)
			)
		)
		(property "Device Type" "R402H16"
			(at 0.064008 -5.517896 270)
			(unlocked yes)
			(layer "F.Fab")
			(hide yes)
			(effects
				(font
					(size 1.016 1.016)
					(thickness 0.1524)
				)
			)
		)
		(duplicate_pad_numbers_are_jumpers no)
		(fp_line
			(start -0.508 -0.9398)
			(end -0.508 0.9398)
			(stroke
				(width 0.1524)
				(type default)
			)
			(layer "F.SilkS")
		)
		(fp_line
			(start 0.508 -0.9398)
			(end -0.508 -0.9398)
			(stroke
				(width 0.1524)
				(type default)
			)
			(layer "F.SilkS")
		)
		(fp_rect
			(start -0.508 0.9398)
			(end 0.508 -0.9398)
			(stroke
				(width 0)
				(type default)
			)
			(fill no)
			(layer "F.CrtYd")
		)
		(fp_rect
			(start -0.508 0.9398)
			(end 0.508 -0.9398)
			(stroke
				(width 0)
				(type default)
			)
			(fill no)
			(layer "F.Fab")
		)
		(pad "1" smd custom
			(at 0 -0.4445 270)
			(size 0.1397 0.1397)
			(layers "F.Cu" "F.Mask" "F.Paste")
			(net "P3V3_STBY_B")
			(options
				(clearance outline)
				(anchor circle)
			)
			(primitives
				(gr_poly
					(pts
						(arc
							(start -0.1778 -0.2794)
							(mid -0.249642 -0.249642)
							(end -0.2794 -0.1778)
						)
						(arc
							(start -0.2794 0.1778)
							(mid -0.249642 0.249642)
							(end -0.1778 0.2794)
						)
						(arc
							(start 0.1778 0.2794)
							(mid 0.249642 0.249642)
							(end 0.2794 0.1778)
						)
						(arc
							(start 0.2794 -0.1778)
							(mid 0.249642 -0.249642)
							(end 0.1778 -0.2794)
						)
					)
					(width 0)
					(fill yes)
				)
			)
		)
		(pad "2" smd custom
			(at 0 0.4445 270)
			(size 0.1397 0.1397)
			(layers "F.Cu" "F.Mask" "F.Paste")
			(net "SCC_B_TYPE_1")
			(options
				(clearance outline)
				(anchor circle)
			)
			(primitives
				(gr_poly
					(pts
						(arc
							(start -0.1778 -0.2794)
							(mid -0.249642 -0.249642)
							(end -0.2794 -0.1778)
						)
						(arc
							(start -0.2794 0.1778)
							(mid -0.249642 0.249642)
							(end -0.1778 0.2794)
						)
						(arc
							(start 0.1778 0.2794)
							(mid 0.249642 0.249642)
							(end 0.2794 0.1778)
						)
						(arc
							(start 0.2794 -0.1778)
							(mid 0.249642 -0.249642)
							(end 0.1778 -0.2794)
						)
					)
					(width 0)
					(fill yes)
				)
			)
		)
	)
	(footprint ""
		(layer "F.Cu")
		(at 419.73754 -369.57)
		(property "Reference" "R955"
			(at 0 0 0)
			(layer "F.SilkS")
			(hide yes)
			(effects
				(font
					(size 1.27 1.27)
				)
			)
		)
		(property "Value" "0R2J-2-GP"
			(at 0.064008 -3.993896 0)
			(unlocked yes)
			(layer "F.Fab")
			(hide yes)
			(effects
				(font
					(size 1.016 1.016)
					(thickness 0.1524)
				)
			)
		)
		(property "Device Type" "R402H16"
			(at 0.064008 -5.517896 0)
			(unlocked yes)
			(layer "F.Fab")
			(hide yes)
			(effects
				(font
					(size 1.016 1.016)
					(thickness 0.1524)
				)
			)
		)
		(duplicate_pad_numbers_are_jumpers no)
		(fp_line
			(start -0.508 -0.9398)
			(end -0.508 0.9398)
			(stroke
				(width 0.1524)
				(type default)
			)
			(layer "F.SilkS")
		)
		(fp_line
			(start 0.508 -0.9398)
			(end -0.508 -0.9398)
			(stroke
				(width 0.1524)
				(type default)
			)
			(layer "F.SilkS")
		)
		(fp_rect
			(start -0.508 0.9398)
			(end 0.508 -0.9398)
			(stroke
				(width 0)
				(type default)
			)
			(fill no)
			(layer "F.CrtYd")
		)
		(fp_rect
			(start -0.508 0.9398)
			(end 0.508 -0.9398)
			(stroke
				(width 0)
				(type default)
			)
			(fill no)
			(layer "F.Fab")
		)
		(pad "1" smd custom
			(at 0 -0.4445)
			(size 0.1397 0.1397)
			(layers "F.Cu" "F.Mask" "F.Paste")
			(net "FAN_3_PWM")
			(options
				(clearance outline)
				(anchor circle)
			)
			(primitives
				(gr_poly
					(pts
						(arc
							(start -0.1778 -0.2794)
							(mid -0.249642 -0.249642)
							(end -0.2794 -0.1778)
						)
						(arc
							(start -0.2794 0.1778)
							(mid -0.249642 0.249642)
							(end -0.1778 0.2794)
						)
						(arc
							(start 0.1778 0.2794)
							(mid 0.249642 0.249642)
							(end 0.2794 0.1778)
						)
						(arc
							(start 0.2794 -0.1778)
							(mid 0.249642 -0.249642)
							(end 0.1778 -0.2794)
						)
					)
					(width 0)
					(fill yes)
				)
			)
		)
		(pad "2" smd custom
			(at 0 0.4445)
			(size 0.1397 0.1397)
			(layers "F.Cu" "F.Mask" "F.Paste")
			(net "PWM_OUT_FAN3")
			(options
				(clearance outline)
				(anchor circle)
			)
			(primitives
				(gr_poly
					(pts
						(arc
							(start -0.1778 -0.2794)
							(mid -0.249642 -0.249642)
							(end -0.2794 -0.1778)
						)
						(arc
							(start -0.2794 0.1778)
							(mid -0.249642 0.249642)
							(end -0.1778 0.2794)
						)
						(arc
							(start 0.1778 0.2794)
							(mid 0.249642 0.249642)
							(end 0.2794 0.1778)
						)
						(arc
							(start 0.2794 -0.1778)
							(mid 0.249642 -0.249642)
							(end 0.1778 -0.2794)
						)
					)
					(width 0)
					(fill yes)
				)
			)
		)
	)
	(footprint ""
		(layer "F.Cu")
		(at 265.0617 -380.216156 90)
		(property "Reference" "R1070"
			(at 0 0 90)
			(layer "F.SilkS")
			(hide yes)
			(effects
				(font
					(size 1.27 1.27)
				)
			)
		)
		(property "Value" "0R2J-2-GP"
			(at 0.064008 -3.993896 90)
			(unlocked yes)
			(layer "F.Fab")
			(hide yes)
			(effects
				(font
					(size 1.016 1.016)
					(thickness 0.1524)
				)
			)
		)
		(property "Device Type" "R402H16"
			(at 0.064008 -5.517896 90)
			(unlocked yes)
			(layer "F.Fab")
			(hide yes)
			(effects
				(font
					(size 1.016 1.016)
					(thickness 0.1524)
				)
			)
		)
		(duplicate_pad_numbers_are_jumpers no)
		(fp_line
			(start 0.508 -0.9398)
			(end -0.508 -0.9398)
			(stroke
				(width 0.1524)
				(type default)
			)
			(layer "F.SilkS")
		)
		(fp_line
			(start -0.508 -0.9398)
			(end -0.508 0.9398)
			(stroke
				(width 0.1524)
				(type default)
			)
			(layer "F.SilkS")
		)
		(fp_rect
			(start -0.508 0.9398)
			(end 0.508 -0.9398)
			(stroke
				(width 0)
				(type default)
			)
			(fill no)
			(layer "F.CrtYd")
		)
		(fp_rect
			(start -0.508 0.9398)
			(end 0.508 -0.9398)
			(stroke
				(width 0)
				(type default)
			)
			(fill no)
			(layer "F.Fab")
		)
		(pad "1" smd custom
			(at 0 -0.4445 90)
			(size 0.1397 0.1397)
			(layers "F.Cu" "F.Mask" "F.Paste")
			(net "DRAWER_OUT_NET")
			(options
				(clearance outline)
				(anchor circle)
			)
			(primitives
				(gr_poly
					(pts
						(arc
							(start -0.1778 -0.2794)
							(mid -0.249642 -0.249642)
							(end -0.2794 -0.1778)
						)
						(arc
							(start -0.2794 0.1778)
							(mid -0.249642 0.249642)
							(end -0.1778 0.2794)
						)
						(arc
							(start 0.1778 0.2794)
							(mid 0.249642 0.249642)
							(end 0.2794 0.1778)
						)
						(arc
							(start 0.2794 -0.1778)
							(mid 0.249642 -0.249642)
							(end 0.1778 -0.2794)
						)
					)
					(width 0)
					(fill yes)
				)
			)
		)
		(pad "2" smd custom
			(at 0 0.4445 90)
			(size 0.1397 0.1397)
			(layers "F.Cu" "F.Mask" "F.Paste")
			(net "DRAWER_MOSFET_G")
			(options
				(clearance outline)
				(anchor circle)
			)
			(primitives
				(gr_poly
					(pts
						(arc
							(start -0.1778 -0.2794)
							(mid -0.249642 -0.249642)
							(end -0.2794 -0.1778)
						)
						(arc
							(start -0.2794 0.1778)
							(mid -0.249642 0.249642)
							(end -0.1778 0.2794)
						)
						(arc
							(start 0.1778 0.2794)
							(mid 0.249642 0.249642)
							(end 0.2794 0.1778)
						)
						(arc
							(start 0.2794 -0.1778)
							(mid 0.249642 -0.249642)
							(end 0.1778 -0.2794)
						)
					)
					(width 0)
					(fill yes)
				)
			)
		)
	)
	(footprint ""
		(layer "F.Cu")
		(at 59.749944 -258.910074 -90)
		(property "Reference" "HDDSAS1"
			(at 0 0 270)
			(layer "F.SilkS")
			(hide yes)
			(effects
				(font
					(size 1.27 1.27)
				)
			)
		)
		(property "Value" "SKT-SAS15P-14P-45-GP"
			(at -20.7645 -8.9789 270)
			(unlocked yes)
			(layer "F.Fab")
			(hide yes)
			(effects
				(font
					(size 1.016 1.016)
					(thickness 0.1524)
				)
			)
		)
		(property "Device Type" "10120818-001C-TRLF"
			(at -20.7645 -10.5029 270)
			(unlocked yes)
			(layer "F.Fab")
			(hide yes)
			(effects
				(font
					(size 1.016 1.016)
					(thickness 0.1524)
				)
			)
		)
		(duplicate_pad_numbers_are_jumpers no)
		(fp_line
			(start 1.651 4.2926)
			(end 1.651 3.0099)
			(stroke
				(width 0.1524)
				(type default)
			)
			(layer "F.SilkS")
		)
		(fp_line
			(start 8.509 4.2926)
			(end 1.651 4.2926)
			(stroke
				(width 0.1524)
				(type default)
			)
			(layer "F.SilkS")
		)
		(fp_line
			(start -23.4188 3.0099)
			(end -23.4188 -3.2512)
			(stroke
				(width 0.1524)
				(type default)
			)
			(layer "F.SilkS")
		)
		(fp_line
			(start 1.651 3.0099)
			(end -23.4188 3.0099)
			(stroke
				(width 0.1524)
				(type default)
			)
			(layer "F.SilkS")
		)
		(fp_line
			(start 8.509 3.0099)
			(end 8.509 4.2926)
			(stroke
				(width 0.1524)
				(type default)
			)
			(layer "F.SilkS")
		)
		(fp_line
			(start 23.4188 3.0099)
			(end 8.509 3.0099)
			(stroke
				(width 0.1524)
				(type default)
			)
			(layer "F.SilkS")
		)
		(fp_line
			(start -23.4188 -3.2512)
			(end 23.4188 -3.2512)
			(stroke
				(width 0.1524)
				(type default)
			)
			(layer "F.SilkS")
		)
		(fp_line
			(start 23.4188 -3.2512)
			(end 23.4188 3.0099)
			(stroke
				(width 0.1524)
				(type default)
			)
			(layer "F.SilkS")
		)
		(fp_line
			(start 15.5067 -3.3401)
			(end 16.2687 -3.3401)
			(stroke
				(width 0.3302)
				(type default)
			)
			(layer "F.SilkS")
		)
		(fp_poly
			(pts
				(xy 15.868904 -3.230372) (xy 16.503904 -3.865372) (xy 15.233904 -3.865372)
			)
			(stroke
				(width 0)
				(type default)
			)
			(fill yes)
			(layer "F.SilkS")
		)
		(fp_poly
			(pts
				(xy -22.8727 -2.7559) (xy 22.8727 -2.7559) (xy 22.8727 2.7559) (xy 8.255 2.7559) (xy 8.255 3.5179)
				(xy 1.905 3.5179) (xy 1.905 2.7559) (xy -22.8727 2.7559)
			)
			(stroke
				(width 0)
				(type default)
			)
			(fill no)
			(layer "F.CrtYd")
		)
		(fp_poly
			(pts
				(xy 1.397 4.5466) (xy 1.397 3.2639) (xy -23.6728 3.2639) (xy -23.6728 -3.5052) (xy 23.6728 -3.5052)
				(xy 23.6728 -0.00635) (xy 22.8727 -0.00635) (xy 22.8727 -2.7559) (xy -22.8727 -2.7559) (xy -22.8727 2.7559)
				(xy 1.905 2.7559) (xy 1.905 3.5179) (xy 8.255 3.5179) (xy 8.255 2.7559) (xy 22.8727 2.7559) (xy 22.8727 0.00635)
				(xy 23.6728 0.00635) (xy 23.6728 3.2639) (xy 8.763 3.2639) (xy 8.763 4.5466)
			)
			(stroke
				(width 0)
				(type default)
			)
			(fill no)
			(layer "F.CrtYd")
		)
		(fp_poly
			(pts
				(xy 1.397 4.5466) (xy 1.397 3.2639) (xy -23.6728 3.2639) (xy -23.6728 -3.5052) (xy 23.6728 -3.5052)
				(xy 23.6728 3.2639) (xy 8.763 3.2639) (xy 8.763 4.5466)
			)
			(stroke
				(width 0)
				(type default)
			)
			(fill no)
			(layer "F.Fab")
		)
		(pad "" np_thru_hole circle
			(at -18.874994 0 270)
			(size 0.254 0.254)
			(drill 1.3462)
			(layers "*.Cu" "*.Mask")
			(clearance 0.9017)
			(thermal_gap 0.9017)
		)
		(pad "" np_thru_hole circle
			(at 18.874994 0 270)
			(size 0.254 0.254)
			(drill 0.9398)
			(layers "*.Cu" "*.Mask")
			(clearance 0.6985)
			(thermal_gap 0.6985)
		)
		(pad "G1" smd rect
			(at 21.874988 0 270)
			(size 2.5908 2.5908)
			(layers "F.Cu" "F.Mask" "F.Paste")
			(net "GND")
		)
		(pad "G2" smd rect
			(at -21.874988 0 270)
			(size 2.5908 2.5908)
			(layers "F.Cu" "F.Mask" "F.Paste")
			(net "GND")
		)
		(pad "P1" smd rect
			(at 1.905 -1.82499 270)
			(size 0.6096 2.3622)
			(layers "F.Cu" "F.Mask" "F.Paste")
			(net "Net_1709")
		)
		(pad "P2" smd rect
			(at 0.635 -1.82499 270)
			(size 0.6096 2.3622)
			(layers "F.Cu" "F.Mask" "F.Paste")
			(net "Net_1710")
		)
		(pad "P3" smd rect
			(at -0.635 -1.82499 270)
			(size 0.6096 2.3622)
			(layers "F.Cu" "F.Mask" "F.Paste")
			(net "Net_1711")
		)
		(pad "P4" smd rect
			(at -1.905 -1.82499 270)
			(size 0.6096 2.3622)
			(layers "F.Cu" "F.Mask" "F.Paste")
			(net "GND")
		)
		(pad "P5" smd rect
			(at -3.175 -1.82499 270)
			(size 0.6096 2.3622)
			(layers "F.Cu" "F.Mask" "F.Paste")
			(net "HDD_PRSNT_1")
		)
		(pad "P6" smd rect
			(at -4.445 -1.82499 270)
			(size 0.6096 2.3622)
			(layers "F.Cu" "F.Mask" "F.Paste")
			(net "GND")
		)
		(pad "P7" smd rect
			(at -5.715 -1.82499 270)
			(size 0.6096 2.3622)
			(layers "F.Cu" "F.Mask" "F.Paste")
			(net "5V_PRE_1")
		)
		(pad "P8" smd rect
			(at -6.985 -1.82499 270)
			(size 0.6096 2.3622)
			(layers "F.Cu" "F.Mask" "F.Paste")
			(net "P5V_HDD1")
		)
		(pad "P9" smd rect
			(at -8.255 -1.82499 270)
			(size 0.6096 2.3622)
			(layers "F.Cu" "F.Mask" "F.Paste")
			(net "P5V_HDD1")
		)
		(pad "P10" smd rect
			(at -9.525 -1.82499 270)
			(size 0.6096 2.3622)
			(layers "F.Cu" "F.Mask" "F.Paste")
			(net "GND")
		)
		(pad "P11" smd rect
			(at -10.795 -1.82499 270)
			(size 0.6096 2.3622)
			(layers "F.Cu" "F.Mask" "F.Paste")
			(net "ACT_HDD_1")
		)
		(pad "P12" smd rect
			(at -12.065 -1.82499 270)
			(size 0.6096 2.3622)
			(layers "F.Cu" "F.Mask" "F.Paste")
			(net "GND")
		)
		(pad "P13" smd rect
			(at -13.335 -1.82499 270)
			(size 0.6096 2.3622)
			(layers "F.Cu" "F.Mask" "F.Paste")
			(net "12V_PRE_1")
		)
		(pad "P14" smd rect
			(at -14.605 -1.82499 270)
			(size 0.6096 2.3622)
			(layers "F.Cu" "F.Mask" "F.Paste")
			(net "P12V_HDD1")
		)
		(pad "P15" smd rect
			(at -15.875 -1.82499 270)
			(size 0.6096 2.3622)
			(layers "F.Cu" "F.Mask" "F.Paste")
			(net "P12V_HDD1")
		)
		(pad "S1" smd rect
			(at 15.875 -1.82499 270)
			(size 0.6096 2.3622)
			(layers "F.Cu" "F.Mask" "F.Paste")
			(net "GND")
		)
		(pad "S2" smd rect
			(at 14.605 -1.82499 270)
			(size 0.6096 2.3622)
			(layers "F.Cu" "F.Mask" "F.Paste")
			(net "SAS_HDD_RX_P1")
		)
		(pad "S3" smd rect
			(at 13.335 -1.82499 270)
			(size 0.6096 2.3622)
			(layers "F.Cu" "F.Mask" "F.Paste")
			(net "SAS_HDD_RX_N1")
		)
		(pad "S4" smd rect
			(at 12.065 -1.82499 270)
			(size 0.6096 2.3622)
			(layers "F.Cu" "F.Mask" "F.Paste")
			(net "GND")
		)
		(pad "S5" smd rect
			(at 10.795 -1.82499 270)
			(size 0.6096 2.3622)
			(layers "F.Cu" "F.Mask" "F.Paste")
			(net "PHY_DRV_B_TO_SCC_B_1_DN")
		)
		(pad "S6" smd rect
			(at 9.525 -1.82499 270)
			(size 0.6096 2.3622)
			(layers "F.Cu" "F.Mask" "F.Paste")
			(net "PHY_DRV_B_TO_SCC_B_1_DP")
		)
		(pad "S7" smd rect
			(at 8.255 -1.82499 270)
			(size 0.6096 2.3622)
			(layers "F.Cu" "F.Mask" "F.Paste")
			(net "GND")
		)
		(pad "S8" smd rect
			(at 7.480046 2.845054 270)
			(size 0.508 2.3622)
			(layers "F.Cu" "F.Mask" "F.Paste")
			(net "GND")
		)
		(pad "S9" smd rect
			(at 6.679946 2.845054 270)
			(size 0.508 2.3622)
			(layers "F.Cu" "F.Mask" "F.Paste")
			(net "Net_442")
		)
		(pad "S10" smd rect
			(at 5.8801 2.845054 270)
			(size 0.508 2.3622)
			(layers "F.Cu" "F.Mask" "F.Paste")
			(net "Net_334")
		)
		(pad "S11" smd rect
			(at 5.08 2.845054 270)
			(size 0.508 2.3622)
			(layers "F.Cu" "F.Mask" "F.Paste")
			(net "GND")
		)
		(pad "S12" smd rect
			(at 4.2799 2.845054 270)
			(size 0.508 2.3622)
			(layers "F.Cu" "F.Mask" "F.Paste")
			(net "Net_370")
		)
		(pad "S13" smd rect
			(at 3.480054 2.845054 270)
			(size 0.508 2.3622)
			(layers "F.Cu" "F.Mask" "F.Paste")
			(net "Net_406")
		)
		(pad "S14" smd rect
			(at 2.679954 2.845054 270)
			(size 0.508 2.3622)
			(layers "F.Cu" "F.Mask" "F.Paste")
			(net "GND")
		)
		(zone
			(layer "F.Cu")
			(hatch none 0.5)
			(connect_pads
				(clearance 0)
			)
			(min_thickness 0.25)
			(keepout
				(tracks not_allowed)
				(vias allowed)
				(pads allowed)
				(copperpour not_allowed)
				(footprints allowed)
			)
			(placement
				(enabled no)
				(sheetname "")
			)
			(fill
				(thermal_gap 0.5)
				(thermal_bridge_width 0.5)
				(island_removal_mode 0)
			)
			(polygon
				(pts
					(xy 63.407544 -275.648674) (xy 56.333644 -275.648674) (xy 56.333644 -282.582874) (xy 57.438544 -282.582874)
					(xy 57.438544 -278.468074) (xy 62.061344 -278.468074) (xy 62.061344 -282.582874) (xy 63.407544 -282.582874)
				)
			)
		)
		(zone
			(layer "F.Cu")
			(hatch none 0.5)
			(connect_pads
				(clearance 0)
			)
			(min_thickness 0.25)
			(keepout
				(tracks allowed)
				(vias not_allowed)
				(pads allowed)
				(copperpour not_allowed)
				(footprints allowed)
			)
			(placement
				(enabled no)
				(sheetname "")
			)
			(fill
				(thermal_gap 0.5)
				(thermal_bridge_width 0.5)
				(island_removal_mode 0)
			)
			(polygon
				(pts
					(xy 63.407544 -275.648674) (xy 56.333644 -275.648674) (xy 56.333644 -282.582874) (xy 57.438544 -282.582874)
					(xy 57.438544 -278.468074) (xy 62.061344 -278.468074) (xy 62.061344 -282.582874) (xy 63.407544 -282.582874)
				)
			)
		)
		(zone
			(layer "F.Cu")
			(hatch none 0.5)
			(connect_pads
				(clearance 0)
			)
			(min_thickness 0.25)
			(keepout
				(tracks allowed)
				(vias not_allowed)
				(pads allowed)
				(copperpour not_allowed)
				(footprints allowed)
			)
			(placement
				(enabled no)
				(sheetname "")
			)
			(fill
				(thermal_gap 0.5)
				(thermal_bridge_width 0.5)
				(island_removal_mode 0)
			)
			(polygon
				(pts
					(xy 63.407544 -242.171474) (xy 56.333644 -242.171474) (xy 56.333644 -235.237274) (xy 57.438544 -235.237274)
					(xy 57.438544 -239.352074) (xy 62.061344 -239.352074) (xy 62.061344 -235.237274) (xy 63.407544 -235.237274)
				)
			)
		)
		(zone
			(layer "F.Cu")
			(hatch none 0.5)
			(connect_pads
				(clearance 0)
			)
			(min_thickness 0.25)
			(keepout
				(tracks not_allowed)
				(vias allowed)
				(pads allowed)
				(copperpour not_allowed)
				(footprints allowed)
			)
			(placement
				(enabled no)
				(sheetname "")
			)
			(fill
				(thermal_gap 0.5)
				(thermal_bridge_width 0.5)
				(island_removal_mode 0)
			)
			(polygon
				(pts
					(xy 63.407544 -242.171474) (xy 56.333644 -242.171474) (xy 56.333644 -235.237274) (xy 57.438544 -235.237274)
					(xy 57.438544 -239.352074) (xy 62.061344 -239.352074) (xy 62.061344 -235.237274) (xy 63.407544 -235.237274)
				)
			)
		)
		(zone
			(layers "F.Cu" "B.Cu" "In1.Cu" "In2.Cu" "In3.Cu" "In4.Cu" "In5.Cu" "In6.Cu")
			(hatch none 0.5)
			(connect_pads
				(clearance 0)
			)
			(min_thickness 0.25)
			(keepout
				(tracks not_allowed)
				(vias allowed)
				(pads allowed)
				(copperpour not_allowed)
				(footprints allowed)
			)
			(placement
				(enabled no)
				(sheetname "")
			)
			(fill
				(thermal_gap 0.5)
				(thermal_bridge_width 0.5)
				(island_removal_mode 0)
			)
			(polygon
				(pts
					(arc
						(start 60.524644 -240.03508)
						(mid 58.975244 -240.03508)
						(end 60.524644 -240.03508)
					)
				)
			)
		)
		(zone
			(layers "F.Cu" "B.Cu" "In1.Cu" "In2.Cu" "In3.Cu" "In4.Cu" "In5.Cu" "In6.Cu")
			(hatch none 0.5)
			(connect_pads
				(clearance 0)
			)
			(min_thickness 0.25)
			(keepout
				(tracks not_allowed)
				(vias allowed)
				(pads allowed)
				(copperpour not_allowed)
				(footprints allowed)
			)
			(placement
				(enabled no)
				(sheetname "")
			)
			(fill
				(thermal_gap 0.5)
				(thermal_bridge_width 0.5)
				(island_removal_mode 0)
			)
			(polygon
				(pts
					(arc
						(start 60.727844 -277.785068)
						(mid 58.772044 -277.785068)
						(end 60.727844 -277.785068)
					)
				)
			)
		)
	)
	(footprint ""
		(layer "F.Cu")
		(at 464.0834 -99.3902)
		(property "Reference" "R459"
			(at 0 0 0)
			(layer "F.SilkS")
			(hide yes)
			(effects
				(font
					(size 1.27 1.27)
				)
			)
		)
		(property "Value" "130R3F-GP"
			(at -0.0254 -2.5146 0)
			(unlocked yes)
			(layer "F.Fab")
			(hide yes)
			(effects
				(font
					(size 1.016 1.016)
					(thickness 0.1524)
				)
			)
		)
		(property "Device Type" "R603H22"
			(at -0.0254 -4.0386 0)
			(unlocked yes)
			(layer "F.Fab")
			(hide yes)
			(effects
				(font
					(size 1.016 1.016)
					(thickness 0.1524)
				)
			)
		)
		(duplicate_pad_numbers_are_jumpers no)
		(fp_line
			(start -0.4826 0)
			(end -0.2032 0)
			(stroke
				(width 0.2032)
				(type default)
			)
			(layer "F.SilkS")
		)
		(fp_line
			(start 0.2032 0)
			(end 0.4826 0)
			(stroke
				(width 0.2032)
				(type default)
			)
			(layer "F.SilkS")
		)
		(fp_rect
			(start -0.5842 1.3335)
			(end 0.5842 -1.3335)
			(stroke
				(width 0)
				(type default)
			)
			(fill no)
			(layer "F.CrtYd")
		)
		(fp_rect
			(start -0.5842 1.3335)
			(end 0.5842 -1.3335)
			(stroke
				(width 0)
				(type default)
			)
			(fill no)
			(layer "F.Fab")
		)
		(pad "1" smd custom
			(at 0 -0.762)
			(size 0.2159 0.2159)
			(layers "F.Cu" "F.Mask" "F.Paste")
			(net "P5V_B_4")
			(options
				(clearance outline)
				(anchor circle)
			)
			(primitives
				(gr_poly
					(pts
						(arc
							(start -0.3302 -0.4318)
							(mid -0.402042 -0.402042)
							(end -0.4318 -0.3302)
						)
						(arc
							(start -0.4318 0.3302)
							(mid -0.402042 0.402042)
							(end -0.3302 0.4318)
						)
						(arc
							(start 0.3302 0.4318)
							(mid 0.402042 0.402042)
							(end 0.4318 0.3302)
						)
						(arc
							(start 0.4318 -0.3302)
							(mid 0.402042 -0.402042)
							(end 0.3302 -0.4318)
						)
					)
					(width 0)
					(fill yes)
				)
			)
		)
		(pad "2" smd custom
			(at 0 0.762)
			(size 0.2159 0.2159)
			(layers "F.Cu" "F.Mask" "F.Paste")
			(net "FLT_HDD23")
			(options
				(clearance outline)
				(anchor circle)
			)
			(primitives
				(gr_poly
					(pts
						(arc
							(start -0.3302 -0.4318)
							(mid -0.402042 -0.402042)
							(end -0.4318 -0.3302)
						)
						(arc
							(start -0.4318 0.3302)
							(mid -0.402042 0.402042)
							(end -0.3302 0.4318)
						)
						(arc
							(start 0.3302 0.4318)
							(mid 0.402042 0.402042)
							(end 0.4318 0.3302)
						)
						(arc
							(start 0.4318 -0.3302)
							(mid 0.402042 -0.402042)
							(end 0.3302 -0.4318)
						)
					)
					(width 0)
					(fill yes)
				)
			)
		)
	)
	(footprint ""
		(layer "F.Cu")
		(at 428.2694 -155.575 -90)
		(property "Reference" "R554"
			(at 0 0 270)
			(layer "F.SilkS")
			(hide yes)
			(effects
				(font
					(size 1.27 1.27)
				)
			)
		)
		(property "Value" "2R6F-GP"
			(at -0.0508 -4.8514 270)
			(unlocked yes)
			(layer "F.Fab")
			(hide yes)
			(effects
				(font
					(size 1.016 1.016)
					(thickness 0.1524)
				)
			)
		)
		(property "Device Type" "R1206H26"
			(at 0 -6.3754 270)
			(unlocked yes)
			(layer "F.Fab")
			(hide yes)
			(effects
				(font
					(size 1.016 1.016)
					(thickness 0.1524)
				)
			)
		)
		(duplicate_pad_numbers_are_jumpers no)
		(fp_line
			(start -1.016 2.2352)
			(end -1.016 -2.2352)
			(stroke
				(width 0.1524)
				(type default)
			)
			(layer "F.SilkS")
		)
		(fp_line
			(start 1.016 2.2352)
			(end -1.016 2.2352)
			(stroke
				(width 0.1524)
				(type default)
			)
			(layer "F.SilkS")
		)
		(fp_line
			(start -1.016 -2.2352)
			(end 1.016 -2.2352)
			(stroke
				(width 0.1524)
				(type default)
			)
			(layer "F.SilkS")
		)
		(fp_line
			(start 1.016 -2.2352)
			(end 1.016 2.2352)
			(stroke
				(width 0.1524)
				(type default)
			)
			(layer "F.SilkS")
		)
		(fp_rect
			(start -1.0922 2.3114)
			(end 1.0922 -2.3114)
			(stroke
				(width 0)
				(type default)
			)
			(fill no)
			(layer "F.CrtYd")
		)
		(fp_poly
			(pts
				(xy -1.0922 -2.3114) (xy 1.0922 -2.3114) (xy 1.0922 2.3114) (xy -1.0922 2.3114)
			)
			(stroke
				(width 0)
				(type default)
			)
			(fill no)
			(layer "F.Fab")
		)
		(pad "1" smd rect
			(at 0 -1.397 270)
			(size 1.651 1.27)
			(layers "F.Cu" "F.Mask" "F.Paste")
			(net "P12V_HDD21")
		)
		(pad "2" smd rect
			(at 0 1.397 270)
			(size 1.651 1.27)
			(layers "F.Cu" "F.Mask" "F.Paste")
			(net "12V_PRE_21")
		)
	)
	(footprint ""
		(layer "F.Cu")
		(at 433.324 -257.81 -90)
		(property "Reference" "R313"
			(at 0 0 270)
			(layer "F.SilkS")
			(hide yes)
			(effects
				(font
					(size 1.27 1.27)
				)
			)
		)
		(property "Value" "300KR2F-GP"
			(at 0.064008 -3.993896 270)
			(unlocked yes)
			(layer "F.Fab")
			(hide yes)
			(effects
				(font
					(size 1.016 1.016)
					(thickness 0.1524)
				)
			)
		)
		(property "Device Type" "R402H16"
			(at 0.064008 -5.517896 270)
			(unlocked yes)
			(layer "F.Fab")
			(hide yes)
			(effects
				(font
					(size 1.016 1.016)
					(thickness 0.1524)
				)
			)
		)
		(duplicate_pad_numbers_are_jumpers no)
		(fp_line
			(start -0.508 -0.9398)
			(end -0.508 0.9398)
			(stroke
				(width 0.1524)
				(type default)
			)
			(layer "F.SilkS")
		)
		(fp_line
			(start 0.508 -0.9398)
			(end -0.508 -0.9398)
			(stroke
				(width 0.1524)
				(type default)
			)
			(layer "F.SilkS")
		)
		(fp_rect
			(start -0.508 0.9398)
			(end 0.508 -0.9398)
			(stroke
				(width 0)
				(type default)
			)
			(fill no)
			(layer "F.CrtYd")
		)
		(fp_rect
			(start -0.508 0.9398)
			(end 0.508 -0.9398)
			(stroke
				(width 0)
				(type default)
			)
			(fill no)
			(layer "F.Fab")
		)
		(pad "1" smd custom
			(at 0 -0.4445 270)
			(size 0.1397 0.1397)
			(layers "F.Cu" "F.Mask" "F.Paste")
			(net "SW_HDD_N9")
			(options
				(clearance outline)
				(anchor circle)
			)
			(primitives
				(gr_poly
					(pts
						(arc
							(start -0.1778 -0.2794)
							(mid -0.249642 -0.249642)
							(end -0.2794 -0.1778)
						)
						(arc
							(start -0.2794 0.1778)
							(mid -0.249642 0.249642)
							(end -0.1778 0.2794)
						)
						(arc
							(start 0.1778 0.2794)
							(mid 0.249642 0.249642)
							(end 0.2794 0.1778)
						)
						(arc
							(start 0.2794 -0.1778)
							(mid 0.249642 -0.249642)
							(end 0.1778 -0.2794)
						)
					)
					(width 0)
					(fill yes)
				)
			)
		)
		(pad "2" smd custom
			(at 0 0.4445 270)
			(size 0.1397 0.1397)
			(layers "F.Cu" "F.Mask" "F.Paste")
			(net "P12V_B")
			(options
				(clearance outline)
				(anchor circle)
			)
			(primitives
				(gr_poly
					(pts
						(arc
							(start -0.1778 -0.2794)
							(mid -0.249642 -0.249642)
							(end -0.2794 -0.1778)
						)
						(arc
							(start -0.2794 0.1778)
							(mid -0.249642 0.249642)
							(end -0.1778 0.2794)
						)
						(arc
							(start 0.1778 0.2794)
							(mid 0.249642 0.249642)
							(end 0.2794 0.1778)
						)
						(arc
							(start 0.2794 -0.1778)
							(mid 0.249642 -0.249642)
							(end 0.1778 -0.2794)
						)
					)
					(width 0)
					(fill yes)
				)
			)
		)
	)
	(footprint ""
		(layer "F.Cu")
		(at 220.599 -203.5302)
		(property "Reference" "R44"
			(at 0 0 0)
			(layer "F.SilkS")
			(hide yes)
			(effects
				(font
					(size 1.27 1.27)
				)
			)
		)
		(property "Value" "0R2J-2-GP"
			(at 0.064008 -3.993896 0)
			(unlocked yes)
			(layer "F.Fab")
			(hide yes)
			(effects
				(font
					(size 1.016 1.016)
					(thickness 0.1524)
				)
			)
		)
		(property "Device Type" "R402H16"
			(at 0.064008 -5.517896 0)
			(unlocked yes)
			(layer "F.Fab")
			(hide yes)
			(effects
				(font
					(size 1.016 1.016)
					(thickness 0.1524)
				)
			)
		)
		(duplicate_pad_numbers_are_jumpers no)
		(fp_line
			(start -0.508 -0.9398)
			(end -0.508 0.9398)
			(stroke
				(width 0.1524)
				(type default)
			)
			(layer "F.SilkS")
		)
		(fp_line
			(start 0.508 -0.9398)
			(end -0.508 -0.9398)
			(stroke
				(width 0.1524)
				(type default)
			)
			(layer "F.SilkS")
		)
		(fp_rect
			(start -0.508 0.9398)
			(end 0.508 -0.9398)
			(stroke
				(width 0)
				(type default)
			)
			(fill no)
			(layer "F.CrtYd")
		)
		(fp_rect
			(start -0.508 0.9398)
			(end 0.508 -0.9398)
			(stroke
				(width 0)
				(type default)
			)
			(fill no)
			(layer "F.Fab")
		)
		(pad "1" smd custom
			(at 0 -0.4445)
			(size 0.1397 0.1397)
			(layers "F.Cu" "F.Mask" "F.Paste")
			(net "IO_EXP5_INT_N")
			(options
				(clearance outline)
				(anchor circle)
			)
			(primitives
				(gr_poly
					(pts
						(arc
							(start -0.1778 -0.2794)
							(mid -0.249642 -0.249642)
							(end -0.2794 -0.1778)
						)
						(arc
							(start -0.2794 0.1778)
							(mid -0.249642 0.249642)
							(end -0.1778 0.2794)
						)
						(arc
							(start 0.1778 0.2794)
							(mid 0.249642 0.249642)
							(end 0.2794 0.1778)
						)
						(arc
							(start 0.2794 -0.1778)
							(mid 0.249642 -0.249642)
							(end 0.1778 -0.2794)
						)
					)
					(width 0)
					(fill yes)
				)
			)
		)
		(pad "2" smd custom
			(at 0 0.4445)
			(size 0.1397 0.1397)
			(layers "F.Cu" "F.Mask" "F.Paste")
			(net "DRIVE_INSERT_ALERT_B_N")
			(options
				(clearance outline)
				(anchor circle)
			)
			(primitives
				(gr_poly
					(pts
						(arc
							(start -0.1778 -0.2794)
							(mid -0.249642 -0.249642)
							(end -0.2794 -0.1778)
						)
						(arc
							(start -0.2794 0.1778)
							(mid -0.249642 0.249642)
							(end -0.1778 0.2794)
						)
						(arc
							(start 0.1778 0.2794)
							(mid 0.249642 0.249642)
							(end 0.2794 0.1778)
						)
						(arc
							(start 0.2794 -0.1778)
							(mid 0.249642 -0.249642)
							(end 0.1778 -0.2794)
						)
					)
					(width 0)
					(fill yes)
				)
			)
		)
	)
	(footprint ""
		(layer "F.Cu")
		(at 448.002914 -99.706938 180)
		(property "Reference" "Q241"
			(at 0 0 180)
			(layer "F.SilkS")
			(hide yes)
			(effects
				(font
					(size 1.27 1.27)
				)
			)
		)
		(property "Value" "2N7002K-2-GP"
			(at 0.127 -8.9662 180)
			(unlocked yes)
			(layer "F.Fab")
			(hide yes)
			(effects
				(font
					(size 1.016 1.016)
					(thickness 0.1524)
				)
			)
		)
		(property "Device Type" "SOT23DGS2D4H44"
			(at 0.127 -10.4902 180)
			(unlocked yes)
			(layer "F.Fab")
			(hide yes)
			(effects
				(font
					(size 1.016 1.016)
					(thickness 0.1524)
				)
			)
		)
		(duplicate_pad_numbers_are_jumpers no)
		(fp_line
			(start 1.651 1.778)
			(end 1.651 -1.778)
			(stroke
				(width 0.1524)
				(type default)
			)
			(layer "F.SilkS")
		)
		(fp_line
			(start 1.651 -1.778)
			(end -1.651 -1.778)
			(stroke
				(width 0.1524)
				(type default)
			)
			(layer "F.SilkS")
		)
		(fp_line
			(start -1.651 1.778)
			(end 1.651 1.778)
			(stroke
				(width 0.1524)
				(type default)
			)
			(layer "F.SilkS")
		)
		(fp_line
			(start -1.651 -1.778)
			(end -1.651 1.778)
			(stroke
				(width 0.1524)
				(type default)
			)
			(layer "F.SilkS")
		)
		(fp_poly
			(pts
				(xy -1.778 1.8796) (xy -1.778 -1.8796) (xy 1.778 -1.8796) (xy 1.778 1.8796)
			)
			(stroke
				(width 0)
				(type default)
			)
			(fill no)
			(layer "F.CrtYd")
		)
		(fp_poly
			(pts
				(xy -1.778 1.8796) (xy -1.778 -1.8796) (xy 1.778 -1.8796) (xy 1.778 1.8796)
			)
			(stroke
				(width 0)
				(type default)
			)
			(fill no)
			(layer "F.Fab")
		)
		(pad "D" smd custom
			(at 0 -0.9525 180)
			(size 0.1905 0.1905)
			(layers "F.Cu" "F.Mask" "F.Paste")
			(net "FLT_HDD22_N")
			(options
				(clearance outline)
				(anchor circle)
			)
			(primitives
				(gr_poly
					(pts
						(arc
							(start -0.1778 0.5715)
							(mid -0.321484 0.511984)
							(end -0.381 0.3683)
						)
						(arc
							(start -0.381 -0.3683)
							(mid -0.321484 -0.511984)
							(end -0.1778 -0.5715)
						)
						(arc
							(start 0.1778 -0.5715)
							(mid 0.321484 -0.511984)
							(end 0.381 -0.3683)
						)
						(arc
							(start 0.381 0.3683)
							(mid 0.321484 0.511984)
							(end 0.1778 0.5715)
						)
					)
					(width 0)
					(fill yes)
				)
			)
		)
		(pad "G" smd custom
			(at -0.98425 0.9525 180)
			(size 0.1905 0.1905)
			(layers "F.Cu" "F.Mask" "F.Paste")
			(net "DRIVE_B_22_FLT_LED")
			(options
				(clearance outline)
				(anchor circle)
			)
			(primitives
				(gr_poly
					(pts
						(arc
							(start -0.1778 0.5715)
							(mid -0.321484 0.511984)
							(end -0.381 0.3683)
						)
						(arc
							(start -0.381 -0.3683)
							(mid -0.321484 -0.511984)
							(end -0.1778 -0.5715)
						)
						(arc
							(start 0.1778 -0.5715)
							(mid 0.321484 -0.511984)
							(end 0.381 -0.3683)
						)
						(arc
							(start 0.381 0.3683)
							(mid 0.321484 0.511984)
							(end 0.1778 0.5715)
						)
					)
					(width 0)
					(fill yes)
				)
			)
		)
		(pad "S" smd custom
			(at 0.98425 0.9525 180)
			(size 0.1905 0.1905)
			(layers "F.Cu" "F.Mask" "F.Paste")
			(net "GND")
			(options
				(clearance outline)
				(anchor circle)
			)
			(primitives
				(gr_poly
					(pts
						(arc
							(start -0.1778 0.5715)
							(mid -0.321484 0.511984)
							(end -0.381 0.3683)
						)
						(arc
							(start -0.381 -0.3683)
							(mid -0.321484 -0.511984)
							(end -0.1778 -0.5715)
						)
						(arc
							(start 0.1778 -0.5715)
							(mid 0.321484 -0.511984)
							(end 0.381 -0.3683)
						)
						(arc
							(start 0.381 0.3683)
							(mid 0.321484 0.511984)
							(end 0.1778 0.5715)
						)
					)
					(width 0)
					(fill yes)
				)
			)
		)
	)
	(footprint ""
		(layer "F.Cu")
		(at 109.1184 -214.7062 180)
		(property "Reference" "Q222"
			(at 0 0 180)
			(layer "F.SilkS")
			(hide yes)
			(effects
				(font
					(size 1.27 1.27)
				)
			)
		)
		(property "Value" "2N7002K-2-GP"
			(at 0.127 -8.9662 180)
			(unlocked yes)
			(layer "F.Fab")
			(hide yes)
			(effects
				(font
					(size 1.016 1.016)
					(thickness 0.1524)
				)
			)
		)
		(property "Device Type" "SOT23DGS2D4H44"
			(at 0.127 -10.4902 180)
			(unlocked yes)
			(layer "F.Fab")
			(hide yes)
			(effects
				(font
					(size 1.016 1.016)
					(thickness 0.1524)
				)
			)
		)
		(duplicate_pad_numbers_are_jumpers no)
		(fp_line
			(start 1.651 1.778)
			(end 1.651 -1.778)
			(stroke
				(width 0.1524)
				(type default)
			)
			(layer "F.SilkS")
		)
		(fp_line
			(start 1.651 -1.778)
			(end -1.651 -1.778)
			(stroke
				(width 0.1524)
				(type default)
			)
			(layer "F.SilkS")
		)
		(fp_line
			(start -1.651 1.778)
			(end 1.651 1.778)
			(stroke
				(width 0.1524)
				(type default)
			)
			(layer "F.SilkS")
		)
		(fp_line
			(start -1.651 -1.778)
			(end -1.651 1.778)
			(stroke
				(width 0.1524)
				(type default)
			)
			(layer "F.SilkS")
		)
		(fp_poly
			(pts
				(xy -1.778 1.8796) (xy -1.778 -1.8796) (xy 1.778 -1.8796) (xy 1.778 1.8796)
			)
			(stroke
				(width 0)
				(type default)
			)
			(fill no)
			(layer "F.CrtYd")
		)
		(fp_poly
			(pts
				(xy -1.778 1.8796) (xy -1.778 -1.8796) (xy 1.778 -1.8796) (xy 1.778 1.8796)
			)
			(stroke
				(width 0)
				(type default)
			)
			(fill no)
			(layer "F.Fab")
		)
		(pad "D" smd custom
			(at 0 -0.9525 180)
			(size 0.1905 0.1905)
			(layers "F.Cu" "F.Mask" "F.Paste")
			(net "FLT_HDD3_N")
			(options
				(clearance outline)
				(anchor circle)
			)
			(primitives
				(gr_poly
					(pts
						(arc
							(start -0.1778 0.5715)
							(mid -0.321484 0.511984)
							(end -0.381 0.3683)
						)
						(arc
							(start -0.381 -0.3683)
							(mid -0.321484 -0.511984)
							(end -0.1778 -0.5715)
						)
						(arc
							(start 0.1778 -0.5715)
							(mid 0.321484 -0.511984)
							(end 0.381 -0.3683)
						)
						(arc
							(start 0.381 0.3683)
							(mid 0.321484 0.511984)
							(end 0.1778 0.5715)
						)
					)
					(width 0)
					(fill yes)
				)
			)
		)
		(pad "G" smd custom
			(at -0.98425 0.9525 180)
			(size 0.1905 0.1905)
			(layers "F.Cu" "F.Mask" "F.Paste")
			(net "DRIVE_B_3_FLT_LED")
			(options
				(clearance outline)
				(anchor circle)
			)
			(primitives
				(gr_poly
					(pts
						(arc
							(start -0.1778 0.5715)
							(mid -0.321484 0.511984)
							(end -0.381 0.3683)
						)
						(arc
							(start -0.381 -0.3683)
							(mid -0.321484 -0.511984)
							(end -0.1778 -0.5715)
						)
						(arc
							(start 0.1778 -0.5715)
							(mid 0.321484 -0.511984)
							(end 0.381 -0.3683)
						)
						(arc
							(start 0.381 0.3683)
							(mid 0.321484 0.511984)
							(end 0.1778 0.5715)
						)
					)
					(width 0)
					(fill yes)
				)
			)
		)
		(pad "S" smd custom
			(at 0.98425 0.9525 180)
			(size 0.1905 0.1905)
			(layers "F.Cu" "F.Mask" "F.Paste")
			(net "GND")
			(options
				(clearance outline)
				(anchor circle)
			)
			(primitives
				(gr_poly
					(pts
						(arc
							(start -0.1778 0.5715)
							(mid -0.321484 0.511984)
							(end -0.381 0.3683)
						)
						(arc
							(start -0.381 -0.3683)
							(mid -0.321484 -0.511984)
							(end -0.1778 -0.5715)
						)
						(arc
							(start 0.1778 -0.5715)
							(mid 0.321484 -0.511984)
							(end 0.381 -0.3683)
						)
						(arc
							(start 0.381 0.3683)
							(mid 0.321484 0.511984)
							(end 0.1778 0.5715)
						)
					)
					(width 0)
					(fill yes)
				)
			)
		)
	)
	(footprint ""
		(layer "F.Cu")
		(at 57.371996 -360.934 90)
		(property "Reference" "C520"
			(at 0 0 90)
			(layer "F.SilkS")
			(hide yes)
			(effects
				(font
					(size 1.27 1.27)
				)
			)
		)
		(property "Value" "SC22U25V0MX-2-GP"
			(at -0.00254 -4.78536 90)
			(unlocked yes)
			(layer "F.Fab")
			(hide yes)
			(effects
				(font
					(size 1.016 1.016)
					(thickness 0.1524)
				)
			)
		)
		(property "Device Type" "C1210H111"
			(at -0.00254 -6.38048 90)
			(unlocked yes)
			(layer "F.Fab")
			(hide yes)
			(effects
				(font
					(size 1.016 1.016)
					(thickness 0.1524)
				)
			)
		)
		(duplicate_pad_numbers_are_jumpers no)
		(fp_line
			(start 1.5748 -2.3368)
			(end -1.5748 -2.3368)
			(stroke
				(width 0.1524)
				(type default)
			)
			(layer "F.SilkS")
		)
		(fp_line
			(start -1.5748 -2.3368)
			(end -1.5748 -0.762)
			(stroke
				(width 0.1524)
				(type default)
			)
			(layer "F.SilkS")
		)
		(fp_line
			(start 1.5748 -0.762)
			(end 1.5748 -2.3368)
			(stroke
				(width 0.1524)
				(type default)
			)
			(layer "F.SilkS")
		)
		(fp_line
			(start -1.5748 0.762)
			(end -1.5748 2.3368)
			(stroke
				(width 0.1524)
				(type default)
			)
			(layer "F.SilkS")
		)
		(fp_line
			(start 1.5748 2.3368)
			(end 1.5748 0.762)
			(stroke
				(width 0.1524)
				(type default)
			)
			(layer "F.SilkS")
		)
		(fp_line
			(start -1.5748 2.3368)
			(end 1.5748 2.3368)
			(stroke
				(width 0.1524)
				(type default)
			)
			(layer "F.SilkS")
		)
		(fp_rect
			(start -1.651 2.413)
			(end 1.651 -2.413)
			(stroke
				(width 0)
				(type default)
			)
			(fill no)
			(layer "F.CrtYd")
		)
		(fp_poly
			(pts
				(xy 1.651 2.413) (xy 1.651 -2.413) (xy -1.651 -2.413) (xy -1.651 2.413)
			)
			(stroke
				(width 0)
				(type default)
			)
			(fill no)
			(layer "F.Fab")
		)
		(pad "1" smd rect
			(at 0 -1.4732 90)
			(size 2.794 1.397)
			(layers "F.Cu" "F.Mask" "F.Paste")
			(net "P12V_FAN0")
		)
		(pad "2" smd rect
			(at 0 1.4732 90)
			(size 2.794 1.397)
			(layers "F.Cu" "F.Mask" "F.Paste")
			(net "GND")
		)
	)
	(footprint ""
		(layer "F.Cu")
		(at 170.688 -361.696)
		(property "Reference" "R1004"
			(at 0 0 0)
			(layer "F.SilkS")
			(hide yes)
			(effects
				(font
					(size 1.27 1.27)
				)
			)
		)
		(property "Value" "10KR2J-L-GP"
			(at 0.064008 -3.993896 0)
			(unlocked yes)
			(layer "F.Fab")
			(hide yes)
			(effects
				(font
					(size 1.016 1.016)
					(thickness 0.1524)
				)
			)
		)
		(property "Device Type" "R402H15"
			(at 0.064008 -5.517896 0)
			(unlocked yes)
			(layer "F.Fab")
			(hide yes)
			(effects
				(font
					(size 1.016 1.016)
					(thickness 0.1524)
				)
			)
		)
		(duplicate_pad_numbers_are_jumpers no)
		(fp_line
			(start -0.508 -0.9398)
			(end -0.508 0.9398)
			(stroke
				(width 0.1524)
				(type default)
			)
			(layer "F.SilkS")
		)
		(fp_line
			(start 0.508 -0.9398)
			(end -0.508 -0.9398)
			(stroke
				(width 0.1524)
				(type default)
			)
			(layer "F.SilkS")
		)
		(fp_rect
			(start -0.508 0.9398)
			(end 0.508 -0.9398)
			(stroke
				(width 0)
				(type default)
			)
			(fill no)
			(layer "F.CrtYd")
		)
		(fp_rect
			(start -0.508 0.9398)
			(end 0.508 -0.9398)
			(stroke
				(width 0)
				(type default)
			)
			(fill no)
			(layer "F.Fab")
		)
		(pad "1" smd custom
			(at 0 -0.4445)
			(size 0.1397 0.1397)
			(layers "F.Cu" "F.Mask" "F.Paste")
			(net "MB0_PSET_R")
			(options
				(clearance outline)
				(anchor circle)
			)
			(primitives
				(gr_poly
					(pts
						(arc
							(start -0.1778 -0.2794)
							(mid -0.249642 -0.249642)
							(end -0.2794 -0.1778)
						)
						(arc
							(start -0.2794 0.1778)
							(mid -0.249642 0.249642)
							(end -0.1778 0.2794)
						)
						(arc
							(start 0.1778 0.2794)
							(mid 0.249642 0.249642)
							(end 0.2794 0.1778)
						)
						(arc
							(start 0.2794 -0.1778)
							(mid 0.249642 -0.249642)
							(end 0.1778 -0.2794)
						)
					)
					(width 0)
					(fill yes)
				)
			)
		)
		(pad "2" smd custom
			(at 0 0.4445)
			(size 0.1397 0.1397)
			(layers "F.Cu" "F.Mask" "F.Paste")
			(net "AGND_CURRENT_MON")
			(options
				(clearance outline)
				(anchor circle)
			)
			(primitives
				(gr_poly
					(pts
						(arc
							(start -0.1778 -0.2794)
							(mid -0.249642 -0.249642)
							(end -0.2794 -0.1778)
						)
						(arc
							(start -0.2794 0.1778)
							(mid -0.249642 0.249642)
							(end -0.1778 0.2794)
						)
						(arc
							(start 0.1778 0.2794)
							(mid 0.249642 0.249642)
							(end 0.2794 0.1778)
						)
						(arc
							(start 0.2794 -0.1778)
							(mid 0.249642 -0.249642)
							(end 0.1778 -0.2794)
						)
					)
					(width 0)
					(fill yes)
				)
			)
		)
	)
	(footprint ""
		(layer "F.Cu")
		(at 213.852506 -98.58121 180)
		(property "Reference" "R354"
			(at 0 0 180)
			(layer "F.SilkS")
			(hide yes)
			(effects
				(font
					(size 1.27 1.27)
				)
			)
		)
		(property "Value" "0R2J-2-GP"
			(at 0.064008 -3.993896 180)
			(unlocked yes)
			(layer "F.Fab")
			(hide yes)
			(effects
				(font
					(size 1.016 1.016)
					(thickness 0.1524)
				)
			)
		)
		(property "Device Type" "R402H16"
			(at 0.064008 -5.517896 180)
			(unlocked yes)
			(layer "F.Fab")
			(hide yes)
			(effects
				(font
					(size 1.016 1.016)
					(thickness 0.1524)
				)
			)
		)
		(duplicate_pad_numbers_are_jumpers no)
		(fp_line
			(start 0.508 -0.9398)
			(end -0.508 -0.9398)
			(stroke
				(width 0.1524)
				(type default)
			)
			(layer "F.SilkS")
		)
		(fp_line
			(start -0.508 -0.9398)
			(end -0.508 0.9398)
			(stroke
				(width 0.1524)
				(type default)
			)
			(layer "F.SilkS")
		)
		(fp_rect
			(start -0.508 0.9398)
			(end 0.508 -0.9398)
			(stroke
				(width 0)
				(type default)
			)
			(fill no)
			(layer "F.CrtYd")
		)
		(fp_rect
			(start -0.508 0.9398)
			(end 0.508 -0.9398)
			(stroke
				(width 0)
				(type default)
			)
			(fill no)
			(layer "F.Fab")
		)
		(pad "1" smd custom
			(at 0 -0.4445 180)
			(size 0.1397 0.1397)
			(layers "F.Cu" "F.Mask" "F.Paste")
			(net "I2C_CLIP_A_SDA")
			(options
				(clearance outline)
				(anchor circle)
			)
			(primitives
				(gr_poly
					(pts
						(arc
							(start -0.1778 -0.2794)
							(mid -0.249642 -0.249642)
							(end -0.2794 -0.1778)
						)
						(arc
							(start -0.2794 0.1778)
							(mid -0.249642 0.249642)
							(end -0.1778 0.2794)
						)
						(arc
							(start 0.1778 0.2794)
							(mid 0.249642 0.249642)
							(end 0.2794 0.1778)
						)
						(arc
							(start 0.2794 -0.1778)
							(mid 0.249642 -0.249642)
							(end 0.1778 -0.2794)
						)
					)
					(width 0)
					(fill yes)
				)
			)
		)
		(pad "2" smd custom
			(at 0 0.4445 180)
			(size 0.1397 0.1397)
			(layers "F.Cu" "F.Mask" "F.Paste")
			(net "I2C_CLIP_B_SDA")
			(options
				(clearance outline)
				(anchor circle)
			)
			(primitives
				(gr_poly
					(pts
						(arc
							(start -0.1778 -0.2794)
							(mid -0.249642 -0.249642)
							(end -0.2794 -0.1778)
						)
						(arc
							(start -0.2794 0.1778)
							(mid -0.249642 0.249642)
							(end -0.1778 0.2794)
						)
						(arc
							(start 0.1778 0.2794)
							(mid 0.249642 0.249642)
							(end 0.2794 0.1778)
						)
						(arc
							(start 0.2794 -0.1778)
							(mid 0.249642 -0.249642)
							(end 0.1778 -0.2794)
						)
					)
					(width 0)
					(fill yes)
				)
			)
		)
	)
	(footprint ""
		(layer "F.Cu")
		(at 398.018 -138.938 -90)
		(property "Reference" "Q93"
			(at 0 0 270)
			(layer "F.SilkS")
			(hide yes)
			(effects
				(font
					(size 1.27 1.27)
				)
			)
		)
		(property "Value" "AO4406AL-GP"
			(at -3.707384 -1.5367 270)
			(unlocked yes)
			(layer "F.Fab")
			(hide yes)
			(effects
				(font
					(size 1.016 1.016)
					(thickness 0.1524)
				)
			)
		)
		(property "Device Type" "SOIC8H69"
			(at -3.707384 -3.0607 270)
			(unlocked yes)
			(layer "F.Fab")
			(hide yes)
			(effects
				(font
					(size 1.016 1.016)
					(thickness 0.1524)
				)
			)
		)
		(duplicate_pad_numbers_are_jumpers no)
		(fp_line
			(start -2.6289 3.4417)
			(end -2.6289 1.4732)
			(stroke
				(width 0.381)
				(type default)
			)
			(layer "F.SilkS")
		)
		(fp_line
			(start -2.7432 1.4224)
			(end -2.6416 1.4224)
			(stroke
				(width 0.1524)
				(type default)
			)
			(layer "F.SilkS")
		)
		(fp_line
			(start -2.7432 1.4224)
			(end 2.1336 1.4224)
			(stroke
				(width 0.1524)
				(type default)
			)
			(layer "F.SilkS")
		)
		(fp_line
			(start 2.1336 1.4224)
			(end 2.1336 -1.4224)
			(stroke
				(width 0.1524)
				(type default)
			)
			(layer "F.SilkS")
		)
		(fp_line
			(start -2.1844 -0.0508)
			(end -2.7178 0.508)
			(stroke
				(width 0.1524)
				(type default)
			)
			(layer "F.SilkS")
		)
		(fp_line
			(start -2.7178 -0.508)
			(end -2.1844 -0.0508)
			(stroke
				(width 0.1524)
				(type default)
			)
			(layer "F.SilkS")
		)
		(fp_line
			(start -2.7432 -1.4224)
			(end -2.7432 1.4224)
			(stroke
				(width 0.1524)
				(type default)
			)
			(layer "F.SilkS")
		)
		(fp_line
			(start 2.1336 -1.4224)
			(end -2.7432 -1.4224)
			(stroke
				(width 0.1524)
				(type default)
			)
			(layer "F.SilkS")
		)
		(fp_poly
			(pts
				(xy -2.2098 -1.4224) (xy -2.2098 1.4224) (xy 2.2098 1.4224) (xy 2.2098 -1.4224)
			)
			(stroke
				(width 0)
				(type default)
			)
			(fill yes)
			(layer "F.SilkS")
		)
		(fp_rect
			(start -2.450084 2.999994)
			(end 2.450084 -2.999994)
			(stroke
				(width 0)
				(type default)
			)
			(fill no)
			(layer "F.CrtYd")
		)
		(fp_poly
			(pts
				(xy -2.8194 3.6322) (xy -2.8194 -3.6322) (xy 2.8194 -3.6322) (xy 2.8194 1.18364) (xy 2.450084 1.18364)
				(xy 2.450084 -2.999994) (xy -2.450084 -2.999994) (xy -2.450084 2.999994) (xy 2.450084 2.999994)
				(xy 2.450084 1.18618) (xy 2.8194 1.18618) (xy 2.8194 3.6322)
			)
			(stroke
				(width 0)
				(type default)
			)
			(fill no)
			(layer "F.CrtYd")
		)
		(fp_rect
			(start -2.8194 3.6322)
			(end 2.8194 -3.6322)
			(stroke
				(width 0)
				(type default)
			)
			(fill no)
			(layer "F.Fab")
		)
		(pad "1" smd rect
			(at -1.905 2.54 270)
			(size 0.635 1.651)
			(layers "F.Cu" "F.Mask" "F.Paste")
			(net "P5V_HDD20")
		)
		(pad "2" smd rect
			(at -0.635 2.54 270)
			(size 0.635 1.651)
			(layers "F.Cu" "F.Mask" "F.Paste")
			(net "P5V_HDD20")
		)
		(pad "3" smd rect
			(at 0.635 2.54 270)
			(size 0.635 1.651)
			(layers "F.Cu" "F.Mask" "F.Paste")
			(net "P5V_HDD20")
		)
		(pad "4" smd rect
			(at 1.905 2.54 270)
			(size 0.635 1.651)
			(layers "F.Cu" "F.Mask" "F.Paste")
			(net "SW_HDD_P20")
		)
		(pad "5" smd rect
			(at 1.905 -2.54 270)
			(size 0.635 1.651)
			(layers "F.Cu" "F.Mask" "F.Paste")
			(net "P5V_B_3")
		)
		(pad "6" smd rect
			(at 0.635 -2.54 270)
			(size 0.635 1.651)
			(layers "F.Cu" "F.Mask" "F.Paste")
			(net "P5V_B_3")
		)
		(pad "7" smd rect
			(at -0.635 -2.54 270)
			(size 0.635 1.651)
			(layers "F.Cu" "F.Mask" "F.Paste")
			(net "P5V_B_3")
		)
		(pad "8" smd rect
			(at -1.905 -2.54 270)
			(size 0.635 1.651)
			(layers "F.Cu" "F.Mask" "F.Paste")
			(net "P5V_B_3")
		)
	)
	(footprint ""
		(layer "F.Cu")
		(at 338.455 -27.813 -90)
		(property "Reference" "R775"
			(at 0 0 270)
			(layer "F.SilkS")
			(hide yes)
			(effects
				(font
					(size 1.27 1.27)
				)
			)
		)
		(property "Value" "300KR2F-GP"
			(at 0.064008 -3.993896 270)
			(unlocked yes)
			(layer "F.Fab")
			(hide yes)
			(effects
				(font
					(size 1.016 1.016)
					(thickness 0.1524)
				)
			)
		)
		(property "Device Type" "R402H16"
			(at 0.064008 -5.517896 270)
			(unlocked yes)
			(layer "F.Fab")
			(hide yes)
			(effects
				(font
					(size 1.016 1.016)
					(thickness 0.1524)
				)
			)
		)
		(duplicate_pad_numbers_are_jumpers no)
		(fp_line
			(start -0.508 -0.9398)
			(end -0.508 0.9398)
			(stroke
				(width 0.1524)
				(type default)
			)
			(layer "F.SilkS")
		)
		(fp_line
			(start 0.508 -0.9398)
			(end -0.508 -0.9398)
			(stroke
				(width 0.1524)
				(type default)
			)
			(layer "F.SilkS")
		)
		(fp_rect
			(start -0.508 0.9398)
			(end 0.508 -0.9398)
			(stroke
				(width 0)
				(type default)
			)
			(fill no)
			(layer "F.CrtYd")
		)
		(fp_rect
			(start -0.508 0.9398)
			(end 0.508 -0.9398)
			(stroke
				(width 0)
				(type default)
			)
			(fill no)
			(layer "F.Fab")
		)
		(pad "1" smd custom
			(at 0 -0.4445 270)
			(size 0.1397 0.1397)
			(layers "F.Cu" "F.Mask" "F.Paste")
			(net "SW_HDD_N30")
			(options
				(clearance outline)
				(anchor circle)
			)
			(primitives
				(gr_poly
					(pts
						(arc
							(start -0.1778 -0.2794)
							(mid -0.249642 -0.249642)
							(end -0.2794 -0.1778)
						)
						(arc
							(start -0.2794 0.1778)
							(mid -0.249642 0.249642)
							(end -0.1778 0.2794)
						)
						(arc
							(start 0.1778 0.2794)
							(mid 0.249642 0.249642)
							(end 0.2794 0.1778)
						)
						(arc
							(start 0.2794 -0.1778)
							(mid 0.249642 -0.249642)
							(end 0.1778 -0.2794)
						)
					)
					(width 0)
					(fill yes)
				)
			)
		)
		(pad "2" smd custom
			(at 0 0.4445 270)
			(size 0.1397 0.1397)
			(layers "F.Cu" "F.Mask" "F.Paste")
			(net "P12V_B")
			(options
				(clearance outline)
				(anchor circle)
			)
			(primitives
				(gr_poly
					(pts
						(arc
							(start -0.1778 -0.2794)
							(mid -0.249642 -0.249642)
							(end -0.2794 -0.1778)
						)
						(arc
							(start -0.2794 0.1778)
							(mid -0.249642 0.249642)
							(end -0.1778 0.2794)
						)
						(arc
							(start 0.1778 0.2794)
							(mid 0.249642 0.249642)
							(end 0.2794 0.1778)
						)
						(arc
							(start 0.2794 -0.1778)
							(mid 0.249642 -0.249642)
							(end 0.1778 -0.2794)
						)
					)
					(width 0)
					(fill yes)
				)
			)
		)
	)
	(footprint ""
		(layer "F.Cu")
		(at 180.34 -13.0302 -90)
		(property "Reference" "D29"
			(at 0 0 270)
			(layer "F.SilkS")
			(hide yes)
			(effects
				(font
					(size 1.27 1.27)
				)
			)
		)
		(property "Value" "RB551V30-GP"
			(at 0 -6.7818 270)
			(unlocked yes)
			(layer "F.Fab")
			(hide yes)
			(effects
				(font
					(size 1.016 1.016)
					(thickness 0.1524)
				)
			)
		)
		(property "Device Type" "SOD323AKH38"
			(at 0 -8.6868 270)
			(unlocked yes)
			(layer "F.Fab")
			(hide yes)
			(effects
				(font
					(size 1.016 1.016)
					(thickness 0.1524)
				)
			)
		)
		(duplicate_pad_numbers_are_jumpers no)
		(fp_line
			(start -0.889 2.159)
			(end -0.889 -1.9304)
			(stroke
				(width 0.1524)
				(type default)
			)
			(layer "F.SilkS")
		)
		(fp_line
			(start 0.889 2.159)
			(end -0.889 2.159)
			(stroke
				(width 0.1524)
				(type default)
			)
			(layer "F.SilkS")
		)
		(fp_line
			(start 0.762 2.0574)
			(end -0.762 2.0574)
			(stroke
				(width 0.508)
				(type default)
			)
			(layer "F.SilkS")
		)
		(fp_line
			(start -0.889 -1.9304)
			(end 0.889 -1.9304)
			(stroke
				(width 0.1524)
				(type default)
			)
			(layer "F.SilkS")
		)
		(fp_line
			(start 0.889 -1.9304)
			(end 0.889 2.159)
			(stroke
				(width 0.1524)
				(type default)
			)
			(layer "F.SilkS")
		)
		(fp_rect
			(start -1.016 2.3114)
			(end 1.016 -2.0066)
			(stroke
				(width 0)
				(type default)
			)
			(fill no)
			(layer "F.CrtYd")
		)
		(fp_poly
			(pts
				(xy -1.016 -2.0066) (xy 1.016 -2.0066) (xy 1.016 2.3114) (xy -1.016 2.3114)
			)
			(stroke
				(width 0)
				(type default)
			)
			(fill no)
			(layer "F.Fab")
		)
		(pad "A" smd rect
			(at 0 -1.143 270)
			(size 0.5588 1.016)
			(layers "F.Cu" "F.Mask" "F.Paste")
			(net "SW_HDD_R29")
		)
		(pad "K" smd rect
			(at 0 1.143 270)
			(size 0.5588 1.016)
			(layers "F.Cu" "F.Mask" "F.Paste")
			(net "SW_HDD_N29")
		)
	)
	(footprint ""
		(layer "F.Cu")
		(at 469.9 -255.524 90)
		(property "Reference" "C182"
			(at 0 0 90)
			(layer "F.SilkS")
			(hide yes)
			(effects
				(font
					(size 1.27 1.27)
				)
			)
		)
		(property "Value" "SCD033U25V2KX-GP"
			(at 1.1811 -2.7051 90)
			(unlocked yes)
			(layer "F.Fab")
			(hide yes)
			(effects
				(font
					(size 1.016 1.016)
					(thickness 0.1524)
				)
			)
		)
		(property "Device Type" "C402H22"
			(at 1.1811 -4.2291 90)
			(unlocked yes)
			(layer "F.Fab")
			(hide yes)
			(effects
				(font
					(size 1.016 1.016)
					(thickness 0.1524)
				)
			)
		)
		(duplicate_pad_numbers_are_jumpers no)
		(fp_rect
			(start -0.4318 0.9525)
			(end 0.4318 -0.9525)
			(stroke
				(width 0)
				(type default)
			)
			(fill no)
			(layer "F.CrtYd")
		)
		(fp_rect
			(start -0.4318 0.9525)
			(end 0.4318 -0.9525)
			(stroke
				(width 0)
				(type default)
			)
			(fill no)
			(layer "F.Fab")
		)
		(pad "1" smd custom
			(at 0 -0.4445 90)
			(size 0.1524 0.1524)
			(layers "F.Cu" "F.Mask" "F.Paste")
			(net "P12V_B")
			(options
				(clearance outline)
				(anchor circle)
			)
			(primitives
				(gr_poly
					(pts
						(arc
							(start 0.3048 -0.2032)
							(mid 0.275042 -0.275042)
							(end 0.2032 -0.3048)
						)
						(arc
							(start -0.2032 -0.3048)
							(mid -0.275042 -0.275042)
							(end -0.3048 -0.2032)
						)
						(arc
							(start -0.3048 0.2032)
							(mid -0.275042 0.275042)
							(end -0.2032 0.3048)
						)
						(arc
							(start 0.2032 0.3048)
							(mid 0.275042 0.275042)
							(end 0.3048 0.2032)
						)
					)
					(width 0)
					(fill yes)
				)
			)
		)
		(pad "2" smd custom
			(at 0 0.4445 90)
			(size 0.1524 0.1524)
			(layers "F.Cu" "F.Mask" "F.Paste")
			(net "SW_HDD_N11")
			(options
				(clearance outline)
				(anchor circle)
			)
			(primitives
				(gr_poly
					(pts
						(arc
							(start 0.3048 -0.2032)
							(mid 0.275042 -0.275042)
							(end 0.2032 -0.3048)
						)
						(arc
							(start -0.2032 -0.3048)
							(mid -0.275042 -0.275042)
							(end -0.3048 -0.2032)
						)
						(arc
							(start -0.3048 0.2032)
							(mid -0.275042 0.275042)
							(end -0.2032 0.3048)
						)
						(arc
							(start 0.2032 0.3048)
							(mid 0.275042 0.275042)
							(end 0.3048 0.2032)
						)
					)
					(width 0)
					(fill yes)
				)
			)
		)
	)
	(footprint ""
		(layer "F.Cu")
		(at 253.604522 -360.146346 90)
		(property "Reference" "R1045"
			(at 0 0 90)
			(layer "F.SilkS")
			(hide yes)
			(effects
				(font
					(size 1.27 1.27)
				)
			)
		)
		(property "Value" "100KR2F-L1-GP"
			(at 0.064008 -3.993896 90)
			(unlocked yes)
			(layer "F.Fab")
			(hide yes)
			(effects
				(font
					(size 1.016 1.016)
					(thickness 0.1524)
				)
			)
		)
		(property "Device Type" "R402H16"
			(at 0.064008 -5.517896 90)
			(unlocked yes)
			(layer "F.Fab")
			(hide yes)
			(effects
				(font
					(size 1.016 1.016)
					(thickness 0.1524)
				)
			)
		)
		(duplicate_pad_numbers_are_jumpers no)
		(fp_line
			(start 0.508 -0.9398)
			(end -0.508 -0.9398)
			(stroke
				(width 0.1524)
				(type default)
			)
			(layer "F.SilkS")
		)
		(fp_line
			(start -0.508 -0.9398)
			(end -0.508 0.9398)
			(stroke
				(width 0.1524)
				(type default)
			)
			(layer "F.SilkS")
		)
		(fp_rect
			(start -0.508 0.9398)
			(end 0.508 -0.9398)
			(stroke
				(width 0)
				(type default)
			)
			(fill no)
			(layer "F.CrtYd")
		)
		(fp_rect
			(start -0.508 0.9398)
			(end 0.508 -0.9398)
			(stroke
				(width 0)
				(type default)
			)
			(fill no)
			(layer "F.Fab")
		)
		(pad "1" smd custom
			(at 0 -0.4445 90)
			(size 0.1397 0.1397)
			(layers "F.Cu" "F.Mask" "F.Paste")
			(net "MB3_VCAP_R")
			(options
				(clearance outline)
				(anchor circle)
			)
			(primitives
				(gr_poly
					(pts
						(arc
							(start -0.1778 -0.2794)
							(mid -0.249642 -0.249642)
							(end -0.2794 -0.1778)
						)
						(arc
							(start -0.2794 0.1778)
							(mid -0.249642 0.249642)
							(end -0.1778 0.2794)
						)
						(arc
							(start 0.1778 0.2794)
							(mid 0.249642 0.249642)
							(end 0.2794 0.1778)
						)
						(arc
							(start 0.2794 -0.1778)
							(mid 0.249642 -0.249642)
							(end 0.1778 -0.2794)
						)
					)
					(width 0)
					(fill yes)
				)
			)
		)
		(pad "2" smd custom
			(at 0 0.4445 90)
			(size 0.1397 0.1397)
			(layers "F.Cu" "F.Mask" "F.Paste")
			(net "MB3_ISTART_R")
			(options
				(clearance outline)
				(anchor circle)
			)
			(primitives
				(gr_poly
					(pts
						(arc
							(start -0.1778 -0.2794)
							(mid -0.249642 -0.249642)
							(end -0.2794 -0.1778)
						)
						(arc
							(start -0.2794 0.1778)
							(mid -0.249642 0.249642)
							(end -0.1778 0.2794)
						)
						(arc
							(start 0.1778 0.2794)
							(mid 0.249642 0.249642)
							(end 0.2794 0.1778)
						)
						(arc
							(start 0.2794 -0.1778)
							(mid 0.249642 -0.249642)
							(end 0.1778 -0.2794)
						)
					)
					(width 0)
					(fill yes)
				)
			)
		)
	)
	(footprint ""
		(layer "F.Cu")
		(at 396.621 -160.02 180)
		(property "Reference" "C295"
			(at 0 0 180)
			(layer "F.SilkS")
			(hide yes)
			(effects
				(font
					(size 1.27 1.27)
				)
			)
		)
		(property "Value" "SC4D7U25V5KX-1-GP"
			(at -0.0762 -6.1214 180)
			(unlocked yes)
			(layer "F.Fab")
			(hide yes)
			(effects
				(font
					(size 1.016 1.016)
					(thickness 0.1524)
				)
			)
		)
		(property "Device Type" "C805H58"
			(at -0.0762 -8.1534 180)
			(unlocked yes)
			(layer "F.Fab")
			(hide yes)
			(effects
				(font
					(size 1.016 1.016)
					(thickness 0.1524)
				)
			)
		)
		(duplicate_pad_numbers_are_jumpers no)
		(fp_line
			(start 0.635 0)
			(end -0.635 0)
			(stroke
				(width 0.508)
				(type default)
			)
			(layer "F.SilkS")
		)
		(fp_rect
			(start -0.9652 1.778)
			(end 0.9652 -1.778)
			(stroke
				(width 0)
				(type default)
			)
			(fill no)
			(layer "F.CrtYd")
		)
		(fp_poly
			(pts
				(xy -0.9652 -1.778) (xy 0.9652 -1.778) (xy 0.9652 1.778) (xy -0.9652 1.778)
			)
			(stroke
				(width 0)
				(type default)
			)
			(fill no)
			(layer "F.Fab")
		)
		(pad "1" smd rect
			(at 0 -0.9652 180)
			(size 1.397 1.143)
			(layers "F.Cu" "F.Mask" "F.Paste")
			(net "P12V_HDD20")
		)
		(pad "2" smd rect
			(at 0 0.9652 180)
			(size 1.397 1.143)
			(layers "F.Cu" "F.Mask" "F.Paste")
			(net "GND")
		)
	)
	(footprint ""
		(layer "F.Cu")
		(at 416.284664 -244.660674 -90)
		(property "Reference" "C146"
			(at 0 0 270)
			(layer "F.SilkS")
			(hide yes)
			(effects
				(font
					(size 1.27 1.27)
				)
			)
		)
		(property "Value" "SCD01U16V1KX-GP"
			(at -2.8321 -1.7399 270)
			(unlocked yes)
			(layer "F.Fab")
			(hide yes)
			(effects
				(font
					(size 1.016 1.016)
					(thickness 0.1524)
				)
			)
		)
		(property "Device Type" "C0201H13"
			(at -2.8321 -3.2639 270)
			(unlocked yes)
			(layer "F.Fab")
			(hide yes)
			(effects
				(font
					(size 1.016 1.016)
					(thickness 0.1524)
				)
			)
		)
		(duplicate_pad_numbers_are_jumpers no)
		(fp_rect
			(start -0.2794 0.6477)
			(end 0.2794 -0.6477)
			(stroke
				(width 0)
				(type default)
			)
			(fill no)
			(layer "F.CrtYd")
		)
		(fp_rect
			(start -0.2794 0.6477)
			(end 0.2794 -0.6477)
			(stroke
				(width 0)
				(type default)
			)
			(fill no)
			(layer "F.Fab")
		)
		(pad "1" smd custom
			(at 0 -0.2794 270)
			(size 0.0762 0.0762)
			(layers "F.Cu" "F.Mask" "F.Paste")
			(net "SAS_HDD_RX_P9")
			(options
				(clearance outline)
				(anchor circle)
			)
			(primitives
				(gr_poly
					(pts
						(arc
							(start 0.1524 -0.127)
							(mid 0.137521 -0.162921)
							(end 0.1016 -0.1778)
						)
						(arc
							(start -0.1016 -0.1778)
							(mid -0.137521 -0.162921)
							(end -0.1524 -0.127)
						)
						(arc
							(start -0.1524 0.127)
							(mid -0.137521 0.162921)
							(end -0.1016 0.1778)
						)
						(arc
							(start 0.1016 0.1778)
							(mid 0.137521 0.162921)
							(end 0.1524 0.127)
						)
					)
					(width 0)
					(fill yes)
				)
			)
		)
		(pad "2" smd custom
			(at 0 0.2794 270)
			(size 0.0762 0.0762)
			(layers "F.Cu" "F.Mask" "F.Paste")
			(net "PHY_SCC_B_TO_DRV_B_9_DP")
			(options
				(clearance outline)
				(anchor circle)
			)
			(primitives
				(gr_poly
					(pts
						(arc
							(start 0.1524 -0.127)
							(mid 0.137521 -0.162921)
							(end 0.1016 -0.1778)
						)
						(arc
							(start -0.1016 -0.1778)
							(mid -0.137521 -0.162921)
							(end -0.1524 -0.127)
						)
						(arc
							(start -0.1524 0.127)
							(mid -0.137521 0.162921)
							(end -0.1016 0.1778)
						)
						(arc
							(start 0.1016 0.1778)
							(mid 0.137521 0.162921)
							(end 0.1524 0.127)
						)
					)
					(width 0)
					(fill yes)
				)
			)
		)
	)
	(footprint ""
		(layer "F.Cu")
		(at 457.581 -262.001 -90)
		(property "Reference" "R318"
			(at 0 0 270)
			(layer "F.SilkS")
			(hide yes)
			(effects
				(font
					(size 1.27 1.27)
				)
			)
		)
		(property "Value" "2R6F-GP"
			(at -0.0508 -4.8514 270)
			(unlocked yes)
			(layer "F.Fab")
			(hide yes)
			(effects
				(font
					(size 1.016 1.016)
					(thickness 0.1524)
				)
			)
		)
		(property "Device Type" "R1206H26"
			(at 0 -6.3754 270)
			(unlocked yes)
			(layer "F.Fab")
			(hide yes)
			(effects
				(font
					(size 1.016 1.016)
					(thickness 0.1524)
				)
			)
		)
		(duplicate_pad_numbers_are_jumpers no)
		(fp_line
			(start -1.016 2.2352)
			(end -1.016 -2.2352)
			(stroke
				(width 0.1524)
				(type default)
			)
			(layer "F.SilkS")
		)
		(fp_line
			(start 1.016 2.2352)
			(end -1.016 2.2352)
			(stroke
				(width 0.1524)
				(type default)
			)
			(layer "F.SilkS")
		)
		(fp_line
			(start -1.016 -2.2352)
			(end 1.016 -2.2352)
			(stroke
				(width 0.1524)
				(type default)
			)
			(layer "F.SilkS")
		)
		(fp_line
			(start 1.016 -2.2352)
			(end 1.016 2.2352)
			(stroke
				(width 0.1524)
				(type default)
			)
			(layer "F.SilkS")
		)
		(fp_rect
			(start -1.0922 2.3114)
			(end 1.0922 -2.3114)
			(stroke
				(width 0)
				(type default)
			)
			(fill no)
			(layer "F.CrtYd")
		)
		(fp_poly
			(pts
				(xy -1.0922 -2.3114) (xy 1.0922 -2.3114) (xy 1.0922 2.3114) (xy -1.0922 2.3114)
			)
			(stroke
				(width 0)
				(type default)
			)
			(fill no)
			(layer "F.Fab")
		)
		(pad "1" smd rect
			(at 0 -1.397 270)
			(size 1.651 1.27)
			(layers "F.Cu" "F.Mask" "F.Paste")
			(net "P5V_HDD10")
		)
		(pad "2" smd rect
			(at 0 1.397 270)
			(size 1.651 1.27)
			(layers "F.Cu" "F.Mask" "F.Paste")
			(net "5V_PRE_10")
		)
	)
	(footprint ""
		(layer "F.Cu")
		(at 350.766126 -154.70505)
		(property "Reference" "TP116"
			(at 0 0 0)
			(layer "F.SilkS")
			(hide yes)
			(effects
				(font
					(size 1.27 1.27)
				)
			)
		)
		(property "Value" "*"
			(at -0.0508 -1.6764 0)
			(unlocked yes)
			(layer "F.Fab")
			(hide yes)
			(effects
				(font
					(size 1.016 1.016)
					(thickness 0.1524)
				)
			)
		)
		(property "Device Type" "TPAD32"
			(at -0.0508 -3.2004 0)
			(unlocked yes)
			(layer "F.Fab")
			(hide yes)
			(effects
				(font
					(size 1.016 1.016)
					(thickness 0.1524)
				)
			)
		)
		(duplicate_pad_numbers_are_jumpers no)
		(fp_poly
			(pts
				(arc
					(start 0.4064 0)
					(mid -0.4064 0)
					(end 0.4064 0)
				)
			)
			(stroke
				(width 0)
				(type default)
			)
			(fill no)
			(layer "F.CrtYd")
		)
		(fp_poly
			(pts
				(arc
					(start 0.7112 0)
					(mid -0.7112 0)
					(end 0.7112 0)
				)
			)
			(stroke
				(width 0)
				(type default)
			)
			(fill no)
			(layer "F.Fab")
		)
		(pad "1" smd circle
			(at 0 0)
			(size 0.8128 0.8128)
			(layers "F.Cu" "F.Mask" "F.Paste")
			(net "ACT_HDD_19")
		)
	)
	(footprint ""
		(layer "F.Cu")
		(at 365.125 -270.5862 -90)
		(property "Reference" "R272"
			(at 0 0 270)
			(layer "F.SilkS")
			(hide yes)
			(effects
				(font
					(size 1.27 1.27)
				)
			)
		)
		(property "Value" "2R6F-GP"
			(at -0.0508 -4.8514 270)
			(unlocked yes)
			(layer "F.Fab")
			(hide yes)
			(effects
				(font
					(size 1.016 1.016)
					(thickness 0.1524)
				)
			)
		)
		(property "Device Type" "R1206H26"
			(at 0 -6.3754 270)
			(unlocked yes)
			(layer "F.Fab")
			(hide yes)
			(effects
				(font
					(size 1.016 1.016)
					(thickness 0.1524)
				)
			)
		)
		(duplicate_pad_numbers_are_jumpers no)
		(fp_line
			(start -1.016 2.2352)
			(end -1.016 -2.2352)
			(stroke
				(width 0.1524)
				(type default)
			)
			(layer "F.SilkS")
		)
		(fp_line
			(start 1.016 2.2352)
			(end -1.016 2.2352)
			(stroke
				(width 0.1524)
				(type default)
			)
			(layer "F.SilkS")
		)
		(fp_line
			(start -1.016 -2.2352)
			(end 1.016 -2.2352)
			(stroke
				(width 0.1524)
				(type default)
			)
			(layer "F.SilkS")
		)
		(fp_line
			(start 1.016 -2.2352)
			(end 1.016 2.2352)
			(stroke
				(width 0.1524)
				(type default)
			)
			(layer "F.SilkS")
		)
		(fp_rect
			(start -1.0922 2.3114)
			(end 1.0922 -2.3114)
			(stroke
				(width 0)
				(type default)
			)
			(fill no)
			(layer "F.CrtYd")
		)
		(fp_poly
			(pts
				(xy -1.0922 -2.3114) (xy 1.0922 -2.3114) (xy 1.0922 2.3114) (xy -1.0922 2.3114)
			)
			(stroke
				(width 0)
				(type default)
			)
			(fill no)
			(layer "F.Fab")
		)
		(pad "1" smd rect
			(at 0 -1.397 270)
			(size 1.651 1.27)
			(layers "F.Cu" "F.Mask" "F.Paste")
			(net "P12V_HDD7")
		)
		(pad "2" smd rect
			(at 0 1.397 270)
			(size 1.651 1.27)
			(layers "F.Cu" "F.Mask" "F.Paste")
			(net "12V_PRE_7")
		)
	)
	(footprint ""
		(layer "F.Cu")
		(at 212.97138 -238.61522 180)
		(property "Reference" "C7"
			(at 0 0 180)
			(layer "F.SilkS")
			(hide yes)
			(effects
				(font
					(size 1.27 1.27)
				)
			)
		)
		(property "Value" "SC1U16V3KX-5GP"
			(at 0 -2.8194 180)
			(unlocked yes)
			(layer "F.Fab")
			(hide yes)
			(effects
				(font
					(size 1.016 1.016)
					(thickness 0.1524)
				)
			)
		)
		(property "Device Type" "C603H36"
			(at 0 -4.3434 180)
			(unlocked yes)
			(layer "F.Fab")
			(hide yes)
			(effects
				(font
					(size 1.016 1.016)
					(thickness 0.1524)
				)
			)
		)
		(duplicate_pad_numbers_are_jumpers no)
		(fp_line
			(start 0.508 0)
			(end -0.508 0)
			(stroke
				(width 0.2032)
				(type default)
			)
			(layer "F.SilkS")
		)
		(fp_rect
			(start -0.5842 1.3335)
			(end 0.5842 -1.3335)
			(stroke
				(width 0)
				(type default)
			)
			(fill no)
			(layer "F.CrtYd")
		)
		(fp_rect
			(start -0.5842 1.3335)
			(end 0.5842 -1.3335)
			(stroke
				(width 0)
				(type default)
			)
			(fill no)
			(layer "F.Fab")
		)
		(pad "1" smd custom
			(at 0 -0.762 180)
			(size 0.2159 0.2159)
			(layers "F.Cu" "F.Mask" "F.Paste")
			(net "P3V3_STBY_B")
			(options
				(clearance outline)
				(anchor circle)
			)
			(primitives
				(gr_poly
					(pts
						(arc
							(start -0.3302 -0.4318)
							(mid -0.402042 -0.402042)
							(end -0.4318 -0.3302)
						)
						(arc
							(start -0.4318 0.3302)
							(mid -0.402042 0.402042)
							(end -0.3302 0.4318)
						)
						(arc
							(start 0.3302 0.4318)
							(mid 0.402042 0.402042)
							(end 0.4318 0.3302)
						)
						(arc
							(start 0.4318 -0.3302)
							(mid 0.402042 -0.402042)
							(end 0.3302 -0.4318)
						)
					)
					(width 0)
					(fill yes)
				)
			)
		)
		(pad "2" smd custom
			(at 0 0.762 180)
			(size 0.2159 0.2159)
			(layers "F.Cu" "F.Mask" "F.Paste")
			(net "GND")
			(options
				(clearance outline)
				(anchor circle)
			)
			(primitives
				(gr_poly
					(pts
						(arc
							(start -0.3302 -0.4318)
							(mid -0.402042 -0.402042)
							(end -0.4318 -0.3302)
						)
						(arc
							(start -0.4318 0.3302)
							(mid -0.402042 0.402042)
							(end -0.3302 0.4318)
						)
						(arc
							(start 0.3302 0.4318)
							(mid 0.402042 0.402042)
							(end 0.4318 0.3302)
						)
						(arc
							(start 0.4318 -0.3302)
							(mid 0.402042 -0.402042)
							(end 0.3302 -0.4318)
						)
					)
					(width 0)
					(fill yes)
				)
			)
		)
	)
	(footprint ""
		(layer "F.Cu")
		(at 478.6884 -11.176 180)
		(property "Reference" "R887"
			(at 0 0 180)
			(layer "F.SilkS")
			(hide yes)
			(effects
				(font
					(size 1.27 1.27)
				)
			)
		)
		(property "Value" "4K7R2F-GP"
			(at 0.064008 -3.993896 180)
			(unlocked yes)
			(layer "F.Fab")
			(hide yes)
			(effects
				(font
					(size 1.016 1.016)
					(thickness 0.1524)
				)
			)
		)
		(property "Device Type" "R402H16"
			(at 0.064008 -5.517896 180)
			(unlocked yes)
			(layer "F.Fab")
			(hide yes)
			(effects
				(font
					(size 1.016 1.016)
					(thickness 0.1524)
				)
			)
		)
		(duplicate_pad_numbers_are_jumpers no)
		(fp_line
			(start 0.508 -0.9398)
			(end -0.508 -0.9398)
			(stroke
				(width 0.1524)
				(type default)
			)
			(layer "F.SilkS")
		)
		(fp_line
			(start -0.508 -0.9398)
			(end -0.508 0.9398)
			(stroke
				(width 0.1524)
				(type default)
			)
			(layer "F.SilkS")
		)
		(fp_rect
			(start -0.508 0.9398)
			(end 0.508 -0.9398)
			(stroke
				(width 0)
				(type default)
			)
			(fill no)
			(layer "F.CrtYd")
		)
		(fp_rect
			(start -0.508 0.9398)
			(end 0.508 -0.9398)
			(stroke
				(width 0)
				(type default)
			)
			(fill no)
			(layer "F.Fab")
		)
		(pad "1" smd custom
			(at 0 -0.4445 180)
			(size 0.1397 0.1397)
			(layers "F.Cu" "F.Mask" "F.Paste")
			(net "SW_PWR_R_HDD35")
			(options
				(clearance outline)
				(anchor circle)
			)
			(primitives
				(gr_poly
					(pts
						(arc
							(start -0.1778 -0.2794)
							(mid -0.249642 -0.249642)
							(end -0.2794 -0.1778)
						)
						(arc
							(start -0.2794 0.1778)
							(mid -0.249642 0.249642)
							(end -0.1778 0.2794)
						)
						(arc
							(start 0.1778 0.2794)
							(mid 0.249642 0.249642)
							(end 0.2794 0.1778)
						)
						(arc
							(start 0.2794 -0.1778)
							(mid 0.249642 -0.249642)
							(end 0.1778 -0.2794)
						)
					)
					(width 0)
					(fill yes)
				)
			)
		)
		(pad "2" smd custom
			(at 0 0.4445 180)
			(size 0.1397 0.1397)
			(layers "F.Cu" "F.Mask" "F.Paste")
			(net "GND")
			(options
				(clearance outline)
				(anchor circle)
			)
			(primitives
				(gr_poly
					(pts
						(arc
							(start -0.1778 -0.2794)
							(mid -0.249642 -0.249642)
							(end -0.2794 -0.1778)
						)
						(arc
							(start -0.2794 0.1778)
							(mid -0.249642 0.249642)
							(end -0.1778 0.2794)
						)
						(arc
							(start 0.1778 0.2794)
							(mid 0.249642 0.249642)
							(end 0.2794 0.1778)
						)
						(arc
							(start 0.2794 -0.1778)
							(mid 0.249642 -0.249642)
							(end 0.1778 -0.2794)
						)
					)
					(width 0)
					(fill yes)
				)
			)
		)
	)
	(footprint ""
		(layer "F.Cu")
		(at 37.0332 -11.2776 -90)
		(property "Reference" "R128"
			(at 0 0 270)
			(layer "F.SilkS")
			(hide yes)
			(effects
				(font
					(size 1.27 1.27)
				)
			)
		)
		(property "Value" "0R2J-2-GP"
			(at 0.064008 -3.993896 270)
			(unlocked yes)
			(layer "F.Fab")
			(hide yes)
			(effects
				(font
					(size 1.016 1.016)
					(thickness 0.1524)
				)
			)
		)
		(property "Device Type" "R402H16"
			(at 0.064008 -5.517896 270)
			(unlocked yes)
			(layer "F.Fab")
			(hide yes)
			(effects
				(font
					(size 1.016 1.016)
					(thickness 0.1524)
				)
			)
		)
		(duplicate_pad_numbers_are_jumpers no)
		(fp_line
			(start -0.508 -0.9398)
			(end -0.508 0.9398)
			(stroke
				(width 0.1524)
				(type default)
			)
			(layer "F.SilkS")
		)
		(fp_line
			(start 0.508 -0.9398)
			(end -0.508 -0.9398)
			(stroke
				(width 0.1524)
				(type default)
			)
			(layer "F.SilkS")
		)
		(fp_rect
			(start -0.508 0.9398)
			(end 0.508 -0.9398)
			(stroke
				(width 0)
				(type default)
			)
			(fill no)
			(layer "F.CrtYd")
		)
		(fp_rect
			(start -0.508 0.9398)
			(end 0.508 -0.9398)
			(stroke
				(width 0)
				(type default)
			)
			(fill no)
			(layer "F.Fab")
		)
		(pad "1" smd custom
			(at 0 -0.4445 270)
			(size 0.1397 0.1397)
			(layers "F.Cu" "F.Mask" "F.Paste")
			(net "I2C_DPB_A_SDA_BUF")
			(options
				(clearance outline)
				(anchor circle)
			)
			(primitives
				(gr_poly
					(pts
						(arc
							(start -0.1778 -0.2794)
							(mid -0.249642 -0.249642)
							(end -0.2794 -0.1778)
						)
						(arc
							(start -0.2794 0.1778)
							(mid -0.249642 0.249642)
							(end -0.1778 0.2794)
						)
						(arc
							(start 0.1778 0.2794)
							(mid 0.249642 0.249642)
							(end 0.2794 0.1778)
						)
						(arc
							(start 0.2794 -0.1778)
							(mid 0.249642 -0.249642)
							(end 0.1778 -0.2794)
						)
					)
					(width 0)
					(fill yes)
				)
			)
		)
		(pad "2" smd custom
			(at 0 0.4445 270)
			(size 0.1397 0.1397)
			(layers "F.Cu" "F.Mask" "F.Paste")
			(net "TEMP1_SDA")
			(options
				(clearance outline)
				(anchor circle)
			)
			(primitives
				(gr_poly
					(pts
						(arc
							(start -0.1778 -0.2794)
							(mid -0.249642 -0.249642)
							(end -0.2794 -0.1778)
						)
						(arc
							(start -0.2794 0.1778)
							(mid -0.249642 0.249642)
							(end -0.1778 0.2794)
						)
						(arc
							(start 0.1778 0.2794)
							(mid 0.249642 0.249642)
							(end 0.2794 0.1778)
						)
						(arc
							(start 0.2794 -0.1778)
							(mid 0.249642 -0.249642)
							(end 0.1778 -0.2794)
						)
					)
					(width 0)
					(fill yes)
				)
			)
		)
	)
	(footprint ""
		(layer "F.Cu")
		(at 178.435 -26.289 180)
		(property "Reference" "Q148"
			(at 0 0 180)
			(layer "F.SilkS")
			(hide yes)
			(effects
				(font
					(size 1.27 1.27)
				)
			)
		)
		(property "Value" "AO4406AL-GP"
			(at -3.707384 -1.5367 180)
			(unlocked yes)
			(layer "F.Fab")
			(hide yes)
			(effects
				(font
					(size 1.016 1.016)
					(thickness 0.1524)
				)
			)
		)
		(property "Device Type" "SOIC8H69"
			(at -3.707384 -3.0607 180)
			(unlocked yes)
			(layer "F.Fab")
			(hide yes)
			(effects
				(font
					(size 1.016 1.016)
					(thickness 0.1524)
				)
			)
		)
		(duplicate_pad_numbers_are_jumpers no)
		(fp_line
			(start 2.1336 1.4224)
			(end 2.1336 -1.4224)
			(stroke
				(width 0.1524)
				(type default)
			)
			(layer "F.SilkS")
		)
		(fp_line
			(start 2.1336 -1.4224)
			(end -2.7432 -1.4224)
			(stroke
				(width 0.1524)
				(type default)
			)
			(layer "F.SilkS")
		)
		(fp_line
			(start -2.1844 -0.0508)
			(end -2.7178 0.508)
			(stroke
				(width 0.1524)
				(type default)
			)
			(layer "F.SilkS")
		)
		(fp_line
			(start -2.6289 3.4417)
			(end -2.6289 1.4732)
			(stroke
				(width 0.381)
				(type default)
			)
			(layer "F.SilkS")
		)
		(fp_line
			(start -2.7178 -0.508)
			(end -2.1844 -0.0508)
			(stroke
				(width 0.1524)
				(type default)
			)
			(layer "F.SilkS")
		)
		(fp_line
			(start -2.7432 1.4224)
			(end 2.1336 1.4224)
			(stroke
				(width 0.1524)
				(type default)
			)
			(layer "F.SilkS")
		)
		(fp_line
			(start -2.7432 1.4224)
			(end -2.6416 1.4224)
			(stroke
				(width 0.1524)
				(type default)
			)
			(layer "F.SilkS")
		)
		(fp_line
			(start -2.7432 -1.4224)
			(end -2.7432 1.4224)
			(stroke
				(width 0.1524)
				(type default)
			)
			(layer "F.SilkS")
		)
		(fp_poly
			(pts
				(xy -2.2098 -1.4224) (xy -2.2098 1.4224) (xy 2.2098 1.4224) (xy 2.2098 -1.4224)
			)
			(stroke
				(width 0)
				(type default)
			)
			(fill yes)
			(layer "F.SilkS")
		)
		(fp_rect
			(start -2.450084 2.999994)
			(end 2.450084 -2.999994)
			(stroke
				(width 0)
				(type default)
			)
			(fill no)
			(layer "F.CrtYd")
		)
		(fp_poly
			(pts
				(xy -2.8194 3.6322) (xy -2.8194 -3.6322) (xy 2.8194 -3.6322) (xy 2.8194 1.18364) (xy 2.450084 1.18364)
				(xy 2.450084 -2.999994) (xy -2.450084 -2.999994) (xy -2.450084 2.999994) (xy 2.450084 2.999994)
				(xy 2.450084 1.18618) (xy 2.8194 1.18618) (xy 2.8194 3.6322)
			)
			(stroke
				(width 0)
				(type default)
			)
			(fill no)
			(layer "F.CrtYd")
		)
		(fp_rect
			(start -2.8194 3.6322)
			(end 2.8194 -3.6322)
			(stroke
				(width 0)
				(type default)
			)
			(fill no)
			(layer "F.Fab")
		)
		(pad "1" smd rect
			(at -1.905 2.54 180)
			(size 0.635 1.651)
			(layers "F.Cu" "F.Mask" "F.Paste")
			(net "P5V_HDD29")
		)
		(pad "2" smd rect
			(at -0.635 2.54 180)
			(size 0.635 1.651)
			(layers "F.Cu" "F.Mask" "F.Paste")
			(net "P5V_HDD29")
		)
		(pad "3" smd rect
			(at 0.635 2.54 180)
			(size 0.635 1.651)
			(layers "F.Cu" "F.Mask" "F.Paste")
			(net "P5V_HDD29")
		)
		(pad "4" smd rect
			(at 1.905 2.54 180)
			(size 0.635 1.651)
			(layers "F.Cu" "F.Mask" "F.Paste")
			(net "SW_HDD_P29")
		)
		(pad "5" smd rect
			(at 1.905 -2.54 180)
			(size 0.635 1.651)
			(layers "F.Cu" "F.Mask" "F.Paste")
			(net "P5V_B_2")
		)
		(pad "6" smd rect
			(at 0.635 -2.54 180)
			(size 0.635 1.651)
			(layers "F.Cu" "F.Mask" "F.Paste")
			(net "P5V_B_2")
		)
		(pad "7" smd rect
			(at -0.635 -2.54 180)
			(size 0.635 1.651)
			(layers "F.Cu" "F.Mask" "F.Paste")
			(net "P5V_B_2")
		)
		(pad "8" smd rect
			(at -1.905 -2.54 180)
			(size 0.635 1.651)
			(layers "F.Cu" "F.Mask" "F.Paste")
			(net "P5V_B_2")
		)
	)
	(footprint ""
		(layer "F.Cu")
		(at 251.746766 -139.547854)
		(property "Reference" "R464"
			(at 0 0 0)
			(layer "F.SilkS")
			(hide yes)
			(effects
				(font
					(size 1.27 1.27)
				)
			)
		)
		(property "Value" "0R2J-2-GP"
			(at 0.064008 -3.993896 0)
			(unlocked yes)
			(layer "F.Fab")
			(hide yes)
			(effects
				(font
					(size 1.016 1.016)
					(thickness 0.1524)
				)
			)
		)
		(property "Device Type" "R402H16"
			(at 0.064008 -5.517896 0)
			(unlocked yes)
			(layer "F.Fab")
			(hide yes)
			(effects
				(font
					(size 1.016 1.016)
					(thickness 0.1524)
				)
			)
		)
		(duplicate_pad_numbers_are_jumpers no)
		(fp_line
			(start -0.508 -0.9398)
			(end -0.508 0.9398)
			(stroke
				(width 0.1524)
				(type default)
			)
			(layer "F.SilkS")
		)
		(fp_line
			(start 0.508 -0.9398)
			(end -0.508 -0.9398)
			(stroke
				(width 0.1524)
				(type default)
			)
			(layer "F.SilkS")
		)
		(fp_rect
			(start -0.508 0.9398)
			(end 0.508 -0.9398)
			(stroke
				(width 0)
				(type default)
			)
			(fill no)
			(layer "F.CrtYd")
		)
		(fp_rect
			(start -0.508 0.9398)
			(end 0.508 -0.9398)
			(stroke
				(width 0)
				(type default)
			)
			(fill no)
			(layer "F.Fab")
		)
		(pad "1" smd custom
			(at 0 -0.4445)
			(size 0.1397 0.1397)
			(layers "F.Cu" "F.Mask" "F.Paste")
			(net "I2C_SCC_B_SDA_BUF")
			(options
				(clearance outline)
				(anchor circle)
			)
			(primitives
				(gr_poly
					(pts
						(arc
							(start -0.1778 -0.2794)
							(mid -0.249642 -0.249642)
							(end -0.2794 -0.1778)
						)
						(arc
							(start -0.2794 0.1778)
							(mid -0.249642 0.249642)
							(end -0.1778 0.2794)
						)
						(arc
							(start 0.1778 0.2794)
							(mid 0.249642 0.249642)
							(end 0.2794 0.1778)
						)
						(arc
							(start 0.2794 -0.1778)
							(mid 0.249642 -0.249642)
							(end 0.1778 -0.2794)
						)
					)
					(width 0)
					(fill yes)
				)
			)
		)
		(pad "2" smd custom
			(at 0 0.4445)
			(size 0.1397 0.1397)
			(layers "F.Cu" "F.Mask" "F.Paste")
			(net "I2C_SCC_B_SDA")
			(options
				(clearance outline)
				(anchor circle)
			)
			(primitives
				(gr_poly
					(pts
						(arc
							(start -0.1778 -0.2794)
							(mid -0.249642 -0.249642)
							(end -0.2794 -0.1778)
						)
						(arc
							(start -0.2794 0.1778)
							(mid -0.249642 0.249642)
							(end -0.1778 0.2794)
						)
						(arc
							(start 0.1778 0.2794)
							(mid 0.249642 0.249642)
							(end 0.2794 0.1778)
						)
						(arc
							(start 0.2794 -0.1778)
							(mid 0.249642 -0.249642)
							(end 0.1778 -0.2794)
						)
					)
					(width 0)
					(fill yes)
				)
			)
		)
	)
	(footprint ""
		(layer "F.Cu")
		(at 22.987 -245.872 -90)
		(property "Reference" "R908"
			(at 0 0 270)
			(layer "F.SilkS")
			(hide yes)
			(effects
				(font
					(size 1.27 1.27)
				)
			)
		)
		(property "Value" "0R2J-2-GP"
			(at 0.064008 -3.993896 270)
			(unlocked yes)
			(layer "F.Fab")
			(hide yes)
			(effects
				(font
					(size 1.016 1.016)
					(thickness 0.1524)
				)
			)
		)
		(property "Device Type" "R402H16"
			(at 0.064008 -5.517896 270)
			(unlocked yes)
			(layer "F.Fab")
			(hide yes)
			(effects
				(font
					(size 1.016 1.016)
					(thickness 0.1524)
				)
			)
		)
		(duplicate_pad_numbers_are_jumpers no)
		(fp_line
			(start -0.508 -0.9398)
			(end -0.508 0.9398)
			(stroke
				(width 0.1524)
				(type default)
			)
			(layer "F.SilkS")
		)
		(fp_line
			(start 0.508 -0.9398)
			(end -0.508 -0.9398)
			(stroke
				(width 0.1524)
				(type default)
			)
			(layer "F.SilkS")
		)
		(fp_rect
			(start -0.508 0.9398)
			(end 0.508 -0.9398)
			(stroke
				(width 0)
				(type default)
			)
			(fill no)
			(layer "F.CrtYd")
		)
		(fp_rect
			(start -0.508 0.9398)
			(end 0.508 -0.9398)
			(stroke
				(width 0)
				(type default)
			)
			(fill no)
			(layer "F.Fab")
		)
		(pad "1" smd custom
			(at 0 -0.4445 270)
			(size 0.1397 0.1397)
			(layers "F.Cu" "F.Mask" "F.Paste")
			(net "DRIVE_B_0_PWR")
			(options
				(clearance outline)
				(anchor circle)
			)
			(primitives
				(gr_poly
					(pts
						(arc
							(start -0.1778 -0.2794)
							(mid -0.249642 -0.249642)
							(end -0.2794 -0.1778)
						)
						(arc
							(start -0.2794 0.1778)
							(mid -0.249642 0.249642)
							(end -0.1778 0.2794)
						)
						(arc
							(start 0.1778 0.2794)
							(mid 0.249642 0.249642)
							(end 0.2794 0.1778)
						)
						(arc
							(start 0.2794 -0.1778)
							(mid 0.249642 -0.249642)
							(end 0.1778 -0.2794)
						)
					)
					(width 0)
					(fill yes)
				)
			)
		)
		(pad "2" smd custom
			(at 0 0.4445 270)
			(size 0.1397 0.1397)
			(layers "F.Cu" "F.Mask" "F.Paste")
			(net "SW_PWR_R_HDD0")
			(options
				(clearance outline)
				(anchor circle)
			)
			(primitives
				(gr_poly
					(pts
						(arc
							(start -0.1778 -0.2794)
							(mid -0.249642 -0.249642)
							(end -0.2794 -0.1778)
						)
						(arc
							(start -0.2794 0.1778)
							(mid -0.249642 0.249642)
							(end -0.1778 0.2794)
						)
						(arc
							(start 0.1778 0.2794)
							(mid 0.249642 0.249642)
							(end 0.2794 0.1778)
						)
						(arc
							(start 0.2794 -0.1778)
							(mid 0.249642 -0.249642)
							(end 0.1778 -0.2794)
						)
					)
					(width 0)
					(fill yes)
				)
			)
		)
	)
	(footprint ""
		(layer "F.Cu")
		(at 361.315 -275.336 180)
		(property "Reference" "C128"
			(at 0 0 180)
			(layer "F.SilkS")
			(hide yes)
			(effects
				(font
					(size 1.27 1.27)
				)
			)
		)
		(property "Value" "SC1U25V3KX-GP"
			(at 0 -2.8194 180)
			(unlocked yes)
			(layer "F.Fab")
			(hide yes)
			(effects
				(font
					(size 1.016 1.016)
					(thickness 0.1524)
				)
			)
		)
		(property "Device Type" "C603H36"
			(at 0 -4.3434 180)
			(unlocked yes)
			(layer "F.Fab")
			(hide yes)
			(effects
				(font
					(size 1.016 1.016)
					(thickness 0.1524)
				)
			)
		)
		(duplicate_pad_numbers_are_jumpers no)
		(fp_line
			(start 0.508 0)
			(end -0.508 0)
			(stroke
				(width 0.2032)
				(type default)
			)
			(layer "F.SilkS")
		)
		(fp_rect
			(start -0.5842 1.3335)
			(end 0.5842 -1.3335)
			(stroke
				(width 0)
				(type default)
			)
			(fill no)
			(layer "F.CrtYd")
		)
		(fp_rect
			(start -0.5842 1.3335)
			(end 0.5842 -1.3335)
			(stroke
				(width 0)
				(type default)
			)
			(fill no)
			(layer "F.Fab")
		)
		(pad "1" smd custom
			(at 0 -0.762 180)
			(size 0.2159 0.2159)
			(layers "F.Cu" "F.Mask" "F.Paste")
			(net "P12V_HDD7")
			(options
				(clearance outline)
				(anchor circle)
			)
			(primitives
				(gr_poly
					(pts
						(arc
							(start -0.3302 -0.4318)
							(mid -0.402042 -0.402042)
							(end -0.4318 -0.3302)
						)
						(arc
							(start -0.4318 0.3302)
							(mid -0.402042 0.402042)
							(end -0.3302 0.4318)
						)
						(arc
							(start 0.3302 0.4318)
							(mid 0.402042 0.402042)
							(end 0.4318 0.3302)
						)
						(arc
							(start 0.4318 -0.3302)
							(mid 0.402042 -0.402042)
							(end 0.3302 -0.4318)
						)
					)
					(width 0)
					(fill yes)
				)
			)
		)
		(pad "2" smd custom
			(at 0 0.762 180)
			(size 0.2159 0.2159)
			(layers "F.Cu" "F.Mask" "F.Paste")
			(net "GND")
			(options
				(clearance outline)
				(anchor circle)
			)
			(primitives
				(gr_poly
					(pts
						(arc
							(start -0.3302 -0.4318)
							(mid -0.402042 -0.402042)
							(end -0.4318 -0.3302)
						)
						(arc
							(start -0.4318 0.3302)
							(mid -0.402042 0.402042)
							(end -0.3302 0.4318)
						)
						(arc
							(start 0.3302 0.4318)
							(mid 0.402042 0.402042)
							(end 0.4318 0.3302)
						)
						(arc
							(start 0.4318 -0.3302)
							(mid 0.402042 -0.402042)
							(end 0.3302 -0.4318)
						)
					)
					(width 0)
					(fill yes)
				)
			)
		)
	)
	(footprint ""
		(layer "F.Cu")
		(at 461.296004 -376.0978 180)
		(property "Reference" "Q207"
			(at 0 0 180)
			(layer "F.SilkS")
			(hide yes)
			(effects
				(font
					(size 1.27 1.27)
				)
			)
		)
		(property "Value" "SSM6P39TU-GP"
			(at 0.0508 -11.5824 180)
			(unlocked yes)
			(layer "F.Fab")
			(hide yes)
			(effects
				(font
					(size 1.016 1.016)
					(thickness 0.1524)
				)
			)
		)
		(property "Device Type" "UMT6H30"
			(at 0.0508 -13.1572 180)
			(unlocked yes)
			(layer "F.Fab")
			(hide yes)
			(effects
				(font
					(size 1.016 1.016)
					(thickness 0.1524)
				)
			)
		)
		(duplicate_pad_numbers_are_jumpers no)
		(fp_line
			(start 1.524 0.36449)
			(end -1.27 0.36449)
			(stroke
				(width 0.1524)
				(type default)
			)
			(layer "F.SilkS")
		)
		(fp_line
			(start 1.524 -0.36449)
			(end 1.524 0.36449)
			(stroke
				(width 0.1524)
				(type default)
			)
			(layer "F.SilkS")
		)
		(fp_line
			(start 1.524 -0.36449)
			(end 1.524 -1.82245)
			(stroke
				(width 0.508)
				(type default)
			)
			(layer "F.SilkS")
		)
		(fp_line
			(start 1.524 -0.36449)
			(end 1.45796 -0.36449)
			(stroke
				(width 0.1524)
				(type default)
			)
			(layer "F.SilkS")
		)
		(fp_line
			(start 1.45796 -0.36449)
			(end 1.09347 0)
			(stroke
				(width 0.1524)
				(type default)
			)
			(layer "F.SilkS")
		)
		(fp_line
			(start 1.09347 0)
			(end 1.45796 0.36449)
			(stroke
				(width 0.1524)
				(type default)
			)
			(layer "F.SilkS")
		)
		(fp_line
			(start -1.27 -0.36449)
			(end 1.524 -0.36449)
			(stroke
				(width 0.1524)
				(type default)
			)
			(layer "F.SilkS")
		)
		(fp_line
			(start -1.27 -0.36449)
			(end -1.27 0.36449)
			(stroke
				(width 0.1524)
				(type default)
			)
			(layer "F.SilkS")
		)
		(fp_poly
			(pts
				(xy -0.65024 0.36449) (xy -0.65024 -0.36449) (xy 0.65024 -0.36449) (xy 0.65024 0.36449)
			)
			(stroke
				(width 0)
				(type default)
			)
			(fill yes)
			(layer "F.SilkS")
		)
		(fp_poly
			(pts
				(xy 1.016 -1.0668) (xy 1.016 1.0668) (xy -1.016 1.0668) (xy -1.016 -1.0668)
			)
			(stroke
				(width 0)
				(type default)
			)
			(fill no)
			(layer "F.CrtYd")
		)
		(fp_poly
			(pts
				(xy -1.524 1.905) (xy 1.524 1.905) (xy 1.524 -1.06426) (xy 1.016 -1.06426) (xy 1.016 1.0668) (xy -1.016 1.0668)
				(xy -1.016 -1.0668) (xy 1.524 -1.0668) (xy 1.524 -1.905) (xy -1.524 -1.905)
			)
			(stroke
				(width 0)
				(type default)
			)
			(fill no)
			(layer "F.CrtYd")
		)
		(fp_poly
			(pts
				(xy -1.524 -1.905) (xy -1.524 1.905) (xy 1.524 1.905) (xy 1.524 -1.905)
			)
			(stroke
				(width 0)
				(type default)
			)
			(fill no)
			(layer "F.Fab")
		)
		(pad "1" smd rect
			(at 0.65024 -1.02489 180)
			(size 0.4064 0.8128)
			(layers "F.Cu" "F.Mask" "F.Paste")
			(net "P12V_IN")
		)
		(pad "2" smd rect
			(at 0 -1.02489 180)
			(size 0.4064 0.8128)
			(layers "F.Cu" "F.Mask" "F.Paste")
			(net "FAN_YELLOW_LED3")
		)
		(pad "3" smd rect
			(at -0.65024 -1.02489 180)
			(size 0.4064 0.8128)
			(layers "F.Cu" "F.Mask" "F.Paste")
			(net "FAN_BLUE3")
		)
		(pad "4" smd rect
			(at -0.65024 1.02489 180)
			(size 0.4064 0.8128)
			(layers "F.Cu" "F.Mask" "F.Paste")
			(net "P12V_IN")
		)
		(pad "5" smd rect
			(at 0 1.02489 180)
			(size 0.4064 0.8128)
			(layers "F.Cu" "F.Mask" "F.Paste")
			(net "FAN_BLUE_LED3")
		)
		(pad "6" smd rect
			(at 0.65024 1.02489 180)
			(size 0.4064 0.8128)
			(layers "F.Cu" "F.Mask" "F.Paste")
			(net "FAN_YELLOW_3")
		)
	)
	(footprint ""
		(layer "F.Cu")
		(at 265.938 -362.839 180)
		(property "Reference" "Q5"
			(at 0 0 180)
			(layer "F.SilkS")
			(hide yes)
			(effects
				(font
					(size 1.27 1.27)
				)
			)
		)
		(property "Value" "MMBT3904TT1G-GP"
			(at 0 -9.7282 180)
			(unlocked yes)
			(layer "F.Fab")
			(hide yes)
			(effects
				(font
					(size 1.016 1.016)
					(thickness 0.1524)
				)
			)
		)
		(property "Device Type" "SC75CBE1D6H36"
			(at 0 -11.6332 180)
			(unlocked yes)
			(layer "F.Fab")
			(hide yes)
			(effects
				(font
					(size 1.016 1.016)
					(thickness 0.1524)
				)
			)
		)
		(duplicate_pad_numbers_are_jumpers no)
		(fp_line
			(start 0.9652 1.3716)
			(end 0.9652 -1.3716)
			(stroke
				(width 0.1524)
				(type default)
			)
			(layer "F.SilkS")
		)
		(fp_line
			(start 0.9652 -1.3716)
			(end -0.9652 -1.3716)
			(stroke
				(width 0.1524)
				(type default)
			)
			(layer "F.SilkS")
		)
		(fp_line
			(start -0.9652 1.3716)
			(end 0.9652 1.3716)
			(stroke
				(width 0.1524)
				(type default)
			)
			(layer "F.SilkS")
		)
		(fp_line
			(start -0.9652 -1.3716)
			(end -0.9652 1.3716)
			(stroke
				(width 0.1524)
				(type default)
			)
			(layer "F.SilkS")
		)
		(fp_rect
			(start -1.0414 1.4478)
			(end 1.0414 -1.4478)
			(stroke
				(width 0)
				(type default)
			)
			(fill no)
			(layer "F.CrtYd")
		)
		(fp_poly
			(pts
				(xy -1.0414 -1.4478) (xy 1.0414 -1.4478) (xy 1.0414 1.4478) (xy -1.0414 1.4478)
			)
			(stroke
				(width 0)
				(type default)
			)
			(fill no)
			(layer "F.Fab")
		)
		(pad "B" smd custom
			(at -0.508 0.7112 180)
			(size 0.127 0.127)
			(layers "F.Cu" "F.Mask" "F.Paste")
			(net "VCCP_IN")
			(options
				(clearance outline)
				(anchor circle)
			)
			(primitives
				(gr_poly
					(pts
						(arc
							(start -0.044958 0.4572)
							(mid -0.192463 0.399794)
							(end -0.254 0.254)
						)
						(xy -0.254 -0.254)
						(arc
							(start -0.253746 -0.254)
							(mid -0.192968 -0.398936)
							(end -0.04699 -0.4572)
						)
						(arc
							(start 0.04699 -0.4572)
							(mid 0.192989 -0.398958)
							(end 0.253746 -0.254)
						)
						(xy 0.254 -0.254)
						(arc
							(start 0.254 0.254)
							(mid 0.192404 0.399734)
							(end 0.044958 0.4572)
						)
					)
					(width 0)
					(fill yes)
				)
			)
		)
		(pad "C" smd custom
			(at 0 -0.7112 180)
			(size 0.127 0.127)
			(layers "F.Cu" "F.Mask" "F.Paste")
			(net "P12V_IN")
			(options
				(clearance outline)
				(anchor circle)
			)
			(primitives
				(gr_poly
					(pts
						(arc
							(start -0.044958 0.4572)
							(mid -0.192463 0.399794)
							(end -0.254 0.254)
						)
						(xy -0.254 -0.254)
						(arc
							(start -0.253746 -0.254)
							(mid -0.192968 -0.398936)
							(end -0.04699 -0.4572)
						)
						(arc
							(start 0.04699 -0.4572)
							(mid 0.192989 -0.398958)
							(end 0.253746 -0.254)
						)
						(xy 0.254 -0.254)
						(arc
							(start 0.254 0.254)
							(mid 0.192404 0.399734)
							(end 0.044958 0.4572)
						)
					)
					(width 0)
					(fill yes)
				)
			)
		)
		(pad "E" smd custom
			(at 0.508 0.7112 180)
			(size 0.127 0.127)
			(layers "F.Cu" "F.Mask" "F.Paste")
			(net "P3V3_IN_BIAS")
			(options
				(clearance outline)
				(anchor circle)
			)
			(primitives
				(gr_poly
					(pts
						(arc
							(start -0.044958 0.4572)
							(mid -0.192463 0.399794)
							(end -0.254 0.254)
						)
						(xy -0.254 -0.254)
						(arc
							(start -0.253746 -0.254)
							(mid -0.192968 -0.398936)
							(end -0.04699 -0.4572)
						)
						(arc
							(start 0.04699 -0.4572)
							(mid 0.192989 -0.398958)
							(end 0.253746 -0.254)
						)
						(xy 0.254 -0.254)
						(arc
							(start 0.254 0.254)
							(mid 0.192404 0.399734)
							(end 0.044958 0.4572)
						)
					)
					(width 0)
					(fill yes)
				)
			)
		)
	)
	(footprint ""
		(layer "F.Cu")
		(at 209.775298 -224.651062 90)
		(property "Reference" "R19"
			(at 0 0 90)
			(layer "F.SilkS")
			(hide yes)
			(effects
				(font
					(size 1.27 1.27)
				)
			)
		)
		(property "Value" "4K7R2F-GP"
			(at 0.064008 -3.993896 90)
			(unlocked yes)
			(layer "F.Fab")
			(hide yes)
			(effects
				(font
					(size 1.016 1.016)
					(thickness 0.1524)
				)
			)
		)
		(property "Device Type" "R402H16"
			(at 0.064008 -5.517896 90)
			(unlocked yes)
			(layer "F.Fab")
			(hide yes)
			(effects
				(font
					(size 1.016 1.016)
					(thickness 0.1524)
				)
			)
		)
		(duplicate_pad_numbers_are_jumpers no)
		(fp_line
			(start 0.508 -0.9398)
			(end -0.508 -0.9398)
			(stroke
				(width 0.1524)
				(type default)
			)
			(layer "F.SilkS")
		)
		(fp_line
			(start -0.508 -0.9398)
			(end -0.508 0.9398)
			(stroke
				(width 0.1524)
				(type default)
			)
			(layer "F.SilkS")
		)
		(fp_rect
			(start -0.508 0.9398)
			(end 0.508 -0.9398)
			(stroke
				(width 0)
				(type default)
			)
			(fill no)
			(layer "F.CrtYd")
		)
		(fp_rect
			(start -0.508 0.9398)
			(end 0.508 -0.9398)
			(stroke
				(width 0)
				(type default)
			)
			(fill no)
			(layer "F.Fab")
		)
		(pad "1" smd custom
			(at 0 -0.4445 90)
			(size 0.1397 0.1397)
			(layers "F.Cu" "F.Mask" "F.Paste")
			(net "P3V3_STBY_B")
			(options
				(clearance outline)
				(anchor circle)
			)
			(primitives
				(gr_poly
					(pts
						(arc
							(start -0.1778 -0.2794)
							(mid -0.249642 -0.249642)
							(end -0.2794 -0.1778)
						)
						(arc
							(start -0.2794 0.1778)
							(mid -0.249642 0.249642)
							(end -0.1778 0.2794)
						)
						(arc
							(start 0.1778 0.2794)
							(mid 0.249642 0.249642)
							(end 0.2794 0.1778)
						)
						(arc
							(start 0.2794 -0.1778)
							(mid 0.249642 -0.249642)
							(end 0.1778 -0.2794)
						)
					)
					(width 0)
					(fill yes)
				)
			)
		)
		(pad "2" smd custom
			(at 0 0.4445 90)
			(size 0.1397 0.1397)
			(layers "F.Cu" "F.Mask" "F.Paste")
			(net "IO_EXP1_HDD_FAULT_A2")
			(options
				(clearance outline)
				(anchor circle)
			)
			(primitives
				(gr_poly
					(pts
						(arc
							(start -0.1778 -0.2794)
							(mid -0.249642 -0.249642)
							(end -0.2794 -0.1778)
						)
						(arc
							(start -0.2794 0.1778)
							(mid -0.249642 0.249642)
							(end -0.1778 0.2794)
						)
						(arc
							(start 0.1778 0.2794)
							(mid 0.249642 0.249642)
							(end 0.2794 0.1778)
						)
						(arc
							(start 0.2794 -0.1778)
							(mid 0.249642 -0.249642)
							(end 0.1778 -0.2794)
						)
					)
					(width 0)
					(fill yes)
				)
			)
		)
	)
	(footprint ""
		(layer "F.Cu")
		(at 186.748928 -367.114836)
		(property "Reference" "C711"
			(at 0 0 0)
			(layer "F.SilkS")
			(hide yes)
			(effects
				(font
					(size 1.27 1.27)
				)
			)
		)
		(property "Value" "SCD1U16V2KX-3GP"
			(at 1.1811 -2.7051 0)
			(unlocked yes)
			(layer "F.Fab")
			(hide yes)
			(effects
				(font
					(size 1.016 1.016)
					(thickness 0.1524)
				)
			)
		)
		(property "Device Type" "C402H22"
			(at 1.1811 -4.2291 0)
			(unlocked yes)
			(layer "F.Fab")
			(hide yes)
			(effects
				(font
					(size 1.016 1.016)
					(thickness 0.1524)
				)
			)
		)
		(duplicate_pad_numbers_are_jumpers no)
		(fp_rect
			(start -0.4318 0.9525)
			(end 0.4318 -0.9525)
			(stroke
				(width 0)
				(type default)
			)
			(fill no)
			(layer "F.CrtYd")
		)
		(fp_rect
			(start -0.4318 0.9525)
			(end 0.4318 -0.9525)
			(stroke
				(width 0)
				(type default)
			)
			(fill no)
			(layer "F.Fab")
		)
		(pad "1" smd custom
			(at 0 -0.4445)
			(size 0.1524 0.1524)
			(layers "F.Cu" "F.Mask" "F.Paste")
			(net "P3V3_IN")
			(options
				(clearance outline)
				(anchor circle)
			)
			(primitives
				(gr_poly
					(pts
						(arc
							(start 0.3048 -0.2032)
							(mid 0.275042 -0.275042)
							(end 0.2032 -0.3048)
						)
						(arc
							(start -0.2032 -0.3048)
							(mid -0.275042 -0.275042)
							(end -0.3048 -0.2032)
						)
						(arc
							(start -0.3048 0.2032)
							(mid -0.275042 0.275042)
							(end -0.2032 0.3048)
						)
						(arc
							(start 0.2032 0.3048)
							(mid 0.275042 0.275042)
							(end 0.3048 0.2032)
						)
					)
					(width 0)
					(fill yes)
				)
			)
		)
		(pad "2" smd custom
			(at 0 0.4445)
			(size 0.1524 0.1524)
			(layers "F.Cu" "F.Mask" "F.Paste")
			(net "GND")
			(options
				(clearance outline)
				(anchor circle)
			)
			(primitives
				(gr_poly
					(pts
						(arc
							(start 0.3048 -0.2032)
							(mid 0.275042 -0.275042)
							(end 0.2032 -0.3048)
						)
						(arc
							(start -0.2032 -0.3048)
							(mid -0.275042 -0.275042)
							(end -0.3048 -0.2032)
						)
						(arc
							(start -0.3048 0.2032)
							(mid -0.275042 0.275042)
							(end -0.2032 0.3048)
						)
						(arc
							(start 0.2032 0.3048)
							(mid 0.275042 0.275042)
							(end 0.3048 0.2032)
						)
					)
					(width 0)
					(fill yes)
				)
			)
		)
	)
	(footprint ""
		(layer "F.Cu")
		(at 332.867 -362.077 180)
		(property "Reference" "Q213"
			(at 0 0 180)
			(layer "F.SilkS")
			(hide yes)
			(effects
				(font
					(size 1.27 1.27)
				)
			)
		)
		(property "Value" "2N7002K-2-GP"
			(at 0.127 -8.9662 180)
			(unlocked yes)
			(layer "F.Fab")
			(hide yes)
			(effects
				(font
					(size 1.016 1.016)
					(thickness 0.1524)
				)
			)
		)
		(property "Device Type" "SOT23DGS2D4H44"
			(at 0.127 -10.4902 180)
			(unlocked yes)
			(layer "F.Fab")
			(hide yes)
			(effects
				(font
					(size 1.016 1.016)
					(thickness 0.1524)
				)
			)
		)
		(duplicate_pad_numbers_are_jumpers no)
		(fp_line
			(start 1.651 1.778)
			(end 1.651 -1.778)
			(stroke
				(width 0.1524)
				(type default)
			)
			(layer "F.SilkS")
		)
		(fp_line
			(start 1.651 -1.778)
			(end -1.651 -1.778)
			(stroke
				(width 0.1524)
				(type default)
			)
			(layer "F.SilkS")
		)
		(fp_line
			(start -1.651 1.778)
			(end 1.651 1.778)
			(stroke
				(width 0.1524)
				(type default)
			)
			(layer "F.SilkS")
		)
		(fp_line
			(start -1.651 -1.778)
			(end -1.651 1.778)
			(stroke
				(width 0.1524)
				(type default)
			)
			(layer "F.SilkS")
		)
		(fp_poly
			(pts
				(xy -1.778 1.8796) (xy -1.778 -1.8796) (xy 1.778 -1.8796) (xy 1.778 1.8796)
			)
			(stroke
				(width 0)
				(type default)
			)
			(fill no)
			(layer "F.CrtYd")
		)
		(fp_poly
			(pts
				(xy -1.778 1.8796) (xy -1.778 -1.8796) (xy 1.778 -1.8796) (xy 1.778 1.8796)
			)
			(stroke
				(width 0)
				(type default)
			)
			(fill no)
			(layer "F.Fab")
		)
		(pad "D" smd custom
			(at 0 -0.9525 180)
			(size 0.1905 0.1905)
			(layers "F.Cu" "F.Mask" "F.Paste")
			(net "GATE_FAN2")
			(options
				(clearance outline)
				(anchor circle)
			)
			(primitives
				(gr_poly
					(pts
						(arc
							(start -0.1778 0.5715)
							(mid -0.321484 0.511984)
							(end -0.381 0.3683)
						)
						(arc
							(start -0.381 -0.3683)
							(mid -0.321484 -0.511984)
							(end -0.1778 -0.5715)
						)
						(arc
							(start 0.1778 -0.5715)
							(mid 0.321484 -0.511984)
							(end 0.381 -0.3683)
						)
						(arc
							(start 0.381 0.3683)
							(mid 0.321484 0.511984)
							(end 0.1778 0.5715)
						)
					)
					(width 0)
					(fill yes)
				)
			)
		)
		(pad "G" smd custom
			(at -0.98425 0.9525 180)
			(size 0.1905 0.1905)
			(layers "F.Cu" "F.Mask" "F.Paste")
			(net "FAN_EN")
			(options
				(clearance outline)
				(anchor circle)
			)
			(primitives
				(gr_poly
					(pts
						(arc
							(start -0.1778 0.5715)
							(mid -0.321484 0.511984)
							(end -0.381 0.3683)
						)
						(arc
							(start -0.381 -0.3683)
							(mid -0.321484 -0.511984)
							(end -0.1778 -0.5715)
						)
						(arc
							(start 0.1778 -0.5715)
							(mid 0.321484 -0.511984)
							(end 0.381 -0.3683)
						)
						(arc
							(start 0.381 0.3683)
							(mid 0.321484 0.511984)
							(end 0.1778 0.5715)
						)
					)
					(width 0)
					(fill yes)
				)
			)
		)
		(pad "S" smd custom
			(at 0.98425 0.9525 180)
			(size 0.1905 0.1905)
			(layers "F.Cu" "F.Mask" "F.Paste")
			(net "GND")
			(options
				(clearance outline)
				(anchor circle)
			)
			(primitives
				(gr_poly
					(pts
						(arc
							(start -0.1778 0.5715)
							(mid -0.321484 0.511984)
							(end -0.381 0.3683)
						)
						(arc
							(start -0.381 -0.3683)
							(mid -0.321484 -0.511984)
							(end -0.1778 -0.5715)
						)
						(arc
							(start 0.1778 -0.5715)
							(mid 0.321484 -0.511984)
							(end 0.381 -0.3683)
						)
						(arc
							(start 0.381 0.3683)
							(mid 0.321484 0.511984)
							(end 0.1778 0.5715)
						)
					)
					(width 0)
					(fill yes)
				)
			)
		)
	)
	(footprint ""
		(layer "F.Cu")
		(at 140.97 -35.687 -90)
		(property "Reference" "C398"
			(at 0 0 270)
			(layer "F.SilkS")
			(hide yes)
			(effects
				(font
					(size 1.27 1.27)
				)
			)
		)
		(property "Value" "SC4D7U25V5KX-1-GP"
			(at -0.0762 -6.1214 270)
			(unlocked yes)
			(layer "F.Fab")
			(hide yes)
			(effects
				(font
					(size 1.016 1.016)
					(thickness 0.1524)
				)
			)
		)
		(property "Device Type" "C805H58"
			(at -0.0762 -8.1534 270)
			(unlocked yes)
			(layer "F.Fab")
			(hide yes)
			(effects
				(font
					(size 1.016 1.016)
					(thickness 0.1524)
				)
			)
		)
		(duplicate_pad_numbers_are_jumpers no)
		(fp_line
			(start 0.635 0)
			(end -0.635 0)
			(stroke
				(width 0.508)
				(type default)
			)
			(layer "F.SilkS")
		)
		(fp_rect
			(start -0.9652 1.778)
			(end 0.9652 -1.778)
			(stroke
				(width 0)
				(type default)
			)
			(fill no)
			(layer "F.CrtYd")
		)
		(fp_poly
			(pts
				(xy -0.9652 -1.778) (xy 0.9652 -1.778) (xy 0.9652 1.778) (xy -0.9652 1.778)
			)
			(stroke
				(width 0)
				(type default)
			)
			(fill no)
			(layer "F.Fab")
		)
		(pad "1" smd rect
			(at 0 -0.9652 270)
			(size 1.397 1.143)
			(layers "F.Cu" "F.Mask" "F.Paste")
			(net "P12V_HDD28")
		)
		(pad "2" smd rect
			(at 0 0.9652 270)
			(size 1.397 1.143)
			(layers "F.Cu" "F.Mask" "F.Paste")
			(net "GND")
		)
	)
	(footprint ""
		(layer "F.Cu")
		(at 461.01 -253.873 -90)
		(property "Reference" "Q38"
			(at 0 0 270)
			(layer "F.SilkS")
			(hide yes)
			(effects
				(font
					(size 1.27 1.27)
				)
			)
		)
		(property "Value" "AO4406AL-GP"
			(at -3.707384 -1.5367 270)
			(unlocked yes)
			(layer "F.Fab")
			(hide yes)
			(effects
				(font
					(size 1.016 1.016)
					(thickness 0.1524)
				)
			)
		)
		(property "Device Type" "SOIC8H69"
			(at -3.707384 -3.0607 270)
			(unlocked yes)
			(layer "F.Fab")
			(hide yes)
			(effects
				(font
					(size 1.016 1.016)
					(thickness 0.1524)
				)
			)
		)
		(duplicate_pad_numbers_are_jumpers no)
		(fp_line
			(start -2.6289 3.4417)
			(end -2.6289 1.4732)
			(stroke
				(width 0.381)
				(type default)
			)
			(layer "F.SilkS")
		)
		(fp_line
			(start -2.7432 1.4224)
			(end -2.6416 1.4224)
			(stroke
				(width 0.1524)
				(type default)
			)
			(layer "F.SilkS")
		)
		(fp_line
			(start -2.7432 1.4224)
			(end 2.1336 1.4224)
			(stroke
				(width 0.1524)
				(type default)
			)
			(layer "F.SilkS")
		)
		(fp_line
			(start 2.1336 1.4224)
			(end 2.1336 -1.4224)
			(stroke
				(width 0.1524)
				(type default)
			)
			(layer "F.SilkS")
		)
		(fp_line
			(start -2.1844 -0.0508)
			(end -2.7178 0.508)
			(stroke
				(width 0.1524)
				(type default)
			)
			(layer "F.SilkS")
		)
		(fp_line
			(start -2.7178 -0.508)
			(end -2.1844 -0.0508)
			(stroke
				(width 0.1524)
				(type default)
			)
			(layer "F.SilkS")
		)
		(fp_line
			(start -2.7432 -1.4224)
			(end -2.7432 1.4224)
			(stroke
				(width 0.1524)
				(type default)
			)
			(layer "F.SilkS")
		)
		(fp_line
			(start 2.1336 -1.4224)
			(end -2.7432 -1.4224)
			(stroke
				(width 0.1524)
				(type default)
			)
			(layer "F.SilkS")
		)
		(fp_poly
			(pts
				(xy -2.2098 -1.4224) (xy -2.2098 1.4224) (xy 2.2098 1.4224) (xy 2.2098 -1.4224)
			)
			(stroke
				(width 0)
				(type default)
			)
			(fill yes)
			(layer "F.SilkS")
		)
		(fp_rect
			(start -2.450084 2.999994)
			(end 2.450084 -2.999994)
			(stroke
				(width 0)
				(type default)
			)
			(fill no)
			(layer "F.CrtYd")
		)
		(fp_poly
			(pts
				(xy -2.8194 3.6322) (xy -2.8194 -3.6322) (xy 2.8194 -3.6322) (xy 2.8194 1.18364) (xy 2.450084 1.18364)
				(xy 2.450084 -2.999994) (xy -2.450084 -2.999994) (xy -2.450084 2.999994) (xy 2.450084 2.999994)
				(xy 2.450084 1.18618) (xy 2.8194 1.18618) (xy 2.8194 3.6322)
			)
			(stroke
				(width 0)
				(type default)
			)
			(fill no)
			(layer "F.CrtYd")
		)
		(fp_rect
			(start -2.8194 3.6322)
			(end 2.8194 -3.6322)
			(stroke
				(width 0)
				(type default)
			)
			(fill no)
			(layer "F.Fab")
		)
		(pad "1" smd rect
			(at -1.905 2.54 270)
			(size 0.635 1.651)
			(layers "F.Cu" "F.Mask" "F.Paste")
			(net "P5V_HDD10")
		)
		(pad "2" smd rect
			(at -0.635 2.54 270)
			(size 0.635 1.651)
			(layers "F.Cu" "F.Mask" "F.Paste")
			(net "P5V_HDD10")
		)
		(pad "3" smd rect
			(at 0.635 2.54 270)
			(size 0.635 1.651)
			(layers "F.Cu" "F.Mask" "F.Paste")
			(net "P5V_HDD10")
		)
		(pad "4" smd rect
			(at 1.905 2.54 270)
			(size 0.635 1.651)
			(layers "F.Cu" "F.Mask" "F.Paste")
			(net "SW_HDD_P10")
		)
		(pad "5" smd rect
			(at 1.905 -2.54 270)
			(size 0.635 1.651)
			(layers "F.Cu" "F.Mask" "F.Paste")
			(net "P5V_B_3")
		)
		(pad "6" smd rect
			(at 0.635 -2.54 270)
			(size 0.635 1.651)
			(layers "F.Cu" "F.Mask" "F.Paste")
			(net "P5V_B_3")
		)
		(pad "7" smd rect
			(at -0.635 -2.54 270)
			(size 0.635 1.651)
			(layers "F.Cu" "F.Mask" "F.Paste")
			(net "P5V_B_3")
		)
		(pad "8" smd rect
			(at -1.905 -2.54 270)
			(size 0.635 1.651)
			(layers "F.Cu" "F.Mask" "F.Paste")
			(net "P5V_B_3")
		)
	)
	(footprint ""
		(layer "F.Cu")
		(at 95.608902 -248.750074 -90)
		(property "Reference" "VIA6"
			(at 0 0 270)
			(layer "F.SilkS")
			(hide yes)
			(effects
				(font
					(size 1.27 1.27)
				)
			)
		)
		(property "Value" "100OHM-8L-2D36MM-L16-GP"
			(at -3.4036 -0.4572 270)
			(unlocked yes)
			(layer "F.Fab")
			(hide yes)
			(effects
				(font
					(size 1.016 1.016)
					(thickness 0.1524)
				)
			)
		)
		(property "Device Type" "VIA-PCIE-4P-427097"
			(at -3.4036 -1.9812 270)
			(unlocked yes)
			(layer "F.Fab")
			(hide yes)
			(effects
				(font
					(size 1.016 1.016)
					(thickness 0.1524)
				)
			)
		)
		(duplicate_pad_numbers_are_jumpers no)
		(fp_rect
			(start -2.1336 0.4826)
			(end 2.1336 -0.4826)
			(stroke
				(width 0)
				(type default)
			)
			(fill no)
			(layer "F.CrtYd")
		)
		(fp_rect
			(start -2.1336 0.4826)
			(end 2.1336 -0.4826)
			(stroke
				(width 0)
				(type default)
			)
			(fill no)
			(layer "F.Fab")
		)
		(pad "1" thru_hole circle
			(at -1.651 0 270)
			(size 0.508 0.508)
			(drill 0.254)
			(layers "*.Cu" "*.Mask")
			(remove_unused_layers no)
			(net "GND")
			(clearance 0.2286)
			(thermal_gap 0.2286)
		)
		(pad "2" thru_hole circle
			(at -0.635 0 270)
			(size 0.508 0.508)
			(drill 0.254)
			(layers "*.Cu" "*.Mask")
			(remove_unused_layers no)
			(net "PHY_DRV_B_TO_SCC_B_2_DP")
			(clearance 0.2286)
			(thermal_gap 0.2286)
		)
		(pad "3" thru_hole circle
			(at 0.635 0 270)
			(size 0.508 0.508)
			(drill 0.254)
			(layers "*.Cu" "*.Mask")
			(remove_unused_layers no)
			(net "PHY_DRV_B_TO_SCC_B_2_DN")
			(clearance 0.2286)
			(thermal_gap 0.2286)
		)
		(pad "4" thru_hole circle
			(at 1.651 0 270)
			(size 0.508 0.508)
			(drill 0.254)
			(layers "*.Cu" "*.Mask")
			(remove_unused_layers no)
			(net "GND")
			(clearance 0.2286)
			(thermal_gap 0.2286)
		)
	)
	(footprint ""
		(layer "F.Cu")
		(at 287.32861 -333.51978 180)
		(property "Reference" "C20"
			(at 0 0 180)
			(layer "F.SilkS")
			(hide yes)
			(effects
				(font
					(size 1.27 1.27)
				)
			)
		)
		(property "Value" "SC1U16V3KX-5GP"
			(at 0 -2.8194 180)
			(unlocked yes)
			(layer "F.Fab")
			(hide yes)
			(effects
				(font
					(size 1.016 1.016)
					(thickness 0.1524)
				)
			)
		)
		(property "Device Type" "C603H36"
			(at 0 -4.3434 180)
			(unlocked yes)
			(layer "F.Fab")
			(hide yes)
			(effects
				(font
					(size 1.016 1.016)
					(thickness 0.1524)
				)
			)
		)
		(duplicate_pad_numbers_are_jumpers no)
		(fp_line
			(start 0.508 0)
			(end -0.508 0)
			(stroke
				(width 0.2032)
				(type default)
			)
			(layer "F.SilkS")
		)
		(fp_rect
			(start -0.5842 1.3335)
			(end 0.5842 -1.3335)
			(stroke
				(width 0)
				(type default)
			)
			(fill no)
			(layer "F.CrtYd")
		)
		(fp_rect
			(start -0.5842 1.3335)
			(end 0.5842 -1.3335)
			(stroke
				(width 0)
				(type default)
			)
			(fill no)
			(layer "F.Fab")
		)
		(pad "1" smd custom
			(at 0 -0.762 180)
			(size 0.2159 0.2159)
			(layers "F.Cu" "F.Mask" "F.Paste")
			(net "P3V3_IN")
			(options
				(clearance outline)
				(anchor circle)
			)
			(primitives
				(gr_poly
					(pts
						(arc
							(start -0.3302 -0.4318)
							(mid -0.402042 -0.402042)
							(end -0.4318 -0.3302)
						)
						(arc
							(start -0.4318 0.3302)
							(mid -0.402042 0.402042)
							(end -0.3302 0.4318)
						)
						(arc
							(start 0.3302 0.4318)
							(mid 0.402042 0.402042)
							(end 0.4318 0.3302)
						)
						(arc
							(start 0.4318 -0.3302)
							(mid 0.402042 -0.402042)
							(end 0.3302 -0.4318)
						)
					)
					(width 0)
					(fill yes)
				)
			)
		)
		(pad "2" smd custom
			(at 0 0.762 180)
			(size 0.2159 0.2159)
			(layers "F.Cu" "F.Mask" "F.Paste")
			(net "GND")
			(options
				(clearance outline)
				(anchor circle)
			)
			(primitives
				(gr_poly
					(pts
						(arc
							(start -0.3302 -0.4318)
							(mid -0.402042 -0.402042)
							(end -0.4318 -0.3302)
						)
						(arc
							(start -0.4318 0.3302)
							(mid -0.402042 0.402042)
							(end -0.3302 0.4318)
						)
						(arc
							(start 0.3302 0.4318)
							(mid 0.402042 0.402042)
							(end 0.4318 0.3302)
						)
						(arc
							(start 0.4318 -0.3302)
							(mid 0.402042 -0.402042)
							(end 0.3302 -0.4318)
						)
					)
					(width 0)
					(fill yes)
				)
			)
		)
	)
	(footprint ""
		(layer "F.Cu")
		(at 454.168002 -230.96855 -90)
		(property "Reference" "R1148"
			(at 0 0 270)
			(layer "F.SilkS")
			(hide yes)
			(effects
				(font
					(size 1.27 1.27)
				)
			)
		)
		(property "Value" "143KR2F-L-1-GP"
			(at 0.064008 -3.993896 270)
			(unlocked yes)
			(layer "F.Fab")
			(hide yes)
			(effects
				(font
					(size 1.016 1.016)
					(thickness 0.1524)
				)
			)
		)
		(property "Device Type" "R402H16"
			(at 0.064008 -5.517896 270)
			(unlocked yes)
			(layer "F.Fab")
			(hide yes)
			(effects
				(font
					(size 1.016 1.016)
					(thickness 0.1524)
				)
			)
		)
		(duplicate_pad_numbers_are_jumpers no)
		(fp_line
			(start -0.508 -0.9398)
			(end -0.508 0.9398)
			(stroke
				(width 0.1524)
				(type default)
			)
			(layer "F.SilkS")
		)
		(fp_line
			(start 0.508 -0.9398)
			(end -0.508 -0.9398)
			(stroke
				(width 0.1524)
				(type default)
			)
			(layer "F.SilkS")
		)
		(fp_rect
			(start -0.508 0.9398)
			(end 0.508 -0.9398)
			(stroke
				(width 0)
				(type default)
			)
			(fill no)
			(layer "F.CrtYd")
		)
		(fp_rect
			(start -0.508 0.9398)
			(end 0.508 -0.9398)
			(stroke
				(width 0)
				(type default)
			)
			(fill no)
			(layer "F.Fab")
		)
		(pad "1" smd custom
			(at 0 -0.4445 270)
			(size 0.1397 0.1397)
			(layers "F.Cu" "F.Mask" "F.Paste")
			(net "AGND_P5V_B_3")
			(options
				(clearance outline)
				(anchor circle)
			)
			(primitives
				(gr_poly
					(pts
						(arc
							(start -0.1778 -0.2794)
							(mid -0.249642 -0.249642)
							(end -0.2794 -0.1778)
						)
						(arc
							(start -0.2794 0.1778)
							(mid -0.249642 0.249642)
							(end -0.1778 0.2794)
						)
						(arc
							(start 0.1778 0.2794)
							(mid 0.249642 0.249642)
							(end 0.2794 0.1778)
						)
						(arc
							(start 0.2794 -0.1778)
							(mid 0.249642 -0.249642)
							(end 0.1778 -0.2794)
						)
					)
					(width 0)
					(fill yes)
				)
			)
		)
		(pad "2" smd custom
			(at 0 0.4445 270)
			(size 0.1397 0.1397)
			(layers "F.Cu" "F.Mask" "F.Paste")
			(net "P5V_B_3_TRIP")
			(options
				(clearance outline)
				(anchor circle)
			)
			(primitives
				(gr_poly
					(pts
						(arc
							(start -0.1778 -0.2794)
							(mid -0.249642 -0.249642)
							(end -0.2794 -0.1778)
						)
						(arc
							(start -0.2794 0.1778)
							(mid -0.249642 0.249642)
							(end -0.1778 0.2794)
						)
						(arc
							(start 0.1778 0.2794)
							(mid 0.249642 0.249642)
							(end 0.2794 0.1778)
						)
						(arc
							(start 0.2794 -0.1778)
							(mid 0.249642 -0.249642)
							(end 0.1778 -0.2794)
						)
					)
					(width 0)
					(fill yes)
				)
			)
		)
	)
	(footprint ""
		(layer "F.Cu")
		(at 251.948696 -226.35591 -90)
		(property "Reference" "C30"
			(at 0 0 270)
			(layer "F.SilkS")
			(hide yes)
			(effects
				(font
					(size 1.27 1.27)
				)
			)
		)
		(property "Value" "SCD1U16V2KX-3GP"
			(at 1.1811 -2.7051 270)
			(unlocked yes)
			(layer "F.Fab")
			(hide yes)
			(effects
				(font
					(size 1.016 1.016)
					(thickness 0.1524)
				)
			)
		)
		(property "Device Type" "C402H22"
			(at 1.1811 -4.2291 270)
			(unlocked yes)
			(layer "F.Fab")
			(hide yes)
			(effects
				(font
					(size 1.016 1.016)
					(thickness 0.1524)
				)
			)
		)
		(duplicate_pad_numbers_are_jumpers no)
		(fp_rect
			(start -0.4318 0.9525)
			(end 0.4318 -0.9525)
			(stroke
				(width 0)
				(type default)
			)
			(fill no)
			(layer "F.CrtYd")
		)
		(fp_rect
			(start -0.4318 0.9525)
			(end 0.4318 -0.9525)
			(stroke
				(width 0)
				(type default)
			)
			(fill no)
			(layer "F.Fab")
		)
		(pad "1" smd custom
			(at 0 -0.4445 270)
			(size 0.1524 0.1524)
			(layers "F.Cu" "F.Mask" "F.Paste")
			(net "P3V3_SENSE")
			(options
				(clearance outline)
				(anchor circle)
			)
			(primitives
				(gr_poly
					(pts
						(arc
							(start 0.3048 -0.2032)
							(mid 0.275042 -0.275042)
							(end 0.2032 -0.3048)
						)
						(arc
							(start -0.2032 -0.3048)
							(mid -0.275042 -0.275042)
							(end -0.3048 -0.2032)
						)
						(arc
							(start -0.3048 0.2032)
							(mid -0.275042 0.275042)
							(end -0.2032 0.3048)
						)
						(arc
							(start 0.2032 0.3048)
							(mid 0.275042 0.275042)
							(end 0.3048 0.2032)
						)
					)
					(width 0)
					(fill yes)
				)
			)
		)
		(pad "2" smd custom
			(at 0 0.4445 270)
			(size 0.1524 0.1524)
			(layers "F.Cu" "F.Mask" "F.Paste")
			(net "GND")
			(options
				(clearance outline)
				(anchor circle)
			)
			(primitives
				(gr_poly
					(pts
						(arc
							(start 0.3048 -0.2032)
							(mid 0.275042 -0.275042)
							(end 0.2032 -0.3048)
						)
						(arc
							(start -0.2032 -0.3048)
							(mid -0.275042 -0.275042)
							(end -0.3048 -0.2032)
						)
						(arc
							(start -0.3048 0.2032)
							(mid -0.275042 0.275042)
							(end -0.2032 0.3048)
						)
						(arc
							(start 0.2032 0.3048)
							(mid 0.275042 0.275042)
							(end 0.3048 0.2032)
						)
					)
					(width 0)
					(fill yes)
				)
			)
		)
	)
	(footprint ""
		(layer "F.Cu")
		(at 52.649882 -111.842804 90)
		(property "Reference" "C643"
			(at 0 0 90)
			(layer "F.SilkS")
			(hide yes)
			(effects
				(font
					(size 1.27 1.27)
				)
			)
		)
		(property "Value" "SCD1U16V2KX-3GP"
			(at 1.1811 -2.7051 90)
			(unlocked yes)
			(layer "F.Fab")
			(hide yes)
			(effects
				(font
					(size 1.016 1.016)
					(thickness 0.1524)
				)
			)
		)
		(property "Device Type" "C402H22"
			(at 1.1811 -4.2291 90)
			(unlocked yes)
			(layer "F.Fab")
			(hide yes)
			(effects
				(font
					(size 1.016 1.016)
					(thickness 0.1524)
				)
			)
		)
		(duplicate_pad_numbers_are_jumpers no)
		(fp_rect
			(start -0.4318 0.9525)
			(end 0.4318 -0.9525)
			(stroke
				(width 0)
				(type default)
			)
			(fill no)
			(layer "F.CrtYd")
		)
		(fp_rect
			(start -0.4318 0.9525)
			(end 0.4318 -0.9525)
			(stroke
				(width 0)
				(type default)
			)
			(fill no)
			(layer "F.Fab")
		)
		(pad "1" smd custom
			(at 0 -0.4445 90)
			(size 0.1524 0.1524)
			(layers "F.Cu" "F.Mask" "F.Paste")
			(net "P5V_B_2_VBST_RC")
			(options
				(clearance outline)
				(anchor circle)
			)
			(primitives
				(gr_poly
					(pts
						(arc
							(start 0.3048 -0.2032)
							(mid 0.275042 -0.275042)
							(end 0.2032 -0.3048)
						)
						(arc
							(start -0.2032 -0.3048)
							(mid -0.275042 -0.275042)
							(end -0.3048 -0.2032)
						)
						(arc
							(start -0.3048 0.2032)
							(mid -0.275042 0.275042)
							(end -0.2032 0.3048)
						)
						(arc
							(start 0.2032 0.3048)
							(mid 0.275042 0.275042)
							(end 0.3048 0.2032)
						)
					)
					(width 0)
					(fill yes)
				)
			)
		)
		(pad "2" smd custom
			(at 0 0.4445 90)
			(size 0.1524 0.1524)
			(layers "F.Cu" "F.Mask" "F.Paste")
			(net "P5V_B_2_LL")
			(options
				(clearance outline)
				(anchor circle)
			)
			(primitives
				(gr_poly
					(pts
						(arc
							(start 0.3048 -0.2032)
							(mid 0.275042 -0.275042)
							(end 0.2032 -0.3048)
						)
						(arc
							(start -0.2032 -0.3048)
							(mid -0.275042 -0.275042)
							(end -0.3048 -0.2032)
						)
						(arc
							(start -0.3048 0.2032)
							(mid -0.275042 0.275042)
							(end -0.2032 0.3048)
						)
						(arc
							(start 0.2032 0.3048)
							(mid 0.275042 0.275042)
							(end 0.3048 0.2032)
						)
					)
					(width 0)
					(fill yes)
				)
			)
		)
	)
	(footprint ""
		(layer "F.Cu")
		(at 400.05 -131.826 180)
		(property "Reference" "R544"
			(at 0 0 180)
			(layer "F.SilkS")
			(hide yes)
			(effects
				(font
					(size 1.27 1.27)
				)
			)
		)
		(property "Value" "4K7R2J-2-GP"
			(at 0.064008 -3.993896 180)
			(unlocked yes)
			(layer "F.Fab")
			(hide yes)
			(effects
				(font
					(size 1.016 1.016)
					(thickness 0.1524)
				)
			)
		)
		(property "Device Type" "R402H16"
			(at 0.064008 -5.517896 180)
			(unlocked yes)
			(layer "F.Fab")
			(hide yes)
			(effects
				(font
					(size 1.016 1.016)
					(thickness 0.1524)
				)
			)
		)
		(duplicate_pad_numbers_are_jumpers no)
		(fp_line
			(start 0.508 -0.9398)
			(end -0.508 -0.9398)
			(stroke
				(width 0.1524)
				(type default)
			)
			(layer "F.SilkS")
		)
		(fp_line
			(start -0.508 -0.9398)
			(end -0.508 0.9398)
			(stroke
				(width 0.1524)
				(type default)
			)
			(layer "F.SilkS")
		)
		(fp_rect
			(start -0.508 0.9398)
			(end 0.508 -0.9398)
			(stroke
				(width 0)
				(type default)
			)
			(fill no)
			(layer "F.CrtYd")
		)
		(fp_rect
			(start -0.508 0.9398)
			(end 0.508 -0.9398)
			(stroke
				(width 0)
				(type default)
			)
			(fill no)
			(layer "F.Fab")
		)
		(pad "1" smd custom
			(at 0 -0.4445 180)
			(size 0.1397 0.1397)
			(layers "F.Cu" "F.Mask" "F.Paste")
			(net "P12V_B")
			(options
				(clearance outline)
				(anchor circle)
			)
			(primitives
				(gr_poly
					(pts
						(arc
							(start -0.1778 -0.2794)
							(mid -0.249642 -0.249642)
							(end -0.2794 -0.1778)
						)
						(arc
							(start -0.2794 0.1778)
							(mid -0.249642 0.249642)
							(end -0.1778 0.2794)
						)
						(arc
							(start 0.1778 0.2794)
							(mid 0.249642 0.249642)
							(end 0.2794 0.1778)
						)
						(arc
							(start 0.2794 -0.1778)
							(mid 0.249642 -0.249642)
							(end 0.1778 -0.2794)
						)
					)
					(width 0)
					(fill yes)
				)
			)
		)
		(pad "2" smd custom
			(at 0 0.4445 180)
			(size 0.1397 0.1397)
			(layers "F.Cu" "F.Mask" "F.Paste")
			(net "SW_HDD_R20")
			(options
				(clearance outline)
				(anchor circle)
			)
			(primitives
				(gr_poly
					(pts
						(arc
							(start -0.1778 -0.2794)
							(mid -0.249642 -0.249642)
							(end -0.2794 -0.1778)
						)
						(arc
							(start -0.2794 0.1778)
							(mid -0.249642 0.249642)
							(end -0.1778 0.2794)
						)
						(arc
							(start 0.1778 0.2794)
							(mid 0.249642 0.249642)
							(end 0.2794 0.1778)
						)
						(arc
							(start 0.2794 -0.1778)
							(mid 0.249642 -0.249642)
							(end 0.1778 -0.2794)
						)
					)
					(width 0)
					(fill yes)
				)
			)
		)
	)
	(footprint ""
		(layer "F.Cu")
		(at 418.239702 -248.750074 -90)
		(property "Reference" "VIA20"
			(at 0 0 270)
			(layer "F.SilkS")
			(hide yes)
			(effects
				(font
					(size 1.27 1.27)
				)
			)
		)
		(property "Value" "100OHM-8L-2D36MM-L16-GP"
			(at -3.4036 -0.4572 270)
			(unlocked yes)
			(layer "F.Fab")
			(hide yes)
			(effects
				(font
					(size 1.016 1.016)
					(thickness 0.1524)
				)
			)
		)
		(property "Device Type" "VIA-PCIE-4P-427097"
			(at -3.4036 -1.9812 270)
			(unlocked yes)
			(layer "F.Fab")
			(hide yes)
			(effects
				(font
					(size 1.016 1.016)
					(thickness 0.1524)
				)
			)
		)
		(duplicate_pad_numbers_are_jumpers no)
		(fp_rect
			(start -2.1336 0.4826)
			(end 2.1336 -0.4826)
			(stroke
				(width 0)
				(type default)
			)
			(fill no)
			(layer "F.CrtYd")
		)
		(fp_rect
			(start -2.1336 0.4826)
			(end 2.1336 -0.4826)
			(stroke
				(width 0)
				(type default)
			)
			(fill no)
			(layer "F.Fab")
		)
		(pad "1" thru_hole circle
			(at -1.651 0 270)
			(size 0.508 0.508)
			(drill 0.254)
			(layers "*.Cu" "*.Mask")
			(remove_unused_layers no)
			(net "GND")
			(clearance 0.2286)
			(thermal_gap 0.2286)
		)
		(pad "2" thru_hole circle
			(at -0.635 0 270)
			(size 0.508 0.508)
			(drill 0.254)
			(layers "*.Cu" "*.Mask")
			(remove_unused_layers no)
			(net "PHY_DRV_B_TO_SCC_B_9_DP")
			(clearance 0.2286)
			(thermal_gap 0.2286)
		)
		(pad "3" thru_hole circle
			(at 0.635 0 270)
			(size 0.508 0.508)
			(drill 0.254)
			(layers "*.Cu" "*.Mask")
			(remove_unused_layers no)
			(net "PHY_DRV_B_TO_SCC_B_9_DN")
			(clearance 0.2286)
			(thermal_gap 0.2286)
		)
		(pad "4" thru_hole circle
			(at 1.651 0 270)
			(size 0.508 0.508)
			(drill 0.254)
			(layers "*.Cu" "*.Mask")
			(remove_unused_layers no)
			(net "GND")
			(clearance 0.2286)
			(thermal_gap 0.2286)
		)
	)
	(footprint ""
		(layer "F.Cu")
		(at 221.29496 -161.90976)
		(property "Reference" "R56"
			(at 0 0 0)
			(layer "F.SilkS")
			(hide yes)
			(effects
				(font
					(size 1.27 1.27)
				)
			)
		)
		(property "Value" "0R2J-2-GP"
			(at 0.064008 -3.993896 0)
			(unlocked yes)
			(layer "F.Fab")
			(hide yes)
			(effects
				(font
					(size 1.016 1.016)
					(thickness 0.1524)
				)
			)
		)
		(property "Device Type" "R402H16"
			(at 0.064008 -5.517896 0)
			(unlocked yes)
			(layer "F.Fab")
			(hide yes)
			(effects
				(font
					(size 1.016 1.016)
					(thickness 0.1524)
				)
			)
		)
		(duplicate_pad_numbers_are_jumpers no)
		(fp_line
			(start -0.508 -0.9398)
			(end -0.508 0.9398)
			(stroke
				(width 0.1524)
				(type default)
			)
			(layer "F.SilkS")
		)
		(fp_line
			(start 0.508 -0.9398)
			(end -0.508 -0.9398)
			(stroke
				(width 0.1524)
				(type default)
			)
			(layer "F.SilkS")
		)
		(fp_rect
			(start -0.508 0.9398)
			(end 0.508 -0.9398)
			(stroke
				(width 0)
				(type default)
			)
			(fill no)
			(layer "F.CrtYd")
		)
		(fp_rect
			(start -0.508 0.9398)
			(end 0.508 -0.9398)
			(stroke
				(width 0)
				(type default)
			)
			(fill no)
			(layer "F.Fab")
		)
		(pad "1" smd custom
			(at 0 -0.4445)
			(size 0.1397 0.1397)
			(layers "F.Cu" "F.Mask" "F.Paste")
			(net "IO_EXP6_INT_N")
			(options
				(clearance outline)
				(anchor circle)
			)
			(primitives
				(gr_poly
					(pts
						(arc
							(start -0.1778 -0.2794)
							(mid -0.249642 -0.249642)
							(end -0.2794 -0.1778)
						)
						(arc
							(start -0.2794 0.1778)
							(mid -0.249642 0.249642)
							(end -0.1778 0.2794)
						)
						(arc
							(start 0.1778 0.2794)
							(mid 0.249642 0.249642)
							(end 0.2794 0.1778)
						)
						(arc
							(start 0.2794 -0.1778)
							(mid 0.249642 -0.249642)
							(end 0.1778 -0.2794)
						)
					)
					(width 0)
					(fill yes)
				)
			)
		)
		(pad "2" smd custom
			(at 0 0.4445)
			(size 0.1397 0.1397)
			(layers "F.Cu" "F.Mask" "F.Paste")
			(net "DRIVE_INSERT_ALERT_B_N")
			(options
				(clearance outline)
				(anchor circle)
			)
			(primitives
				(gr_poly
					(pts
						(arc
							(start -0.1778 -0.2794)
							(mid -0.249642 -0.249642)
							(end -0.2794 -0.1778)
						)
						(arc
							(start -0.2794 0.1778)
							(mid -0.249642 0.249642)
							(end -0.1778 0.2794)
						)
						(arc
							(start 0.1778 0.2794)
							(mid 0.249642 0.249642)
							(end 0.2794 0.1778)
						)
						(arc
							(start 0.2794 -0.1778)
							(mid 0.249642 -0.249642)
							(end 0.1778 -0.2794)
						)
					)
					(width 0)
					(fill yes)
				)
			)
		)
	)
	(footprint ""
		(layer "F.Cu")
		(at 55.88 -19.177)
		(property "Reference" "R656"
			(at 0 0 0)
			(layer "F.SilkS")
			(hide yes)
			(effects
				(font
					(size 1.27 1.27)
				)
			)
		)
		(property "Value" "0R2J-2-GP"
			(at 0.064008 -3.993896 0)
			(unlocked yes)
			(layer "F.Fab")
			(hide yes)
			(effects
				(font
					(size 1.016 1.016)
					(thickness 0.1524)
				)
			)
		)
		(property "Device Type" "R402H16"
			(at 0.064008 -5.517896 0)
			(unlocked yes)
			(layer "F.Fab")
			(hide yes)
			(effects
				(font
					(size 1.016 1.016)
					(thickness 0.1524)
				)
			)
		)
		(duplicate_pad_numbers_are_jumpers no)
		(fp_line
			(start -0.508 -0.9398)
			(end -0.508 0.9398)
			(stroke
				(width 0.1524)
				(type default)
			)
			(layer "F.SilkS")
		)
		(fp_line
			(start 0.508 -0.9398)
			(end -0.508 -0.9398)
			(stroke
				(width 0.1524)
				(type default)
			)
			(layer "F.SilkS")
		)
		(fp_rect
			(start -0.508 0.9398)
			(end 0.508 -0.9398)
			(stroke
				(width 0)
				(type default)
			)
			(fill no)
			(layer "F.CrtYd")
		)
		(fp_rect
			(start -0.508 0.9398)
			(end 0.508 -0.9398)
			(stroke
				(width 0)
				(type default)
			)
			(fill no)
			(layer "F.Fab")
		)
		(pad "1" smd custom
			(at 0 -0.4445)
			(size 0.1397 0.1397)
			(layers "F.Cu" "F.Mask" "F.Paste")
			(net "DRIVE_B_25_PWR")
			(options
				(clearance outline)
				(anchor circle)
			)
			(primitives
				(gr_poly
					(pts
						(arc
							(start -0.1778 -0.2794)
							(mid -0.249642 -0.249642)
							(end -0.2794 -0.1778)
						)
						(arc
							(start -0.2794 0.1778)
							(mid -0.249642 0.249642)
							(end -0.1778 0.2794)
						)
						(arc
							(start 0.1778 0.2794)
							(mid 0.249642 0.249642)
							(end 0.2794 0.1778)
						)
						(arc
							(start 0.2794 -0.1778)
							(mid 0.249642 -0.249642)
							(end 0.1778 -0.2794)
						)
					)
					(width 0)
					(fill yes)
				)
			)
		)
		(pad "2" smd custom
			(at 0 0.4445)
			(size 0.1397 0.1397)
			(layers "F.Cu" "F.Mask" "F.Paste")
			(net "SW_PWR_R_HDD25")
			(options
				(clearance outline)
				(anchor circle)
			)
			(primitives
				(gr_poly
					(pts
						(arc
							(start -0.1778 -0.2794)
							(mid -0.249642 -0.249642)
							(end -0.2794 -0.1778)
						)
						(arc
							(start -0.2794 0.1778)
							(mid -0.249642 0.249642)
							(end -0.1778 0.2794)
						)
						(arc
							(start 0.1778 0.2794)
							(mid 0.249642 0.249642)
							(end 0.2794 0.1778)
						)
						(arc
							(start 0.2794 -0.1778)
							(mid 0.249642 -0.249642)
							(end 0.1778 -0.2794)
						)
					)
					(width 0)
					(fill yes)
				)
			)
		)
	)
	(footprint ""
		(layer "F.Cu")
		(at 186.7281 -377.5583 -90)
		(property "Reference" "R967"
			(at 0 0 270)
			(layer "F.SilkS")
			(hide yes)
			(effects
				(font
					(size 1.27 1.27)
				)
			)
		)
		(property "Value" "1KR5F-1-GP"
			(at 0 -8.9535 270)
			(unlocked yes)
			(layer "F.Fab")
			(hide yes)
			(effects
				(font
					(size 1.27 1.016)
					(thickness 0.1524)
				)
			)
		)
		(property "Device Type" "R805H24"
			(at 0 -10.6299 270)
			(unlocked yes)
			(layer "F.Fab")
			(hide yes)
			(effects
				(font
					(size 1.27 1.016)
					(thickness 0.1524)
				)
			)
		)
		(duplicate_pad_numbers_are_jumpers no)
		(fp_line
			(start -0.889 1.7018)
			(end 0.889 1.7018)
			(stroke
				(width 0.1524)
				(type default)
			)
			(layer "F.SilkS")
		)
		(fp_line
			(start 0.889 1.7018)
			(end 0.889 -0.508)
			(stroke
				(width 0.1524)
				(type default)
			)
			(layer "F.SilkS")
		)
		(fp_line
			(start -0.889 0.0762)
			(end -0.889 1.7018)
			(stroke
				(width 0.1524)
				(type default)
			)
			(layer "F.SilkS")
		)
		(fp_line
			(start -0.889 -1.7018)
			(end -0.889 0.2794)
			(stroke
				(width 0.1524)
				(type default)
			)
			(layer "F.SilkS")
		)
		(fp_line
			(start 0.889 -1.7018)
			(end 0.889 -0.381)
			(stroke
				(width 0.1524)
				(type default)
			)
			(layer "F.SilkS")
		)
		(fp_line
			(start 0.889 -1.7018)
			(end -0.889 -1.7018)
			(stroke
				(width 0.1524)
				(type default)
			)
			(layer "F.SilkS")
		)
		(fp_poly
			(pts
				(xy 0.9652 -1.778) (xy 0.9652 1.778) (xy -0.9652 1.778) (xy -0.9652 -1.778)
			)
			(stroke
				(width 0)
				(type default)
			)
			(fill no)
			(layer "F.CrtYd")
		)
		(fp_rect
			(start -0.9652 1.778)
			(end 0.9652 -1.778)
			(stroke
				(width 0)
				(type default)
			)
			(fill no)
			(layer "F.Fab")
		)
		(pad "1" smd rect
			(at 0 -0.9652 270)
			(size 1.397 1.143)
			(layers "F.Cu" "F.Mask" "F.Paste")
			(net "FAN_YELLOW_1")
		)
		(pad "2" smd rect
			(at 0 0.9652 270)
			(size 1.397 1.143)
			(layers "F.Cu" "F.Mask" "F.Paste")
			(net "FAN_LED_YELLOW_1")
		)
	)
	(footprint ""
		(layer "F.Cu")
		(at 172.593 -246.634 90)
		(property "Reference" "R248"
			(at 0 0 90)
			(layer "F.SilkS")
			(hide yes)
			(effects
				(font
					(size 1.27 1.27)
				)
			)
		)
		(property "Value" "4K7R2J-2-GP"
			(at 0.064008 -3.993896 90)
			(unlocked yes)
			(layer "F.Fab")
			(hide yes)
			(effects
				(font
					(size 1.016 1.016)
					(thickness 0.1524)
				)
			)
		)
		(property "Device Type" "R402H16"
			(at 0.064008 -5.517896 90)
			(unlocked yes)
			(layer "F.Fab")
			(hide yes)
			(effects
				(font
					(size 1.016 1.016)
					(thickness 0.1524)
				)
			)
		)
		(duplicate_pad_numbers_are_jumpers no)
		(fp_line
			(start 0.508 -0.9398)
			(end -0.508 -0.9398)
			(stroke
				(width 0.1524)
				(type default)
			)
			(layer "F.SilkS")
		)
		(fp_line
			(start -0.508 -0.9398)
			(end -0.508 0.9398)
			(stroke
				(width 0.1524)
				(type default)
			)
			(layer "F.SilkS")
		)
		(fp_rect
			(start -0.508 0.9398)
			(end 0.508 -0.9398)
			(stroke
				(width 0)
				(type default)
			)
			(fill no)
			(layer "F.CrtYd")
		)
		(fp_rect
			(start -0.508 0.9398)
			(end 0.508 -0.9398)
			(stroke
				(width 0)
				(type default)
			)
			(fill no)
			(layer "F.Fab")
		)
		(pad "1" smd custom
			(at 0 -0.4445 90)
			(size 0.1397 0.1397)
			(layers "F.Cu" "F.Mask" "F.Paste")
			(net "P12V_B")
			(options
				(clearance outline)
				(anchor circle)
			)
			(primitives
				(gr_poly
					(pts
						(arc
							(start -0.1778 -0.2794)
							(mid -0.249642 -0.249642)
							(end -0.2794 -0.1778)
						)
						(arc
							(start -0.2794 0.1778)
							(mid -0.249642 0.249642)
							(end -0.1778 0.2794)
						)
						(arc
							(start 0.1778 0.2794)
							(mid 0.249642 0.249642)
							(end 0.2794 0.1778)
						)
						(arc
							(start 0.2794 -0.1778)
							(mid 0.249642 -0.249642)
							(end 0.1778 -0.2794)
						)
					)
					(width 0)
					(fill yes)
				)
			)
		)
		(pad "2" smd custom
			(at 0 0.4445 90)
			(size 0.1397 0.1397)
			(layers "F.Cu" "F.Mask" "F.Paste")
			(net "SW_HDD_R5")
			(options
				(clearance outline)
				(anchor circle)
			)
			(primitives
				(gr_poly
					(pts
						(arc
							(start -0.1778 -0.2794)
							(mid -0.249642 -0.249642)
							(end -0.2794 -0.1778)
						)
						(arc
							(start -0.2794 0.1778)
							(mid -0.249642 0.249642)
							(end -0.1778 0.2794)
						)
						(arc
							(start 0.1778 0.2794)
							(mid 0.249642 0.249642)
							(end 0.2794 0.1778)
						)
						(arc
							(start 0.2794 -0.1778)
							(mid 0.249642 -0.249642)
							(end 0.1778 -0.2794)
						)
					)
					(width 0)
					(fill yes)
				)
			)
		)
	)
	(footprint ""
		(layer "F.Cu")
		(at 37.0332 -12.319 -90)
		(property "Reference" "R127"
			(at 0 0 270)
			(layer "F.SilkS")
			(hide yes)
			(effects
				(font
					(size 1.27 1.27)
				)
			)
		)
		(property "Value" "0R2J-2-GP"
			(at 0.064008 -3.993896 270)
			(unlocked yes)
			(layer "F.Fab")
			(hide yes)
			(effects
				(font
					(size 1.016 1.016)
					(thickness 0.1524)
				)
			)
		)
		(property "Device Type" "R402H16"
			(at 0.064008 -5.517896 270)
			(unlocked yes)
			(layer "F.Fab")
			(hide yes)
			(effects
				(font
					(size 1.016 1.016)
					(thickness 0.1524)
				)
			)
		)
		(duplicate_pad_numbers_are_jumpers no)
		(fp_line
			(start -0.508 -0.9398)
			(end -0.508 0.9398)
			(stroke
				(width 0.1524)
				(type default)
			)
			(layer "F.SilkS")
		)
		(fp_line
			(start 0.508 -0.9398)
			(end -0.508 -0.9398)
			(stroke
				(width 0.1524)
				(type default)
			)
			(layer "F.SilkS")
		)
		(fp_rect
			(start -0.508 0.9398)
			(end 0.508 -0.9398)
			(stroke
				(width 0)
				(type default)
			)
			(fill no)
			(layer "F.CrtYd")
		)
		(fp_rect
			(start -0.508 0.9398)
			(end 0.508 -0.9398)
			(stroke
				(width 0)
				(type default)
			)
			(fill no)
			(layer "F.Fab")
		)
		(pad "1" smd custom
			(at 0 -0.4445 270)
			(size 0.1397 0.1397)
			(layers "F.Cu" "F.Mask" "F.Paste")
			(net "I2C_DPB_A_SCL_BUF")
			(options
				(clearance outline)
				(anchor circle)
			)
			(primitives
				(gr_poly
					(pts
						(arc
							(start -0.1778 -0.2794)
							(mid -0.249642 -0.249642)
							(end -0.2794 -0.1778)
						)
						(arc
							(start -0.2794 0.1778)
							(mid -0.249642 0.249642)
							(end -0.1778 0.2794)
						)
						(arc
							(start 0.1778 0.2794)
							(mid 0.249642 0.249642)
							(end 0.2794 0.1778)
						)
						(arc
							(start 0.2794 -0.1778)
							(mid 0.249642 -0.249642)
							(end 0.1778 -0.2794)
						)
					)
					(width 0)
					(fill yes)
				)
			)
		)
		(pad "2" smd custom
			(at 0 0.4445 270)
			(size 0.1397 0.1397)
			(layers "F.Cu" "F.Mask" "F.Paste")
			(net "TEMP1_SCL")
			(options
				(clearance outline)
				(anchor circle)
			)
			(primitives
				(gr_poly
					(pts
						(arc
							(start -0.1778 -0.2794)
							(mid -0.249642 -0.249642)
							(end -0.2794 -0.1778)
						)
						(arc
							(start -0.2794 0.1778)
							(mid -0.249642 0.249642)
							(end -0.1778 0.2794)
						)
						(arc
							(start 0.1778 0.2794)
							(mid 0.249642 0.249642)
							(end 0.2794 0.1778)
						)
						(arc
							(start 0.2794 -0.1778)
							(mid 0.249642 -0.249642)
							(end 0.1778 -0.2794)
						)
					)
					(width 0)
					(fill yes)
				)
			)
		)
	)
	(footprint ""
		(layer "F.Cu")
		(at 321.7164 -146.6342)
		(property "Reference" "C269"
			(at 0 0 0)
			(layer "F.SilkS")
			(hide yes)
			(effects
				(font
					(size 1.27 1.27)
				)
			)
		)
		(property "Value" "SCD01U50V2KX-1GP"
			(at 1.1811 -2.7051 0)
			(unlocked yes)
			(layer "F.Fab")
			(hide yes)
			(effects
				(font
					(size 1.016 1.016)
					(thickness 0.1524)
				)
			)
		)
		(property "Device Type" "C402H22"
			(at 1.1811 -4.2291 0)
			(unlocked yes)
			(layer "F.Fab")
			(hide yes)
			(effects
				(font
					(size 1.016 1.016)
					(thickness 0.1524)
				)
			)
		)
		(duplicate_pad_numbers_are_jumpers no)
		(fp_rect
			(start -0.4318 0.9525)
			(end 0.4318 -0.9525)
			(stroke
				(width 0)
				(type default)
			)
			(fill no)
			(layer "F.CrtYd")
		)
		(fp_rect
			(start -0.4318 0.9525)
			(end 0.4318 -0.9525)
			(stroke
				(width 0)
				(type default)
			)
			(fill no)
			(layer "F.Fab")
		)
		(pad "1" smd custom
			(at 0 -0.4445)
			(size 0.1524 0.1524)
			(layers "F.Cu" "F.Mask" "F.Paste")
			(net "HDD_PRSNT_18")
			(options
				(clearance outline)
				(anchor circle)
			)
			(primitives
				(gr_poly
					(pts
						(arc
							(start 0.3048 -0.2032)
							(mid 0.275042 -0.275042)
							(end 0.2032 -0.3048)
						)
						(arc
							(start -0.2032 -0.3048)
							(mid -0.275042 -0.275042)
							(end -0.3048 -0.2032)
						)
						(arc
							(start -0.3048 0.2032)
							(mid -0.275042 0.275042)
							(end -0.2032 0.3048)
						)
						(arc
							(start 0.2032 0.3048)
							(mid 0.275042 0.275042)
							(end 0.3048 0.2032)
						)
					)
					(width 0)
					(fill yes)
				)
			)
		)
		(pad "2" smd custom
			(at 0 0.4445)
			(size 0.1524 0.1524)
			(layers "F.Cu" "F.Mask" "F.Paste")
			(net "GND")
			(options
				(clearance outline)
				(anchor circle)
			)
			(primitives
				(gr_poly
					(pts
						(arc
							(start 0.3048 -0.2032)
							(mid 0.275042 -0.275042)
							(end 0.2032 -0.3048)
						)
						(arc
							(start -0.2032 -0.3048)
							(mid -0.275042 -0.275042)
							(end -0.3048 -0.2032)
						)
						(arc
							(start -0.3048 0.2032)
							(mid -0.275042 0.275042)
							(end -0.2032 0.3048)
						)
						(arc
							(start 0.2032 0.3048)
							(mid 0.275042 0.275042)
							(end 0.3048 0.2032)
						)
					)
					(width 0)
					(fill yes)
				)
			)
		)
	)
	(footprint ""
		(layer "F.Cu")
		(at 382.315974 -154.70505)
		(property "Reference" "TP121"
			(at 0 0 0)
			(layer "F.SilkS")
			(hide yes)
			(effects
				(font
					(size 1.27 1.27)
				)
			)
		)
		(property "Value" "*"
			(at -0.0508 -1.6764 0)
			(unlocked yes)
			(layer "F.Fab")
			(hide yes)
			(effects
				(font
					(size 1.016 1.016)
					(thickness 0.1524)
				)
			)
		)
		(property "Device Type" "TPAD32"
			(at -0.0508 -3.2004 0)
			(unlocked yes)
			(layer "F.Fab")
			(hide yes)
			(effects
				(font
					(size 1.016 1.016)
					(thickness 0.1524)
				)
			)
		)
		(duplicate_pad_numbers_are_jumpers no)
		(fp_poly
			(pts
				(arc
					(start 0.4064 0)
					(mid -0.4064 0)
					(end 0.4064 0)
				)
			)
			(stroke
				(width 0)
				(type default)
			)
			(fill no)
			(layer "F.CrtYd")
		)
		(fp_poly
			(pts
				(arc
					(start 0.7112 0)
					(mid -0.7112 0)
					(end 0.7112 0)
				)
			)
			(stroke
				(width 0)
				(type default)
			)
			(fill no)
			(layer "F.Fab")
		)
		(pad "1" smd circle
			(at 0 0)
			(size 0.8128 0.8128)
			(layers "F.Cu" "F.Mask" "F.Paste")
			(net "ACT_HDD_20")
		)
	)
	(footprint ""
		(layer "F.Cu")
		(at 417.966652 -132.437124)
		(property "Reference" "VIA44"
			(at 0 0 0)
			(layer "F.SilkS")
			(hide yes)
			(effects
				(font
					(size 1.27 1.27)
				)
			)
		)
		(property "Value" "100OHM-8L-2D36MM-L16-GP"
			(at -3.4036 -0.4572 0)
			(unlocked yes)
			(layer "F.Fab")
			(hide yes)
			(effects
				(font
					(size 1.016 1.016)
					(thickness 0.1524)
				)
			)
		)
		(property "Device Type" "VIA-PCIE-4P-427097"
			(at -3.4036 -1.9812 0)
			(unlocked yes)
			(layer "F.Fab")
			(hide yes)
			(effects
				(font
					(size 1.016 1.016)
					(thickness 0.1524)
				)
			)
		)
		(duplicate_pad_numbers_are_jumpers no)
		(fp_rect
			(start -2.1336 0.4826)
			(end 2.1336 -0.4826)
			(stroke
				(width 0)
				(type default)
			)
			(fill no)
			(layer "F.CrtYd")
		)
		(fp_rect
			(start -2.1336 0.4826)
			(end 2.1336 -0.4826)
			(stroke
				(width 0)
				(type default)
			)
			(fill no)
			(layer "F.Fab")
		)
		(pad "1" thru_hole circle
			(at -1.651 0)
			(size 0.508 0.508)
			(drill 0.254)
			(layers "*.Cu" "*.Mask")
			(remove_unused_layers no)
			(net "GND")
			(clearance 0.2286)
			(thermal_gap 0.2286)
		)
		(pad "2" thru_hole circle
			(at -0.635 0)
			(size 0.508 0.508)
			(drill 0.254)
			(layers "*.Cu" "*.Mask")
			(remove_unused_layers no)
			(net "PHY_DRV_B_TO_SCC_B_21_DP")
			(clearance 0.2286)
			(thermal_gap 0.2286)
		)
		(pad "3" thru_hole circle
			(at 0.635 0)
			(size 0.508 0.508)
			(drill 0.254)
			(layers "*.Cu" "*.Mask")
			(remove_unused_layers no)
			(net "PHY_DRV_B_TO_SCC_B_21_DN")
			(clearance 0.2286)
			(thermal_gap 0.2286)
		)
		(pad "4" thru_hole circle
			(at 1.651 0)
			(size 0.508 0.508)
			(drill 0.254)
			(layers "*.Cu" "*.Mask")
			(remove_unused_layers no)
			(net "GND")
			(clearance 0.2286)
			(thermal_gap 0.2286)
		)
	)
	(footprint ""
		(layer "F.Cu")
		(at 78.11135 -102.427786 -90)
		(property "Reference" "R372"
			(at 0 0 270)
			(layer "F.SilkS")
			(hide yes)
			(effects
				(font
					(size 1.27 1.27)
				)
			)
		)
		(property "Value" "4K7R2F-GP"
			(at 0.064008 -3.993896 270)
			(unlocked yes)
			(layer "F.Fab")
			(hide yes)
			(effects
				(font
					(size 1.016 1.016)
					(thickness 0.1524)
				)
			)
		)
		(property "Device Type" "R402H16"
			(at 0.064008 -5.517896 270)
			(unlocked yes)
			(layer "F.Fab")
			(hide yes)
			(effects
				(font
					(size 1.016 1.016)
					(thickness 0.1524)
				)
			)
		)
		(duplicate_pad_numbers_are_jumpers no)
		(fp_line
			(start -0.508 -0.9398)
			(end -0.508 0.9398)
			(stroke
				(width 0.1524)
				(type default)
			)
			(layer "F.SilkS")
		)
		(fp_line
			(start 0.508 -0.9398)
			(end -0.508 -0.9398)
			(stroke
				(width 0.1524)
				(type default)
			)
			(layer "F.SilkS")
		)
		(fp_rect
			(start -0.508 0.9398)
			(end 0.508 -0.9398)
			(stroke
				(width 0)
				(type default)
			)
			(fill no)
			(layer "F.CrtYd")
		)
		(fp_rect
			(start -0.508 0.9398)
			(end 0.508 -0.9398)
			(stroke
				(width 0)
				(type default)
			)
			(fill no)
			(layer "F.Fab")
		)
		(pad "1" smd custom
			(at 0 -0.4445 270)
			(size 0.1397 0.1397)
			(layers "F.Cu" "F.Mask" "F.Paste")
			(net "DRIVE_B_14_FLT_LED")
			(options
				(clearance outline)
				(anchor circle)
			)
			(primitives
				(gr_poly
					(pts
						(arc
							(start -0.1778 -0.2794)
							(mid -0.249642 -0.249642)
							(end -0.2794 -0.1778)
						)
						(arc
							(start -0.2794 0.1778)
							(mid -0.249642 0.249642)
							(end -0.1778 0.2794)
						)
						(arc
							(start 0.1778 0.2794)
							(mid 0.249642 0.249642)
							(end 0.2794 0.1778)
						)
						(arc
							(start 0.2794 -0.1778)
							(mid 0.249642 -0.249642)
							(end 0.1778 -0.2794)
						)
					)
					(width 0)
					(fill yes)
				)
			)
		)
		(pad "2" smd custom
			(at 0 0.4445 270)
			(size 0.1397 0.1397)
			(layers "F.Cu" "F.Mask" "F.Paste")
			(net "GND")
			(options
				(clearance outline)
				(anchor circle)
			)
			(primitives
				(gr_poly
					(pts
						(arc
							(start -0.1778 -0.2794)
							(mid -0.249642 -0.249642)
							(end -0.2794 -0.1778)
						)
						(arc
							(start -0.2794 0.1778)
							(mid -0.249642 0.249642)
							(end -0.1778 0.2794)
						)
						(arc
							(start 0.1778 0.2794)
							(mid 0.249642 0.249642)
							(end 0.2794 0.1778)
						)
						(arc
							(start 0.2794 -0.1778)
							(mid 0.249642 -0.249642)
							(end 0.1778 -0.2794)
						)
					)
					(width 0)
					(fill yes)
				)
			)
		)
	)
	(footprint ""
		(layer "F.Cu")
		(at 366.395 -23.876 -90)
		(property "Reference" "Q159"
			(at 0 0 270)
			(layer "F.SilkS")
			(hide yes)
			(effects
				(font
					(size 1.27 1.27)
				)
			)
		)
		(property "Value" "AO4406AL-GP"
			(at -3.707384 -1.5367 270)
			(unlocked yes)
			(layer "F.Fab")
			(hide yes)
			(effects
				(font
					(size 1.016 1.016)
					(thickness 0.1524)
				)
			)
		)
		(property "Device Type" "SOIC8H69"
			(at -3.707384 -3.0607 270)
			(unlocked yes)
			(layer "F.Fab")
			(hide yes)
			(effects
				(font
					(size 1.016 1.016)
					(thickness 0.1524)
				)
			)
		)
		(duplicate_pad_numbers_are_jumpers no)
		(fp_line
			(start -2.6289 3.4417)
			(end -2.6289 1.4732)
			(stroke
				(width 0.381)
				(type default)
			)
			(layer "F.SilkS")
		)
		(fp_line
			(start -2.7432 1.4224)
			(end -2.6416 1.4224)
			(stroke
				(width 0.1524)
				(type default)
			)
			(layer "F.SilkS")
		)
		(fp_line
			(start -2.7432 1.4224)
			(end 2.1336 1.4224)
			(stroke
				(width 0.1524)
				(type default)
			)
			(layer "F.SilkS")
		)
		(fp_line
			(start 2.1336 1.4224)
			(end 2.1336 -1.4224)
			(stroke
				(width 0.1524)
				(type default)
			)
			(layer "F.SilkS")
		)
		(fp_line
			(start -2.1844 -0.0508)
			(end -2.7178 0.508)
			(stroke
				(width 0.1524)
				(type default)
			)
			(layer "F.SilkS")
		)
		(fp_line
			(start -2.7178 -0.508)
			(end -2.1844 -0.0508)
			(stroke
				(width 0.1524)
				(type default)
			)
			(layer "F.SilkS")
		)
		(fp_line
			(start -2.7432 -1.4224)
			(end -2.7432 1.4224)
			(stroke
				(width 0.1524)
				(type default)
			)
			(layer "F.SilkS")
		)
		(fp_line
			(start 2.1336 -1.4224)
			(end -2.7432 -1.4224)
			(stroke
				(width 0.1524)
				(type default)
			)
			(layer "F.SilkS")
		)
		(fp_poly
			(pts
				(xy -2.2098 -1.4224) (xy -2.2098 1.4224) (xy 2.2098 1.4224) (xy 2.2098 -1.4224)
			)
			(stroke
				(width 0)
				(type default)
			)
			(fill yes)
			(layer "F.SilkS")
		)
		(fp_rect
			(start -2.450084 2.999994)
			(end 2.450084 -2.999994)
			(stroke
				(width 0)
				(type default)
			)
			(fill no)
			(layer "F.CrtYd")
		)
		(fp_poly
			(pts
				(xy -2.8194 3.6322) (xy -2.8194 -3.6322) (xy 2.8194 -3.6322) (xy 2.8194 1.18364) (xy 2.450084 1.18364)
				(xy 2.450084 -2.999994) (xy -2.450084 -2.999994) (xy -2.450084 2.999994) (xy 2.450084 2.999994)
				(xy 2.450084 1.18618) (xy 2.8194 1.18618) (xy 2.8194 3.6322)
			)
			(stroke
				(width 0)
				(type default)
			)
			(fill no)
			(layer "F.CrtYd")
		)
		(fp_rect
			(start -2.8194 3.6322)
			(end 2.8194 -3.6322)
			(stroke
				(width 0)
				(type default)
			)
			(fill no)
			(layer "F.Fab")
		)
		(pad "1" smd rect
			(at -1.905 2.54 270)
			(size 0.635 1.651)
			(layers "F.Cu" "F.Mask" "F.Paste")
			(net "P5V_HDD31")
		)
		(pad "2" smd rect
			(at -0.635 2.54 270)
			(size 0.635 1.651)
			(layers "F.Cu" "F.Mask" "F.Paste")
			(net "P5V_HDD31")
		)
		(pad "3" smd rect
			(at 0.635 2.54 270)
			(size 0.635 1.651)
			(layers "F.Cu" "F.Mask" "F.Paste")
			(net "P5V_HDD31")
		)
		(pad "4" smd rect
			(at 1.905 2.54 270)
			(size 0.635 1.651)
			(layers "F.Cu" "F.Mask" "F.Paste")
			(net "SW_HDD_P31")
		)
		(pad "5" smd rect
			(at 1.905 -2.54 270)
			(size 0.635 1.651)
			(layers "F.Cu" "F.Mask" "F.Paste")
			(net "P5V_B_4")
		)
		(pad "6" smd rect
			(at 0.635 -2.54 270)
			(size 0.635 1.651)
			(layers "F.Cu" "F.Mask" "F.Paste")
			(net "P5V_B_4")
		)
		(pad "7" smd rect
			(at -0.635 -2.54 270)
			(size 0.635 1.651)
			(layers "F.Cu" "F.Mask" "F.Paste")
			(net "P5V_B_4")
		)
		(pad "8" smd rect
			(at -1.905 -2.54 270)
			(size 0.635 1.651)
			(layers "F.Cu" "F.Mask" "F.Paste")
			(net "P5V_B_4")
		)
	)
	(footprint ""
		(layer "F.Cu")
		(at 407.093928 -102.413562 -90)
		(property "Reference" "R480"
			(at 0 0 270)
			(layer "F.SilkS")
			(hide yes)
			(effects
				(font
					(size 1.27 1.27)
				)
			)
		)
		(property "Value" "4K7R2F-GP"
			(at 0.064008 -3.993896 270)
			(unlocked yes)
			(layer "F.Fab")
			(hide yes)
			(effects
				(font
					(size 1.016 1.016)
					(thickness 0.1524)
				)
			)
		)
		(property "Device Type" "R402H16"
			(at 0.064008 -5.517896 270)
			(unlocked yes)
			(layer "F.Fab")
			(hide yes)
			(effects
				(font
					(size 1.016 1.016)
					(thickness 0.1524)
				)
			)
		)
		(duplicate_pad_numbers_are_jumpers no)
		(fp_line
			(start -0.508 -0.9398)
			(end -0.508 0.9398)
			(stroke
				(width 0.1524)
				(type default)
			)
			(layer "F.SilkS")
		)
		(fp_line
			(start 0.508 -0.9398)
			(end -0.508 -0.9398)
			(stroke
				(width 0.1524)
				(type default)
			)
			(layer "F.SilkS")
		)
		(fp_rect
			(start -0.508 0.9398)
			(end 0.508 -0.9398)
			(stroke
				(width 0)
				(type default)
			)
			(fill no)
			(layer "F.CrtYd")
		)
		(fp_rect
			(start -0.508 0.9398)
			(end 0.508 -0.9398)
			(stroke
				(width 0)
				(type default)
			)
			(fill no)
			(layer "F.Fab")
		)
		(pad "1" smd custom
			(at 0 -0.4445 270)
			(size 0.1397 0.1397)
			(layers "F.Cu" "F.Mask" "F.Paste")
			(net "DRIVE_B_21_FLT_LED")
			(options
				(clearance outline)
				(anchor circle)
			)
			(primitives
				(gr_poly
					(pts
						(arc
							(start -0.1778 -0.2794)
							(mid -0.249642 -0.249642)
							(end -0.2794 -0.1778)
						)
						(arc
							(start -0.2794 0.1778)
							(mid -0.249642 0.249642)
							(end -0.1778 0.2794)
						)
						(arc
							(start 0.1778 0.2794)
							(mid 0.249642 0.249642)
							(end 0.2794 0.1778)
						)
						(arc
							(start 0.2794 -0.1778)
							(mid 0.249642 -0.249642)
							(end 0.1778 -0.2794)
						)
					)
					(width 0)
					(fill yes)
				)
			)
		)
		(pad "2" smd custom
			(at 0 0.4445 270)
			(size 0.1397 0.1397)
			(layers "F.Cu" "F.Mask" "F.Paste")
			(net "GND")
			(options
				(clearance outline)
				(anchor circle)
			)
			(primitives
				(gr_poly
					(pts
						(arc
							(start -0.1778 -0.2794)
							(mid -0.249642 -0.249642)
							(end -0.2794 -0.1778)
						)
						(arc
							(start -0.2794 0.1778)
							(mid -0.249642 0.249642)
							(end -0.1778 0.2794)
						)
						(arc
							(start 0.1778 0.2794)
							(mid 0.249642 0.249642)
							(end 0.2794 0.1778)
						)
						(arc
							(start 0.2794 -0.1778)
							(mid 0.249642 -0.249642)
							(end 0.1778 -0.2794)
						)
					)
					(width 0)
					(fill yes)
				)
			)
		)
	)
	(footprint ""
		(layer "F.Cu")
		(at 97.863914 -269.705074)
		(property "Reference" "TP31"
			(at 0 0 0)
			(layer "F.SilkS")
			(hide yes)
			(effects
				(font
					(size 1.27 1.27)
				)
			)
		)
		(property "Value" "*"
			(at -0.0508 -1.6764 0)
			(unlocked yes)
			(layer "F.Fab")
			(hide yes)
			(effects
				(font
					(size 1.016 1.016)
					(thickness 0.1524)
				)
			)
		)
		(property "Device Type" "TPAD32"
			(at -0.0508 -3.2004 0)
			(unlocked yes)
			(layer "F.Fab")
			(hide yes)
			(effects
				(font
					(size 1.016 1.016)
					(thickness 0.1524)
				)
			)
		)
		(duplicate_pad_numbers_are_jumpers no)
		(fp_poly
			(pts
				(arc
					(start 0.4064 0)
					(mid -0.4064 0)
					(end 0.4064 0)
				)
			)
			(stroke
				(width 0)
				(type default)
			)
			(fill no)
			(layer "F.CrtYd")
		)
		(fp_poly
			(pts
				(arc
					(start 0.7112 0)
					(mid -0.7112 0)
					(end 0.7112 0)
				)
			)
			(stroke
				(width 0)
				(type default)
			)
			(fill no)
			(layer "F.Fab")
		)
		(pad "1" smd circle
			(at 0 0)
			(size 0.8128 0.8128)
			(layers "F.Cu" "F.Mask" "F.Paste")
			(net "ACT_HDD_2")
		)
	)
	(footprint ""
		(layer "F.Cu")
		(at 111.506 -132.588 180)
		(property "Reference" "D15"
			(at 0 0 180)
			(layer "F.SilkS")
			(hide yes)
			(effects
				(font
					(size 1.27 1.27)
				)
			)
		)
		(property "Value" "RB551V30-GP"
			(at 0 -6.7818 180)
			(unlocked yes)
			(layer "F.Fab")
			(hide yes)
			(effects
				(font
					(size 1.016 1.016)
					(thickness 0.1524)
				)
			)
		)
		(property "Device Type" "SOD323AKH38"
			(at 0 -8.6868 180)
			(unlocked yes)
			(layer "F.Fab")
			(hide yes)
			(effects
				(font
					(size 1.016 1.016)
					(thickness 0.1524)
				)
			)
		)
		(duplicate_pad_numbers_are_jumpers no)
		(fp_line
			(start 0.889 2.159)
			(end -0.889 2.159)
			(stroke
				(width 0.1524)
				(type default)
			)
			(layer "F.SilkS")
		)
		(fp_line
			(start 0.889 -1.9304)
			(end 0.889 2.159)
			(stroke
				(width 0.1524)
				(type default)
			)
			(layer "F.SilkS")
		)
		(fp_line
			(start 0.762 2.0574)
			(end -0.762 2.0574)
			(stroke
				(width 0.508)
				(type default)
			)
			(layer "F.SilkS")
		)
		(fp_line
			(start -0.889 2.159)
			(end -0.889 -1.9304)
			(stroke
				(width 0.1524)
				(type default)
			)
			(layer "F.SilkS")
		)
		(fp_line
			(start -0.889 -1.9304)
			(end 0.889 -1.9304)
			(stroke
				(width 0.1524)
				(type default)
			)
			(layer "F.SilkS")
		)
		(fp_rect
			(start -1.016 2.3114)
			(end 1.016 -2.0066)
			(stroke
				(width 0)
				(type default)
			)
			(fill no)
			(layer "F.CrtYd")
		)
		(fp_poly
			(pts
				(xy -1.016 -2.0066) (xy 1.016 -2.0066) (xy 1.016 2.3114) (xy -1.016 2.3114)
			)
			(stroke
				(width 0)
				(type default)
			)
			(fill no)
			(layer "F.Fab")
		)
		(pad "A" smd rect
			(at 0 -1.143 180)
			(size 0.5588 1.016)
			(layers "F.Cu" "F.Mask" "F.Paste")
			(net "SW_HDD_R15")
		)
		(pad "K" smd rect
			(at 0 1.143 180)
			(size 0.5588 1.016)
			(layers "F.Cu" "F.Mask" "F.Paste")
			(net "SW_HDD_N15")
		)
	)
	(footprint ""
		(layer "F.Cu")
		(at 129.413762 -39.705026)
		(property "Reference" "TP156"
			(at 0 0 0)
			(layer "F.SilkS")
			(hide yes)
			(effects
				(font
					(size 1.27 1.27)
				)
			)
		)
		(property "Value" "*"
			(at -0.0508 -1.6764 0)
			(unlocked yes)
			(layer "F.Fab")
			(hide yes)
			(effects
				(font
					(size 1.016 1.016)
					(thickness 0.1524)
				)
			)
		)
		(property "Device Type" "TPAD32"
			(at -0.0508 -3.2004 0)
			(unlocked yes)
			(layer "F.Fab")
			(hide yes)
			(effects
				(font
					(size 1.016 1.016)
					(thickness 0.1524)
				)
			)
		)
		(duplicate_pad_numbers_are_jumpers no)
		(fp_poly
			(pts
				(arc
					(start 0.4064 0)
					(mid -0.4064 0)
					(end 0.4064 0)
				)
			)
			(stroke
				(width 0)
				(type default)
			)
			(fill no)
			(layer "F.CrtYd")
		)
		(fp_poly
			(pts
				(arc
					(start 0.7112 0)
					(mid -0.7112 0)
					(end 0.7112 0)
				)
			)
			(stroke
				(width 0)
				(type default)
			)
			(fill no)
			(layer "F.Fab")
		)
		(pad "1" smd circle
			(at 0 0)
			(size 0.8128 0.8128)
			(layers "F.Cu" "F.Mask" "F.Paste")
			(net "ACT_HDD_27")
		)
	)
	(footprint ""
		(layer "F.Cu")
		(at 149.987 -263.271)
		(property "Reference" "R222"
			(at 0 0 0)
			(layer "F.SilkS")
			(hide yes)
			(effects
				(font
					(size 1.27 1.27)
				)
			)
		)
		(property "Value" "2R6F-GP"
			(at -0.0508 -4.8514 0)
			(unlocked yes)
			(layer "F.Fab")
			(hide yes)
			(effects
				(font
					(size 1.016 1.016)
					(thickness 0.1524)
				)
			)
		)
		(property "Device Type" "R1206H26"
			(at 0 -6.3754 0)
			(unlocked yes)
			(layer "F.Fab")
			(hide yes)
			(effects
				(font
					(size 1.016 1.016)
					(thickness 0.1524)
				)
			)
		)
		(duplicate_pad_numbers_are_jumpers no)
		(fp_line
			(start -1.016 -2.2352)
			(end 1.016 -2.2352)
			(stroke
				(width 0.1524)
				(type default)
			)
			(layer "F.SilkS")
		)
		(fp_line
			(start -1.016 2.2352)
			(end -1.016 -2.2352)
			(stroke
				(width 0.1524)
				(type default)
			)
			(layer "F.SilkS")
		)
		(fp_line
			(start 1.016 -2.2352)
			(end 1.016 2.2352)
			(stroke
				(width 0.1524)
				(type default)
			)
			(layer "F.SilkS")
		)
		(fp_line
			(start 1.016 2.2352)
			(end -1.016 2.2352)
			(stroke
				(width 0.1524)
				(type default)
			)
			(layer "F.SilkS")
		)
		(fp_rect
			(start -1.0922 2.3114)
			(end 1.0922 -2.3114)
			(stroke
				(width 0)
				(type default)
			)
			(fill no)
			(layer "F.CrtYd")
		)
		(fp_poly
			(pts
				(xy -1.0922 -2.3114) (xy 1.0922 -2.3114) (xy 1.0922 2.3114) (xy -1.0922 2.3114)
			)
			(stroke
				(width 0)
				(type default)
			)
			(fill no)
			(layer "F.Fab")
		)
		(pad "1" smd rect
			(at 0 -1.397)
			(size 1.651 1.27)
			(layers "F.Cu" "F.Mask" "F.Paste")
			(net "P5V_HDD4")
		)
		(pad "2" smd rect
			(at 0 1.397)
			(size 1.651 1.27)
			(layers "F.Cu" "F.Mask" "F.Paste")
			(net "5V_PRE_4")
		)
	)
	(footprint ""
		(layer "F.Cu")
		(at 181.61 -365.379 90)
		(property "Reference" "R986"
			(at 0 0 90)
			(layer "F.SilkS")
			(hide yes)
			(effects
				(font
					(size 1.27 1.27)
				)
			)
		)
		(property "Value" "0R2J-2-GP"
			(at 0.064008 -3.993896 90)
			(unlocked yes)
			(layer "F.Fab")
			(hide yes)
			(effects
				(font
					(size 1.016 1.016)
					(thickness 0.1524)
				)
			)
		)
		(property "Device Type" "R402H16"
			(at 0.064008 -5.517896 90)
			(unlocked yes)
			(layer "F.Fab")
			(hide yes)
			(effects
				(font
					(size 1.016 1.016)
					(thickness 0.1524)
				)
			)
		)
		(duplicate_pad_numbers_are_jumpers no)
		(fp_line
			(start 0.508 -0.9398)
			(end -0.508 -0.9398)
			(stroke
				(width 0.1524)
				(type default)
			)
			(layer "F.SilkS")
		)
		(fp_line
			(start -0.508 -0.9398)
			(end -0.508 0.9398)
			(stroke
				(width 0.1524)
				(type default)
			)
			(layer "F.SilkS")
		)
		(fp_rect
			(start -0.508 0.9398)
			(end 0.508 -0.9398)
			(stroke
				(width 0)
				(type default)
			)
			(fill no)
			(layer "F.CrtYd")
		)
		(fp_rect
			(start -0.508 0.9398)
			(end 0.508 -0.9398)
			(stroke
				(width 0)
				(type default)
			)
			(fill no)
			(layer "F.Fab")
		)
		(pad "1" smd custom
			(at 0 -0.4445 90)
			(size 0.1397 0.1397)
			(layers "F.Cu" "F.Mask" "F.Paste")
			(net "MB0_CM_ADR2_R")
			(options
				(clearance outline)
				(anchor circle)
			)
			(primitives
				(gr_poly
					(pts
						(arc
							(start -0.1778 -0.2794)
							(mid -0.249642 -0.249642)
							(end -0.2794 -0.1778)
						)
						(arc
							(start -0.2794 0.1778)
							(mid -0.249642 0.249642)
							(end -0.1778 0.2794)
						)
						(arc
							(start 0.1778 0.2794)
							(mid 0.249642 0.249642)
							(end 0.2794 0.1778)
						)
						(arc
							(start 0.2794 -0.1778)
							(mid 0.249642 -0.249642)
							(end 0.1778 -0.2794)
						)
					)
					(width 0)
					(fill yes)
				)
			)
		)
		(pad "2" smd custom
			(at 0 0.4445 90)
			(size 0.1397 0.1397)
			(layers "F.Cu" "F.Mask" "F.Paste")
			(net "AGND_CURRENT_MON")
			(options
				(clearance outline)
				(anchor circle)
			)
			(primitives
				(gr_poly
					(pts
						(arc
							(start -0.1778 -0.2794)
							(mid -0.249642 -0.249642)
							(end -0.2794 -0.1778)
						)
						(arc
							(start -0.2794 0.1778)
							(mid -0.249642 0.249642)
							(end -0.1778 0.2794)
						)
						(arc
							(start 0.1778 0.2794)
							(mid 0.249642 0.249642)
							(end 0.2794 0.1778)
						)
						(arc
							(start 0.2794 -0.1778)
							(mid 0.249642 -0.249642)
							(end 0.1778 -0.2794)
						)
					)
					(width 0)
					(fill yes)
				)
			)
		)
	)
	(footprint ""
		(layer "F.Cu")
		(at 46.482 -246.634 90)
		(property "Reference" "R184"
			(at 0 0 90)
			(layer "F.SilkS")
			(hide yes)
			(effects
				(font
					(size 1.27 1.27)
				)
			)
		)
		(property "Value" "4K7R2J-2-GP"
			(at 0.064008 -3.993896 90)
			(unlocked yes)
			(layer "F.Fab")
			(hide yes)
			(effects
				(font
					(size 1.016 1.016)
					(thickness 0.1524)
				)
			)
		)
		(property "Device Type" "R402H16"
			(at 0.064008 -5.517896 90)
			(unlocked yes)
			(layer "F.Fab")
			(hide yes)
			(effects
				(font
					(size 1.016 1.016)
					(thickness 0.1524)
				)
			)
		)
		(duplicate_pad_numbers_are_jumpers no)
		(fp_line
			(start 0.508 -0.9398)
			(end -0.508 -0.9398)
			(stroke
				(width 0.1524)
				(type default)
			)
			(layer "F.SilkS")
		)
		(fp_line
			(start -0.508 -0.9398)
			(end -0.508 0.9398)
			(stroke
				(width 0.1524)
				(type default)
			)
			(layer "F.SilkS")
		)
		(fp_rect
			(start -0.508 0.9398)
			(end 0.508 -0.9398)
			(stroke
				(width 0)
				(type default)
			)
			(fill no)
			(layer "F.CrtYd")
		)
		(fp_rect
			(start -0.508 0.9398)
			(end 0.508 -0.9398)
			(stroke
				(width 0)
				(type default)
			)
			(fill no)
			(layer "F.Fab")
		)
		(pad "1" smd custom
			(at 0 -0.4445 90)
			(size 0.1397 0.1397)
			(layers "F.Cu" "F.Mask" "F.Paste")
			(net "P12V_B")
			(options
				(clearance outline)
				(anchor circle)
			)
			(primitives
				(gr_poly
					(pts
						(arc
							(start -0.1778 -0.2794)
							(mid -0.249642 -0.249642)
							(end -0.2794 -0.1778)
						)
						(arc
							(start -0.2794 0.1778)
							(mid -0.249642 0.249642)
							(end -0.1778 0.2794)
						)
						(arc
							(start 0.1778 0.2794)
							(mid 0.249642 0.249642)
							(end 0.2794 0.1778)
						)
						(arc
							(start 0.2794 -0.1778)
							(mid 0.249642 -0.249642)
							(end 0.1778 -0.2794)
						)
					)
					(width 0)
					(fill yes)
				)
			)
		)
		(pad "2" smd custom
			(at 0 0.4445 90)
			(size 0.1397 0.1397)
			(layers "F.Cu" "F.Mask" "F.Paste")
			(net "SW_HDD_R1")
			(options
				(clearance outline)
				(anchor circle)
			)
			(primitives
				(gr_poly
					(pts
						(arc
							(start -0.1778 -0.2794)
							(mid -0.249642 -0.249642)
							(end -0.2794 -0.1778)
						)
						(arc
							(start -0.2794 0.1778)
							(mid -0.249642 0.249642)
							(end -0.1778 0.2794)
						)
						(arc
							(start 0.1778 0.2794)
							(mid 0.249642 0.249642)
							(end 0.2794 0.1778)
						)
						(arc
							(start 0.2794 -0.1778)
							(mid 0.249642 -0.249642)
							(end 0.1778 -0.2794)
						)
					)
					(width 0)
					(fill yes)
				)
			)
		)
	)
	(footprint ""
		(layer "F.Cu")
		(at 244.729 -311.912)
		(property "Reference" "R1095"
			(at 0 0 0)
			(layer "F.SilkS")
			(hide yes)
			(effects
				(font
					(size 1.27 1.27)
				)
			)
		)
		(property "Value" "0R2J-2-GP"
			(at 0.064008 -3.993896 0)
			(unlocked yes)
			(layer "F.Fab")
			(hide yes)
			(effects
				(font
					(size 1.016 1.016)
					(thickness 0.1524)
				)
			)
		)
		(property "Device Type" "R402H16"
			(at 0.064008 -5.517896 0)
			(unlocked yes)
			(layer "F.Fab")
			(hide yes)
			(effects
				(font
					(size 1.016 1.016)
					(thickness 0.1524)
				)
			)
		)
		(duplicate_pad_numbers_are_jumpers no)
		(fp_line
			(start -0.508 -0.9398)
			(end -0.508 0.9398)
			(stroke
				(width 0.1524)
				(type default)
			)
			(layer "F.SilkS")
		)
		(fp_line
			(start 0.508 -0.9398)
			(end -0.508 -0.9398)
			(stroke
				(width 0.1524)
				(type default)
			)
			(layer "F.SilkS")
		)
		(fp_rect
			(start -0.508 0.9398)
			(end 0.508 -0.9398)
			(stroke
				(width 0)
				(type default)
			)
			(fill no)
			(layer "F.CrtYd")
		)
		(fp_rect
			(start -0.508 0.9398)
			(end 0.508 -0.9398)
			(stroke
				(width 0)
				(type default)
			)
			(fill no)
			(layer "F.Fab")
		)
		(pad "1" smd custom
			(at 0 -0.4445)
			(size 0.1397 0.1397)
			(layers "F.Cu" "F.Mask" "F.Paste")
			(net "GND")
			(options
				(clearance outline)
				(anchor circle)
			)
			(primitives
				(gr_poly
					(pts
						(arc
							(start -0.1778 -0.2794)
							(mid -0.249642 -0.249642)
							(end -0.2794 -0.1778)
						)
						(arc
							(start -0.2794 0.1778)
							(mid -0.249642 0.249642)
							(end -0.1778 0.2794)
						)
						(arc
							(start 0.1778 0.2794)
							(mid 0.249642 0.249642)
							(end 0.2794 0.1778)
						)
						(arc
							(start 0.2794 -0.1778)
							(mid 0.249642 -0.249642)
							(end 0.1778 -0.2794)
						)
					)
					(width 0)
					(fill yes)
				)
			)
		)
		(pad "2" smd custom
			(at 0 0.4445)
			(size 0.1397 0.1397)
			(layers "F.Cu" "F.Mask" "F.Paste")
			(net "MAX31790_A_SPIN_ST")
			(options
				(clearance outline)
				(anchor circle)
			)
			(primitives
				(gr_poly
					(pts
						(arc
							(start -0.1778 -0.2794)
							(mid -0.249642 -0.249642)
							(end -0.2794 -0.1778)
						)
						(arc
							(start -0.2794 0.1778)
							(mid -0.249642 0.249642)
							(end -0.1778 0.2794)
						)
						(arc
							(start 0.1778 0.2794)
							(mid 0.249642 0.249642)
							(end 0.2794 0.1778)
						)
						(arc
							(start 0.2794 -0.1778)
							(mid 0.249642 -0.249642)
							(end 0.1778 -0.2794)
						)
					)
					(width 0)
					(fill yes)
				)
			)
		)
	)
	(footprint ""
		(layer "F.Cu")
		(at 149.225 -249.555 90)
		(property "Reference" "R231"
			(at 0 0 90)
			(layer "F.SilkS")
			(hide yes)
			(effects
				(font
					(size 1.27 1.27)
				)
			)
		)
		(property "Value" "4K7R2F-GP"
			(at 0.064008 -3.993896 90)
			(unlocked yes)
			(layer "F.Fab")
			(hide yes)
			(effects
				(font
					(size 1.016 1.016)
					(thickness 0.1524)
				)
			)
		)
		(property "Device Type" "R402H16"
			(at 0.064008 -5.517896 90)
			(unlocked yes)
			(layer "F.Fab")
			(hide yes)
			(effects
				(font
					(size 1.016 1.016)
					(thickness 0.1524)
				)
			)
		)
		(duplicate_pad_numbers_are_jumpers no)
		(fp_line
			(start 0.508 -0.9398)
			(end -0.508 -0.9398)
			(stroke
				(width 0.1524)
				(type default)
			)
			(layer "F.SilkS")
		)
		(fp_line
			(start -0.508 -0.9398)
			(end -0.508 0.9398)
			(stroke
				(width 0.1524)
				(type default)
			)
			(layer "F.SilkS")
		)
		(fp_rect
			(start -0.508 0.9398)
			(end 0.508 -0.9398)
			(stroke
				(width 0)
				(type default)
			)
			(fill no)
			(layer "F.CrtYd")
		)
		(fp_rect
			(start -0.508 0.9398)
			(end 0.508 -0.9398)
			(stroke
				(width 0)
				(type default)
			)
			(fill no)
			(layer "F.Fab")
		)
		(pad "1" smd custom
			(at 0 -0.4445 90)
			(size 0.1397 0.1397)
			(layers "F.Cu" "F.Mask" "F.Paste")
			(net "SW_PWR_R_HDD4")
			(options
				(clearance outline)
				(anchor circle)
			)
			(primitives
				(gr_poly
					(pts
						(arc
							(start -0.1778 -0.2794)
							(mid -0.249642 -0.249642)
							(end -0.2794 -0.1778)
						)
						(arc
							(start -0.2794 0.1778)
							(mid -0.249642 0.249642)
							(end -0.1778 0.2794)
						)
						(arc
							(start 0.1778 0.2794)
							(mid 0.249642 0.249642)
							(end 0.2794 0.1778)
						)
						(arc
							(start 0.2794 -0.1778)
							(mid 0.249642 -0.249642)
							(end 0.1778 -0.2794)
						)
					)
					(width 0)
					(fill yes)
				)
			)
		)
		(pad "2" smd custom
			(at 0 0.4445 90)
			(size 0.1397 0.1397)
			(layers "F.Cu" "F.Mask" "F.Paste")
			(net "GND")
			(options
				(clearance outline)
				(anchor circle)
			)
			(primitives
				(gr_poly
					(pts
						(arc
							(start -0.1778 -0.2794)
							(mid -0.249642 -0.249642)
							(end -0.2794 -0.1778)
						)
						(arc
							(start -0.2794 0.1778)
							(mid -0.249642 0.249642)
							(end -0.1778 0.2794)
						)
						(arc
							(start 0.1778 0.2794)
							(mid 0.249642 0.249642)
							(end 0.2794 0.1778)
						)
						(arc
							(start 0.2794 -0.1778)
							(mid 0.249642 -0.249642)
							(end 0.1778 -0.2794)
						)
					)
					(width 0)
					(fill yes)
				)
			)
		)
	)
	(footprint ""
		(layer "F.Cu")
		(at 431.419 -33.02)
		(property "Reference" "Q174"
			(at 0 0 0)
			(layer "F.SilkS")
			(hide yes)
			(effects
				(font
					(size 1.27 1.27)
				)
			)
		)
		(property "Value" "AO4407AL-GP"
			(at -3.707384 -1.5367 0)
			(unlocked yes)
			(layer "F.Fab")
			(hide yes)
			(effects
				(font
					(size 1.016 1.016)
					(thickness 0.1524)
				)
			)
		)
		(property "Device Type" "SOIC8H69"
			(at -3.707384 -3.0607 0)
			(unlocked yes)
			(layer "F.Fab")
			(hide yes)
			(effects
				(font
					(size 1.016 1.016)
					(thickness 0.1524)
				)
			)
		)
		(duplicate_pad_numbers_are_jumpers no)
		(fp_line
			(start -2.7432 -1.4224)
			(end -2.7432 1.4224)
			(stroke
				(width 0.1524)
				(type default)
			)
			(layer "F.SilkS")
		)
		(fp_line
			(start -2.7432 1.4224)
			(end -2.6416 1.4224)
			(stroke
				(width 0.1524)
				(type default)
			)
			(layer "F.SilkS")
		)
		(fp_line
			(start -2.7432 1.4224)
			(end 2.1336 1.4224)
			(stroke
				(width 0.1524)
				(type default)
			)
			(layer "F.SilkS")
		)
		(fp_line
			(start -2.7178 -0.508)
			(end -2.1844 -0.0508)
			(stroke
				(width 0.1524)
				(type default)
			)
			(layer "F.SilkS")
		)
		(fp_line
			(start -2.6289 3.4417)
			(end -2.6289 1.4732)
			(stroke
				(width 0.381)
				(type default)
			)
			(layer "F.SilkS")
		)
		(fp_line
			(start -2.1844 -0.0508)
			(end -2.7178 0.508)
			(stroke
				(width 0.1524)
				(type default)
			)
			(layer "F.SilkS")
		)
		(fp_line
			(start 2.1336 -1.4224)
			(end -2.7432 -1.4224)
			(stroke
				(width 0.1524)
				(type default)
			)
			(layer "F.SilkS")
		)
		(fp_line
			(start 2.1336 1.4224)
			(end 2.1336 -1.4224)
			(stroke
				(width 0.1524)
				(type default)
			)
			(layer "F.SilkS")
		)
		(fp_poly
			(pts
				(xy -2.2098 -1.4224) (xy -2.2098 1.4224) (xy 2.2098 1.4224) (xy 2.2098 -1.4224)
			)
			(stroke
				(width 0)
				(type default)
			)
			(fill yes)
			(layer "F.SilkS")
		)
		(fp_rect
			(start -2.450084 2.999994)
			(end 2.450084 -2.999994)
			(stroke
				(width 0)
				(type default)
			)
			(fill no)
			(layer "F.CrtYd")
		)
		(fp_poly
			(pts
				(xy -2.8194 3.6322) (xy -2.8194 -3.6322) (xy 2.8194 -3.6322) (xy 2.8194 1.18364) (xy 2.450084 1.18364)
				(xy 2.450084 -2.999994) (xy -2.450084 -2.999994) (xy -2.450084 2.999994) (xy 2.450084 2.999994)
				(xy 2.450084 1.18618) (xy 2.8194 1.18618) (xy 2.8194 3.6322)
			)
			(stroke
				(width 0)
				(type default)
			)
			(fill no)
			(layer "F.CrtYd")
		)
		(fp_rect
			(start -2.8194 3.6322)
			(end 2.8194 -3.6322)
			(stroke
				(width 0)
				(type default)
			)
			(fill no)
			(layer "F.Fab")
		)
		(pad "1" smd rect
			(at -1.905 2.54)
			(size 0.635 1.651)
			(layers "F.Cu" "F.Mask" "F.Paste")
			(net "P12V_B")
		)
		(pad "2" smd rect
			(at -0.635 2.54)
			(size 0.635 1.651)
			(layers "F.Cu" "F.Mask" "F.Paste")
			(net "P12V_B")
		)
		(pad "3" smd rect
			(at 0.635 2.54)
			(size 0.635 1.651)
			(layers "F.Cu" "F.Mask" "F.Paste")
			(net "P12V_B")
		)
		(pad "4" smd rect
			(at 1.905 2.54)
			(size 0.635 1.651)
			(layers "F.Cu" "F.Mask" "F.Paste")
			(net "SW_HDD_N33")
		)
		(pad "5" smd rect
			(at 1.905 -2.54)
			(size 0.635 1.651)
			(layers "F.Cu" "F.Mask" "F.Paste")
			(net "P12V_HDD33")
		)
		(pad "6" smd rect
			(at 0.635 -2.54)
			(size 0.635 1.651)
			(layers "F.Cu" "F.Mask" "F.Paste")
			(net "P12V_HDD33")
		)
		(pad "7" smd rect
			(at -0.635 -2.54)
			(size 0.635 1.651)
			(layers "F.Cu" "F.Mask" "F.Paste")
			(net "P12V_HDD33")
		)
		(pad "8" smd rect
			(at -1.905 -2.54)
			(size 0.635 1.651)
			(layers "F.Cu" "F.Mask" "F.Paste")
			(net "P12V_HDD33")
		)
	)
	(footprint ""
		(layer "F.Cu")
		(at 67.1068 -266.065 90)
		(property "Reference" "R176"
			(at 0 0 90)
			(layer "F.SilkS")
			(hide yes)
			(effects
				(font
					(size 1.27 1.27)
				)
			)
		)
		(property "Value" "220R3F-1-GP"
			(at -0.0254 -2.5146 90)
			(unlocked yes)
			(layer "F.Fab")
			(hide yes)
			(effects
				(font
					(size 1.016 1.016)
					(thickness 0.1524)
				)
			)
		)
		(property "Device Type" "R603H22"
			(at -0.0254 -4.0386 90)
			(unlocked yes)
			(layer "F.Fab")
			(hide yes)
			(effects
				(font
					(size 1.016 1.016)
					(thickness 0.1524)
				)
			)
		)
		(duplicate_pad_numbers_are_jumpers no)
		(fp_line
			(start 0.2032 0)
			(end 0.4826 0)
			(stroke
				(width 0.2032)
				(type default)
			)
			(layer "F.SilkS")
		)
		(fp_line
			(start -0.4826 0)
			(end -0.2032 0)
			(stroke
				(width 0.2032)
				(type default)
			)
			(layer "F.SilkS")
		)
		(fp_rect
			(start -0.5842 1.3335)
			(end 0.5842 -1.3335)
			(stroke
				(width 0)
				(type default)
			)
			(fill no)
			(layer "F.CrtYd")
		)
		(fp_rect
			(start -0.5842 1.3335)
			(end 0.5842 -1.3335)
			(stroke
				(width 0)
				(type default)
			)
			(fill no)
			(layer "F.Fab")
		)
		(pad "1" smd custom
			(at 0 -0.762 90)
			(size 0.2159 0.2159)
			(layers "F.Cu" "F.Mask" "F.Paste")
			(net "HDD_PRSNT_1")
			(options
				(clearance outline)
				(anchor circle)
			)
			(primitives
				(gr_poly
					(pts
						(arc
							(start -0.3302 -0.4318)
							(mid -0.402042 -0.402042)
							(end -0.4318 -0.3302)
						)
						(arc
							(start -0.4318 0.3302)
							(mid -0.402042 0.402042)
							(end -0.3302 0.4318)
						)
						(arc
							(start 0.3302 0.4318)
							(mid 0.402042 0.402042)
							(end 0.4318 0.3302)
						)
						(arc
							(start 0.4318 -0.3302)
							(mid 0.402042 -0.402042)
							(end 0.3302 -0.4318)
						)
					)
					(width 0)
					(fill yes)
				)
			)
		)
		(pad "2" smd custom
			(at 0 0.762 90)
			(size 0.2159 0.2159)
			(layers "F.Cu" "F.Mask" "F.Paste")
			(net "DRIVE_B_1_INS")
			(options
				(clearance outline)
				(anchor circle)
			)
			(primitives
				(gr_poly
					(pts
						(arc
							(start -0.3302 -0.4318)
							(mid -0.402042 -0.402042)
							(end -0.4318 -0.3302)
						)
						(arc
							(start -0.4318 0.3302)
							(mid -0.402042 0.402042)
							(end -0.3302 0.4318)
						)
						(arc
							(start 0.3302 0.4318)
							(mid 0.402042 0.402042)
							(end 0.4318 0.3302)
						)
						(arc
							(start 0.4318 -0.3302)
							(mid 0.402042 -0.402042)
							(end 0.3302 -0.4318)
						)
					)
					(width 0)
					(fill yes)
				)
			)
		)
	)
	(footprint ""
		(layer "F.Cu")
		(at 454.98766 -223.994218 90)
		(property "Reference" "C657"
			(at 0 0 90)
			(layer "F.SilkS")
			(hide yes)
			(effects
				(font
					(size 1.27 1.27)
				)
			)
		)
		(property "Value" "SC10U16V5KX-7-GP-U"
			(at -0.0762 -6.1214 90)
			(unlocked yes)
			(layer "F.Fab")
			(hide yes)
			(effects
				(font
					(size 1.016 1.016)
					(thickness 0.1524)
				)
			)
		)
		(property "Device Type" "C805H58"
			(at -0.0762 -8.1534 90)
			(unlocked yes)
			(layer "F.Fab")
			(hide yes)
			(effects
				(font
					(size 1.016 1.016)
					(thickness 0.1524)
				)
			)
		)
		(duplicate_pad_numbers_are_jumpers no)
		(fp_line
			(start 0.635 0)
			(end -0.635 0)
			(stroke
				(width 0.508)
				(type default)
			)
			(layer "F.SilkS")
		)
		(fp_rect
			(start -0.9652 1.778)
			(end 0.9652 -1.778)
			(stroke
				(width 0)
				(type default)
			)
			(fill no)
			(layer "F.CrtYd")
		)
		(fp_poly
			(pts
				(xy -0.9652 -1.778) (xy 0.9652 -1.778) (xy 0.9652 1.778) (xy -0.9652 1.778)
			)
			(stroke
				(width 0)
				(type default)
			)
			(fill no)
			(layer "F.Fab")
		)
		(pad "1" smd rect
			(at 0 -0.9652 90)
			(size 1.397 1.143)
			(layers "F.Cu" "F.Mask" "F.Paste")
			(net "P12V_B_3_VIN_U33")
		)
		(pad "2" smd rect
			(at 0 0.9652 90)
			(size 1.397 1.143)
			(layers "F.Cu" "F.Mask" "F.Paste")
			(net "GND")
		)
	)
	(footprint ""
		(layer "F.Cu")
		(at 144.653 -131.572)
		(property "Reference" "R455"
			(at 0 0 0)
			(layer "F.SilkS")
			(hide yes)
			(effects
				(font
					(size 1.27 1.27)
				)
			)
		)
		(property "Value" "0R2J-2-GP"
			(at 0.064008 -3.993896 0)
			(unlocked yes)
			(layer "F.Fab")
			(hide yes)
			(effects
				(font
					(size 1.016 1.016)
					(thickness 0.1524)
				)
			)
		)
		(property "Device Type" "R402H16"
			(at 0.064008 -5.517896 0)
			(unlocked yes)
			(layer "F.Fab")
			(hide yes)
			(effects
				(font
					(size 1.016 1.016)
					(thickness 0.1524)
				)
			)
		)
		(duplicate_pad_numbers_are_jumpers no)
		(fp_line
			(start -0.508 -0.9398)
			(end -0.508 0.9398)
			(stroke
				(width 0.1524)
				(type default)
			)
			(layer "F.SilkS")
		)
		(fp_line
			(start 0.508 -0.9398)
			(end -0.508 -0.9398)
			(stroke
				(width 0.1524)
				(type default)
			)
			(layer "F.SilkS")
		)
		(fp_rect
			(start -0.508 0.9398)
			(end 0.508 -0.9398)
			(stroke
				(width 0)
				(type default)
			)
			(fill no)
			(layer "F.CrtYd")
		)
		(fp_rect
			(start -0.508 0.9398)
			(end 0.508 -0.9398)
			(stroke
				(width 0)
				(type default)
			)
			(fill no)
			(layer "F.Fab")
		)
		(pad "1" smd custom
			(at 0 -0.4445)
			(size 0.1397 0.1397)
			(layers "F.Cu" "F.Mask" "F.Paste")
			(net "SW_HDD_G16")
			(options
				(clearance outline)
				(anchor circle)
			)
			(primitives
				(gr_poly
					(pts
						(arc
							(start -0.1778 -0.2794)
							(mid -0.249642 -0.249642)
							(end -0.2794 -0.1778)
						)
						(arc
							(start -0.2794 0.1778)
							(mid -0.249642 0.249642)
							(end -0.1778 0.2794)
						)
						(arc
							(start 0.1778 0.2794)
							(mid 0.249642 0.249642)
							(end 0.2794 0.1778)
						)
						(arc
							(start 0.2794 -0.1778)
							(mid 0.249642 -0.249642)
							(end 0.1778 -0.2794)
						)
					)
					(width 0)
					(fill yes)
				)
			)
		)
		(pad "2" smd custom
			(at 0 0.4445)
			(size 0.1397 0.1397)
			(layers "F.Cu" "F.Mask" "F.Paste")
			(net "SW_HDD_R16")
			(options
				(clearance outline)
				(anchor circle)
			)
			(primitives
				(gr_poly
					(pts
						(arc
							(start -0.1778 -0.2794)
							(mid -0.249642 -0.249642)
							(end -0.2794 -0.1778)
						)
						(arc
							(start -0.2794 0.1778)
							(mid -0.249642 0.249642)
							(end -0.1778 0.2794)
						)
						(arc
							(start 0.1778 0.2794)
							(mid 0.249642 0.249642)
							(end 0.2794 0.1778)
						)
						(arc
							(start 0.2794 -0.1778)
							(mid 0.249642 -0.249642)
							(end 0.1778 -0.2794)
						)
					)
					(width 0)
					(fill yes)
				)
			)
		)
	)
	(footprint ""
		(layer "F.Cu")
		(at 318.2112 -262.8138 180)
		(property "Reference" "R257"
			(at 0 0 180)
			(layer "F.SilkS")
			(hide yes)
			(effects
				(font
					(size 1.27 1.27)
				)
			)
		)
		(property "Value" "220R3F-1-GP"
			(at -0.0254 -2.5146 180)
			(unlocked yes)
			(layer "F.Fab")
			(hide yes)
			(effects
				(font
					(size 1.016 1.016)
					(thickness 0.1524)
				)
			)
		)
		(property "Device Type" "R603H22"
			(at -0.0254 -4.0386 180)
			(unlocked yes)
			(layer "F.Fab")
			(hide yes)
			(effects
				(font
					(size 1.016 1.016)
					(thickness 0.1524)
				)
			)
		)
		(duplicate_pad_numbers_are_jumpers no)
		(fp_line
			(start 0.2032 0)
			(end 0.4826 0)
			(stroke
				(width 0.2032)
				(type default)
			)
			(layer "F.SilkS")
		)
		(fp_line
			(start -0.4826 0)
			(end -0.2032 0)
			(stroke
				(width 0.2032)
				(type default)
			)
			(layer "F.SilkS")
		)
		(fp_rect
			(start -0.5842 1.3335)
			(end 0.5842 -1.3335)
			(stroke
				(width 0)
				(type default)
			)
			(fill no)
			(layer "F.CrtYd")
		)
		(fp_rect
			(start -0.5842 1.3335)
			(end 0.5842 -1.3335)
			(stroke
				(width 0)
				(type default)
			)
			(fill no)
			(layer "F.Fab")
		)
		(pad "1" smd custom
			(at 0 -0.762 180)
			(size 0.2159 0.2159)
			(layers "F.Cu" "F.Mask" "F.Paste")
			(net "HDD_PRSNT_6")
			(options
				(clearance outline)
				(anchor circle)
			)
			(primitives
				(gr_poly
					(pts
						(arc
							(start -0.3302 -0.4318)
							(mid -0.402042 -0.402042)
							(end -0.4318 -0.3302)
						)
						(arc
							(start -0.4318 0.3302)
							(mid -0.402042 0.402042)
							(end -0.3302 0.4318)
						)
						(arc
							(start 0.3302 0.4318)
							(mid 0.402042 0.402042)
							(end 0.4318 0.3302)
						)
						(arc
							(start 0.4318 -0.3302)
							(mid 0.402042 -0.402042)
							(end 0.3302 -0.4318)
						)
					)
					(width 0)
					(fill yes)
				)
			)
		)
		(pad "2" smd custom
			(at 0 0.762 180)
			(size 0.2159 0.2159)
			(layers "F.Cu" "F.Mask" "F.Paste")
			(net "DRIVE_B_6_INS")
			(options
				(clearance outline)
				(anchor circle)
			)
			(primitives
				(gr_poly
					(pts
						(arc
							(start -0.3302 -0.4318)
							(mid -0.402042 -0.402042)
							(end -0.4318 -0.3302)
						)
						(arc
							(start -0.4318 0.3302)
							(mid -0.402042 0.402042)
							(end -0.3302 0.4318)
						)
						(arc
							(start 0.3302 0.4318)
							(mid 0.402042 0.402042)
							(end 0.4318 0.3302)
						)
						(arc
							(start 0.4318 -0.3302)
							(mid 0.402042 -0.402042)
							(end 0.3302 -0.4318)
						)
					)
					(width 0)
					(fill yes)
				)
			)
		)
	)
	(footprint ""
		(layer "F.Cu")
		(at 175.550068 -65.39992)
		(property "Reference" "LED18"
			(at 0 0 0)
			(layer "F.SilkS")
			(hide yes)
			(effects
				(font
					(size 1.27 1.27)
				)
			)
		)
		(property "Value" "LED-BY-19-GP"
			(at -2.132076 1.414018 0)
			(unlocked yes)
			(layer "F.Fab")
			(hide yes)
			(effects
				(font
					(size 1.016 1.016)
					(thickness 0.1524)
				)
			)
		)
		(property "Device Type" "LED-1615-4PH26"
			(at -2.132076 -0.109982 0)
			(unlocked yes)
			(layer "F.Fab")
			(hide yes)
			(effects
				(font
					(size 1.016 1.016)
					(thickness 0.1524)
				)
			)
		)
		(duplicate_pad_numbers_are_jumpers no)
		(fp_line
			(start -1.2954 0.254)
			(end -1.2954 1.6002)
			(stroke
				(width 0.508)
				(type default)
			)
			(layer "F.SilkS")
		)
		(fp_line
			(start -1.2954 1.6002)
			(end 1.2954 1.6002)
			(stroke
				(width 0.508)
				(type default)
			)
			(layer "F.SilkS")
		)
		(fp_line
			(start -1.1176 -1.4224)
			(end 1.1176 -1.4224)
			(stroke
				(width 0.1524)
				(type default)
			)
			(layer "F.SilkS")
		)
		(fp_line
			(start -1.1176 1.4224)
			(end -1.1176 -1.4224)
			(stroke
				(width 0.1524)
				(type default)
			)
			(layer "F.SilkS")
		)
		(fp_line
			(start 1.1176 -1.4224)
			(end 1.1176 1.4224)
			(stroke
				(width 0.1524)
				(type default)
			)
			(layer "F.SilkS")
		)
		(fp_line
			(start 1.1176 1.4224)
			(end -1.1176 1.4224)
			(stroke
				(width 0.1524)
				(type default)
			)
			(layer "F.SilkS")
		)
		(fp_line
			(start 1.2954 1.6002)
			(end 1.2954 0.254)
			(stroke
				(width 0.508)
				(type default)
			)
			(layer "F.SilkS")
		)
		(fp_rect
			(start -0.7493 0.8001)
			(end 0.7493 -0.8001)
			(stroke
				(width 0)
				(type default)
			)
			(fill no)
			(layer "F.CrtYd")
		)
		(fp_poly
			(pts
				(xy -1.3716 1.6764) (xy -1.3716 -1.6764) (xy 1.3716 -1.6764) (xy 1.3716 0.0635) (xy 0.7493 0.0635)
				(xy 0.7493 -0.8001) (xy -0.7493 -0.8001) (xy -0.7493 0.8001) (xy 0.7493 0.8001) (xy 0.7493 0.0762)
				(xy 1.3716 0.0762) (xy 1.3716 1.6764)
			)
			(stroke
				(width 0)
				(type default)
			)
			(fill no)
			(layer "F.CrtYd")
		)
		(fp_rect
			(start -1.3716 1.6764)
			(end 1.3716 -1.6764)
			(stroke
				(width 0)
				(type default)
			)
			(fill no)
			(layer "F.Fab")
		)
		(pad "1" smd rect
			(at 0.50038 -0.73025)
			(size 0.7112 0.8636)
			(layers "F.Cu" "F.Mask" "F.Paste")
			(net "DRV_ACT_17")
		)
		(pad "2" smd rect
			(at -0.50038 -0.73025)
			(size 0.7112 0.8636)
			(layers "F.Cu" "F.Mask" "F.Paste")
			(net "FLT_HDD17")
		)
		(pad "3" smd rect
			(at 0.50038 0.73025)
			(size 0.7112 0.8636)
			(layers "F.Cu" "F.Mask" "F.Paste")
			(net "DRV_ACT_17_N")
		)
		(pad "4" smd rect
			(at -0.50038 0.73025)
			(size 0.7112 0.8636)
			(layers "F.Cu" "F.Mask" "F.Paste")
			(net "FLT_HDD17_N")
		)
	)
	(footprint ""
		(layer "F.Cu")
		(at 383.8448 -146.6342 180)
		(property "Reference" "R530"
			(at 0 0 180)
			(layer "F.SilkS")
			(hide yes)
			(effects
				(font
					(size 1.27 1.27)
				)
			)
		)
		(property "Value" "10KR2F-2-GP"
			(at 0.064008 -3.993896 180)
			(unlocked yes)
			(layer "F.Fab")
			(hide yes)
			(effects
				(font
					(size 1.016 1.016)
					(thickness 0.1524)
				)
			)
		)
		(property "Device Type" "R402H16"
			(at 0.064008 -5.517896 180)
			(unlocked yes)
			(layer "F.Fab")
			(hide yes)
			(effects
				(font
					(size 1.016 1.016)
					(thickness 0.1524)
				)
			)
		)
		(duplicate_pad_numbers_are_jumpers no)
		(fp_line
			(start 0.508 -0.9398)
			(end -0.508 -0.9398)
			(stroke
				(width 0.1524)
				(type default)
			)
			(layer "F.SilkS")
		)
		(fp_line
			(start -0.508 -0.9398)
			(end -0.508 0.9398)
			(stroke
				(width 0.1524)
				(type default)
			)
			(layer "F.SilkS")
		)
		(fp_rect
			(start -0.508 0.9398)
			(end 0.508 -0.9398)
			(stroke
				(width 0)
				(type default)
			)
			(fill no)
			(layer "F.CrtYd")
		)
		(fp_rect
			(start -0.508 0.9398)
			(end 0.508 -0.9398)
			(stroke
				(width 0)
				(type default)
			)
			(fill no)
			(layer "F.Fab")
		)
		(pad "1" smd custom
			(at 0 -0.4445 180)
			(size 0.1397 0.1397)
			(layers "F.Cu" "F.Mask" "F.Paste")
			(net "P3V3_STBY_B")
			(options
				(clearance outline)
				(anchor circle)
			)
			(primitives
				(gr_poly
					(pts
						(arc
							(start -0.1778 -0.2794)
							(mid -0.249642 -0.249642)
							(end -0.2794 -0.1778)
						)
						(arc
							(start -0.2794 0.1778)
							(mid -0.249642 0.249642)
							(end -0.1778 0.2794)
						)
						(arc
							(start 0.1778 0.2794)
							(mid 0.249642 0.249642)
							(end 0.2794 0.1778)
						)
						(arc
							(start 0.2794 -0.1778)
							(mid 0.249642 -0.249642)
							(end 0.1778 -0.2794)
						)
					)
					(width 0)
					(fill yes)
				)
			)
		)
		(pad "2" smd custom
			(at 0 0.4445 180)
			(size 0.1397 0.1397)
			(layers "F.Cu" "F.Mask" "F.Paste")
			(net "HDD_PRSNT_20")
			(options
				(clearance outline)
				(anchor circle)
			)
			(primitives
				(gr_poly
					(pts
						(arc
							(start -0.1778 -0.2794)
							(mid -0.249642 -0.249642)
							(end -0.2794 -0.1778)
						)
						(arc
							(start -0.2794 0.1778)
							(mid -0.249642 0.249642)
							(end -0.1778 0.2794)
						)
						(arc
							(start 0.1778 0.2794)
							(mid 0.249642 0.249642)
							(end 0.2794 0.1778)
						)
						(arc
							(start 0.2794 -0.1778)
							(mid 0.249642 -0.249642)
							(end 0.1778 -0.2794)
						)
					)
					(width 0)
					(fill yes)
				)
			)
		)
	)
	(footprint ""
		(layer "F.Cu")
		(at 221.996 -223.139 90)
		(property "Reference" "R22"
			(at 0 0 90)
			(layer "F.SilkS")
			(hide yes)
			(effects
				(font
					(size 1.27 1.27)
				)
			)
		)
		(property "Value" "0R2J-2-GP"
			(at 0.064008 -3.993896 90)
			(unlocked yes)
			(layer "F.Fab")
			(hide yes)
			(effects
				(font
					(size 1.016 1.016)
					(thickness 0.1524)
				)
			)
		)
		(property "Device Type" "R402H16"
			(at 0.064008 -5.517896 90)
			(unlocked yes)
			(layer "F.Fab")
			(hide yes)
			(effects
				(font
					(size 1.016 1.016)
					(thickness 0.1524)
				)
			)
		)
		(duplicate_pad_numbers_are_jumpers no)
		(fp_line
			(start 0.508 -0.9398)
			(end -0.508 -0.9398)
			(stroke
				(width 0.1524)
				(type default)
			)
			(layer "F.SilkS")
		)
		(fp_line
			(start -0.508 -0.9398)
			(end -0.508 0.9398)
			(stroke
				(width 0.1524)
				(type default)
			)
			(layer "F.SilkS")
		)
		(fp_rect
			(start -0.508 0.9398)
			(end 0.508 -0.9398)
			(stroke
				(width 0)
				(type default)
			)
			(fill no)
			(layer "F.CrtYd")
		)
		(fp_rect
			(start -0.508 0.9398)
			(end 0.508 -0.9398)
			(stroke
				(width 0)
				(type default)
			)
			(fill no)
			(layer "F.Fab")
		)
		(pad "1" smd custom
			(at 0 -0.4445 90)
			(size 0.1397 0.1397)
			(layers "F.Cu" "F.Mask" "F.Paste")
			(net "IO_EXP1_LED_SCL")
			(options
				(clearance outline)
				(anchor circle)
			)
			(primitives
				(gr_poly
					(pts
						(arc
							(start -0.1778 -0.2794)
							(mid -0.249642 -0.249642)
							(end -0.2794 -0.1778)
						)
						(arc
							(start -0.2794 0.1778)
							(mid -0.249642 0.249642)
							(end -0.1778 0.2794)
						)
						(arc
							(start 0.1778 0.2794)
							(mid 0.249642 0.249642)
							(end 0.2794 0.1778)
						)
						(arc
							(start 0.2794 -0.1778)
							(mid 0.249642 -0.249642)
							(end 0.1778 -0.2794)
						)
					)
					(width 0)
					(fill yes)
				)
			)
		)
		(pad "2" smd custom
			(at 0 0.4445 90)
			(size 0.1397 0.1397)
			(layers "F.Cu" "F.Mask" "F.Paste")
			(net "I2C_DRIVE_B_FLT_LED_SCL")
			(options
				(clearance outline)
				(anchor circle)
			)
			(primitives
				(gr_poly
					(pts
						(arc
							(start -0.1778 -0.2794)
							(mid -0.249642 -0.249642)
							(end -0.2794 -0.1778)
						)
						(arc
							(start -0.2794 0.1778)
							(mid -0.249642 0.249642)
							(end -0.1778 0.2794)
						)
						(arc
							(start 0.1778 0.2794)
							(mid 0.249642 0.249642)
							(end 0.2794 0.1778)
						)
						(arc
							(start 0.2794 -0.1778)
							(mid 0.249642 -0.249642)
							(end 0.1778 -0.2794)
						)
					)
					(width 0)
					(fill yes)
				)
			)
		)
	)
	(footprint ""
		(layer "F.Cu")
		(at 261.960868 -209.582258 -90)
		(property "Reference" "R1294"
			(at 0 0 270)
			(layer "F.SilkS")
			(hide yes)
			(effects
				(font
					(size 1.27 1.27)
				)
			)
		)
		(property "Value" "1KR2J-1-GP"
			(at 0.064008 -3.993896 270)
			(unlocked yes)
			(layer "F.Fab")
			(hide yes)
			(effects
				(font
					(size 1.016 1.016)
					(thickness 0.1524)
				)
			)
		)
		(property "Device Type" "R402H16"
			(at 0.064008 -5.517896 270)
			(unlocked yes)
			(layer "F.Fab")
			(hide yes)
			(effects
				(font
					(size 1.016 1.016)
					(thickness 0.1524)
				)
			)
		)
		(duplicate_pad_numbers_are_jumpers no)
		(fp_line
			(start -0.508 -0.9398)
			(end -0.508 0.9398)
			(stroke
				(width 0.1524)
				(type default)
			)
			(layer "F.SilkS")
		)
		(fp_line
			(start 0.508 -0.9398)
			(end -0.508 -0.9398)
			(stroke
				(width 0.1524)
				(type default)
			)
			(layer "F.SilkS")
		)
		(fp_rect
			(start -0.508 0.9398)
			(end 0.508 -0.9398)
			(stroke
				(width 0)
				(type default)
			)
			(fill no)
			(layer "F.CrtYd")
		)
		(fp_rect
			(start -0.508 0.9398)
			(end 0.508 -0.9398)
			(stroke
				(width 0)
				(type default)
			)
			(fill no)
			(layer "F.Fab")
		)
		(pad "1" smd custom
			(at 0 -0.4445 270)
			(size 0.1397 0.1397)
			(layers "F.Cu" "F.Mask" "F.Paste")
			(net "P3V3_STBY_B")
			(options
				(clearance outline)
				(anchor circle)
			)
			(primitives
				(gr_poly
					(pts
						(arc
							(start -0.1778 -0.2794)
							(mid -0.249642 -0.249642)
							(end -0.2794 -0.1778)
						)
						(arc
							(start -0.2794 0.1778)
							(mid -0.249642 0.249642)
							(end -0.1778 0.2794)
						)
						(arc
							(start 0.1778 0.2794)
							(mid 0.249642 0.249642)
							(end 0.2794 0.1778)
						)
						(arc
							(start 0.2794 -0.1778)
							(mid 0.249642 -0.249642)
							(end 0.1778 -0.2794)
						)
					)
					(width 0)
					(fill yes)
				)
			)
		)
		(pad "2" smd custom
			(at 0 0.4445 270)
			(size 0.1397 0.1397)
			(layers "F.Cu" "F.Mask" "F.Paste")
			(net "I2C_DRIVE_B_PWR_SCL")
			(options
				(clearance outline)
				(anchor circle)
			)
			(primitives
				(gr_poly
					(pts
						(arc
							(start -0.1778 -0.2794)
							(mid -0.249642 -0.249642)
							(end -0.2794 -0.1778)
						)
						(arc
							(start -0.2794 0.1778)
							(mid -0.249642 0.249642)
							(end -0.1778 0.2794)
						)
						(arc
							(start 0.1778 0.2794)
							(mid 0.249642 0.249642)
							(end 0.2794 0.1778)
						)
						(arc
							(start 0.2794 -0.1778)
							(mid 0.249642 -0.249642)
							(end 0.1778 -0.2794)
						)
					)
					(width 0)
					(fill yes)
				)
			)
		)
	)
	(footprint ""
		(layer "F.Cu")
		(at 357.100124 -143.91005 -90)
		(property "Reference" "HDDSAS19"
			(at 0 0 270)
			(layer "F.SilkS")
			(hide yes)
			(effects
				(font
					(size 1.27 1.27)
				)
			)
		)
		(property "Value" "SKT-SAS15P-14P-45-GP"
			(at -20.7645 -8.9789 270)
			(unlocked yes)
			(layer "F.Fab")
			(hide yes)
			(effects
				(font
					(size 1.016 1.016)
					(thickness 0.1524)
				)
			)
		)
		(property "Device Type" "10120818-001C-TRLF"
			(at -20.7645 -10.5029 270)
			(unlocked yes)
			(layer "F.Fab")
			(hide yes)
			(effects
				(font
					(size 1.016 1.016)
					(thickness 0.1524)
				)
			)
		)
		(duplicate_pad_numbers_are_jumpers no)
		(fp_line
			(start 1.651 4.2926)
			(end 1.651 3.0099)
			(stroke
				(width 0.1524)
				(type default)
			)
			(layer "F.SilkS")
		)
		(fp_line
			(start 8.509 4.2926)
			(end 1.651 4.2926)
			(stroke
				(width 0.1524)
				(type default)
			)
			(layer "F.SilkS")
		)
		(fp_line
			(start -23.4188 3.0099)
			(end -23.4188 -3.2512)
			(stroke
				(width 0.1524)
				(type default)
			)
			(layer "F.SilkS")
		)
		(fp_line
			(start 1.651 3.0099)
			(end -23.4188 3.0099)
			(stroke
				(width 0.1524)
				(type default)
			)
			(layer "F.SilkS")
		)
		(fp_line
			(start 8.509 3.0099)
			(end 8.509 4.2926)
			(stroke
				(width 0.1524)
				(type default)
			)
			(layer "F.SilkS")
		)
		(fp_line
			(start 23.4188 3.0099)
			(end 8.509 3.0099)
			(stroke
				(width 0.1524)
				(type default)
			)
			(layer "F.SilkS")
		)
		(fp_line
			(start -23.4188 -3.2512)
			(end 23.4188 -3.2512)
			(stroke
				(width 0.1524)
				(type default)
			)
			(layer "F.SilkS")
		)
		(fp_line
			(start 23.4188 -3.2512)
			(end 23.4188 3.0099)
			(stroke
				(width 0.1524)
				(type default)
			)
			(layer "F.SilkS")
		)
		(fp_line
			(start 15.5067 -3.3401)
			(end 16.2687 -3.3401)
			(stroke
				(width 0.3302)
				(type default)
			)
			(layer "F.SilkS")
		)
		(fp_poly
			(pts
				(xy 15.868904 -3.230372) (xy 16.503904 -3.865372) (xy 15.233904 -3.865372)
			)
			(stroke
				(width 0)
				(type default)
			)
			(fill yes)
			(layer "F.SilkS")
		)
		(fp_poly
			(pts
				(xy -22.8727 -2.7559) (xy 22.8727 -2.7559) (xy 22.8727 2.7559) (xy 8.255 2.7559) (xy 8.255 3.5179)
				(xy 1.905 3.5179) (xy 1.905 2.7559) (xy -22.8727 2.7559)
			)
			(stroke
				(width 0)
				(type default)
			)
			(fill no)
			(layer "F.CrtYd")
		)
		(fp_poly
			(pts
				(xy 1.397 4.5466) (xy 1.397 3.2639) (xy -23.6728 3.2639) (xy -23.6728 -3.5052) (xy 23.6728 -3.5052)
				(xy 23.6728 -0.00635) (xy 22.8727 -0.00635) (xy 22.8727 -2.7559) (xy -22.8727 -2.7559) (xy -22.8727 2.7559)
				(xy 1.905 2.7559) (xy 1.905 3.5179) (xy 8.255 3.5179) (xy 8.255 2.7559) (xy 22.8727 2.7559) (xy 22.8727 0.00635)
				(xy 23.6728 0.00635) (xy 23.6728 3.2639) (xy 8.763 3.2639) (xy 8.763 4.5466)
			)
			(stroke
				(width 0)
				(type default)
			)
			(fill no)
			(layer "F.CrtYd")
		)
		(fp_poly
			(pts
				(xy 1.397 4.5466) (xy 1.397 3.2639) (xy -23.6728 3.2639) (xy -23.6728 -3.5052) (xy 23.6728 -3.5052)
				(xy 23.6728 3.2639) (xy 8.763 3.2639) (xy 8.763 4.5466)
			)
			(stroke
				(width 0)
				(type default)
			)
			(fill no)
			(layer "F.Fab")
		)
		(pad "" np_thru_hole circle
			(at -18.874994 0 270)
			(size 0.254 0.254)
			(drill 1.3462)
			(layers "*.Cu" "*.Mask")
			(clearance 0.9017)
			(thermal_gap 0.9017)
		)
		(pad "" np_thru_hole circle
			(at 18.874994 0 270)
			(size 0.254 0.254)
			(drill 0.9398)
			(layers "*.Cu" "*.Mask")
			(clearance 0.6985)
			(thermal_gap 0.6985)
		)
		(pad "G1" smd rect
			(at 21.874988 0 270)
			(size 2.5908 2.5908)
			(layers "F.Cu" "F.Mask" "F.Paste")
			(net "GND")
		)
		(pad "G2" smd rect
			(at -21.874988 0 270)
			(size 2.5908 2.5908)
			(layers "F.Cu" "F.Mask" "F.Paste")
			(net "GND")
		)
		(pad "P1" smd rect
			(at 1.905 -1.82499 270)
			(size 0.6096 2.3622)
			(layers "F.Cu" "F.Mask" "F.Paste")
			(net "Net_1704")
		)
		(pad "P2" smd rect
			(at 0.635 -1.82499 270)
			(size 0.6096 2.3622)
			(layers "F.Cu" "F.Mask" "F.Paste")
			(net "Net_1705")
		)
		(pad "P3" smd rect
			(at -0.635 -1.82499 270)
			(size 0.6096 2.3622)
			(layers "F.Cu" "F.Mask" "F.Paste")
			(net "Net_1706")
		)
		(pad "P4" smd rect
			(at -1.905 -1.82499 270)
			(size 0.6096 2.3622)
			(layers "F.Cu" "F.Mask" "F.Paste")
			(net "GND")
		)
		(pad "P5" smd rect
			(at -3.175 -1.82499 270)
			(size 0.6096 2.3622)
			(layers "F.Cu" "F.Mask" "F.Paste")
			(net "HDD_PRSNT_19")
		)
		(pad "P6" smd rect
			(at -4.445 -1.82499 270)
			(size 0.6096 2.3622)
			(layers "F.Cu" "F.Mask" "F.Paste")
			(net "GND")
		)
		(pad "P7" smd rect
			(at -5.715 -1.82499 270)
			(size 0.6096 2.3622)
			(layers "F.Cu" "F.Mask" "F.Paste")
			(net "5V_PRE_19")
		)
		(pad "P8" smd rect
			(at -6.985 -1.82499 270)
			(size 0.6096 2.3622)
			(layers "F.Cu" "F.Mask" "F.Paste")
			(net "P5V_HDD19")
		)
		(pad "P9" smd rect
			(at -8.255 -1.82499 270)
			(size 0.6096 2.3622)
			(layers "F.Cu" "F.Mask" "F.Paste")
			(net "P5V_HDD19")
		)
		(pad "P10" smd rect
			(at -9.525 -1.82499 270)
			(size 0.6096 2.3622)
			(layers "F.Cu" "F.Mask" "F.Paste")
			(net "GND")
		)
		(pad "P11" smd rect
			(at -10.795 -1.82499 270)
			(size 0.6096 2.3622)
			(layers "F.Cu" "F.Mask" "F.Paste")
			(net "ACT_HDD_19")
		)
		(pad "P12" smd rect
			(at -12.065 -1.82499 270)
			(size 0.6096 2.3622)
			(layers "F.Cu" "F.Mask" "F.Paste")
			(net "GND")
		)
		(pad "P13" smd rect
			(at -13.335 -1.82499 270)
			(size 0.6096 2.3622)
			(layers "F.Cu" "F.Mask" "F.Paste")
			(net "12V_PRE_19")
		)
		(pad "P14" smd rect
			(at -14.605 -1.82499 270)
			(size 0.6096 2.3622)
			(layers "F.Cu" "F.Mask" "F.Paste")
			(net "P12V_HDD19")
		)
		(pad "P15" smd rect
			(at -15.875 -1.82499 270)
			(size 0.6096 2.3622)
			(layers "F.Cu" "F.Mask" "F.Paste")
			(net "P12V_HDD19")
		)
		(pad "S1" smd rect
			(at 15.875 -1.82499 270)
			(size 0.6096 2.3622)
			(layers "F.Cu" "F.Mask" "F.Paste")
			(net "GND")
		)
		(pad "S2" smd rect
			(at 14.605 -1.82499 270)
			(size 0.6096 2.3622)
			(layers "F.Cu" "F.Mask" "F.Paste")
			(net "SAS_HDD_RX_P19")
		)
		(pad "S3" smd rect
			(at 13.335 -1.82499 270)
			(size 0.6096 2.3622)
			(layers "F.Cu" "F.Mask" "F.Paste")
			(net "SAS_HDD_RX_N19")
		)
		(pad "S4" smd rect
			(at 12.065 -1.82499 270)
			(size 0.6096 2.3622)
			(layers "F.Cu" "F.Mask" "F.Paste")
			(net "GND")
		)
		(pad "S5" smd rect
			(at 10.795 -1.82499 270)
			(size 0.6096 2.3622)
			(layers "F.Cu" "F.Mask" "F.Paste")
			(net "PHY_DRV_B_TO_SCC_B_19_DN")
		)
		(pad "S6" smd rect
			(at 9.525 -1.82499 270)
			(size 0.6096 2.3622)
			(layers "F.Cu" "F.Mask" "F.Paste")
			(net "PHY_DRV_B_TO_SCC_B_19_DP")
		)
		(pad "S7" smd rect
			(at 8.255 -1.82499 270)
			(size 0.6096 2.3622)
			(layers "F.Cu" "F.Mask" "F.Paste")
			(net "GND")
		)
		(pad "S8" smd rect
			(at 7.480046 2.845054 270)
			(size 0.508 2.3622)
			(layers "F.Cu" "F.Mask" "F.Paste")
			(net "GND")
		)
		(pad "S9" smd rect
			(at 6.679946 2.845054 270)
			(size 0.508 2.3622)
			(layers "F.Cu" "F.Mask" "F.Paste")
			(net "Net_443")
		)
		(pad "S10" smd rect
			(at 5.8801 2.845054 270)
			(size 0.508 2.3622)
			(layers "F.Cu" "F.Mask" "F.Paste")
			(net "Net_335")
		)
		(pad "S11" smd rect
			(at 5.08 2.845054 270)
			(size 0.508 2.3622)
			(layers "F.Cu" "F.Mask" "F.Paste")
			(net "GND")
		)
		(pad "S12" smd rect
			(at 4.2799 2.845054 270)
			(size 0.508 2.3622)
			(layers "F.Cu" "F.Mask" "F.Paste")
			(net "Net_371")
		)
		(pad "S13" smd rect
			(at 3.480054 2.845054 270)
			(size 0.508 2.3622)
			(layers "F.Cu" "F.Mask" "F.Paste")
			(net "Net_407")
		)
		(pad "S14" smd rect
			(at 2.679954 2.845054 270)
			(size 0.508 2.3622)
			(layers "F.Cu" "F.Mask" "F.Paste")
			(net "GND")
		)
		(zone
			(layer "F.Cu")
			(hatch none 0.5)
			(connect_pads
				(clearance 0)
			)
			(min_thickness 0.25)
			(keepout
				(tracks allowed)
				(vias not_allowed)
				(pads allowed)
				(copperpour not_allowed)
				(footprints allowed)
			)
			(placement
				(enabled no)
				(sheetname "")
			)
			(fill
				(thermal_gap 0.5)
				(thermal_bridge_width 0.5)
				(island_removal_mode 0)
			)
			(polygon
				(pts
					(xy 360.757724 -160.64865) (xy 353.683824 -160.64865) (xy 353.683824 -167.58285) (xy 354.788724 -167.58285)
					(xy 354.788724 -163.46805) (xy 359.411524 -163.46805) (xy 359.411524 -167.58285) (xy 360.757724 -167.58285)
				)
			)
		)
		(zone
			(layer "F.Cu")
			(hatch none 0.5)
			(connect_pads
				(clearance 0)
			)
			(min_thickness 0.25)
			(keepout
				(tracks not_allowed)
				(vias allowed)
				(pads allowed)
				(copperpour not_allowed)
				(footprints allowed)
			)
			(placement
				(enabled no)
				(sheetname "")
			)
			(fill
				(thermal_gap 0.5)
				(thermal_bridge_width 0.5)
				(island_removal_mode 0)
			)
			(polygon
				(pts
					(xy 360.757724 -160.64865) (xy 353.683824 -160.64865) (xy 353.683824 -167.58285) (xy 354.788724 -167.58285)
					(xy 354.788724 -163.46805) (xy 359.411524 -163.46805) (xy 359.411524 -167.58285) (xy 360.757724 -167.58285)
				)
			)
		)
		(zone
			(layer "F.Cu")
			(hatch none 0.5)
			(connect_pads
				(clearance 0)
			)
			(min_thickness 0.25)
			(keepout
				(tracks not_allowed)
				(vias allowed)
				(pads allowed)
				(copperpour not_allowed)
				(footprints allowed)
			)
			(placement
				(enabled no)
				(sheetname "")
			)
			(fill
				(thermal_gap 0.5)
				(thermal_bridge_width 0.5)
				(island_removal_mode 0)
			)
			(polygon
				(pts
					(xy 360.757724 -127.17145) (xy 353.683824 -127.17145) (xy 353.683824 -120.23725) (xy 354.788724 -120.23725)
					(xy 354.788724 -124.35205) (xy 359.411524 -124.35205) (xy 359.411524 -120.23725) (xy 360.757724 -120.23725)
				)
			)
		)
		(zone
			(layer "F.Cu")
			(hatch none 0.5)
			(connect_pads
				(clearance 0)
			)
			(min_thickness 0.25)
			(keepout
				(tracks allowed)
				(vias not_allowed)
				(pads allowed)
				(copperpour not_allowed)
				(footprints allowed)
			)
			(placement
				(enabled no)
				(sheetname "")
			)
			(fill
				(thermal_gap 0.5)
				(thermal_bridge_width 0.5)
				(island_removal_mode 0)
			)
			(polygon
				(pts
					(xy 360.757724 -127.17145) (xy 353.683824 -127.17145) (xy 353.683824 -120.23725) (xy 354.788724 -120.23725)
					(xy 354.788724 -124.35205) (xy 359.411524 -124.35205) (xy 359.411524 -120.23725) (xy 360.757724 -120.23725)
				)
			)
		)
		(zone
			(layers "F.Cu" "B.Cu" "In1.Cu" "In2.Cu" "In3.Cu" "In4.Cu" "In5.Cu" "In6.Cu")
			(hatch none 0.5)
			(connect_pads
				(clearance 0)
			)
			(min_thickness 0.25)
			(keepout
				(tracks not_allowed)
				(vias allowed)
				(pads allowed)
				(copperpour not_allowed)
				(footprints allowed)
			)
			(placement
				(enabled no)
				(sheetname "")
			)
			(fill
				(thermal_gap 0.5)
				(thermal_bridge_width 0.5)
				(island_removal_mode 0)
			)
			(polygon
				(pts
					(arc
						(start 357.874824 -125.035056)
						(mid 356.325424 -125.035056)
						(end 357.874824 -125.035056)
					)
				)
			)
		)
		(zone
			(layers "F.Cu" "B.Cu" "In1.Cu" "In2.Cu" "In3.Cu" "In4.Cu" "In5.Cu" "In6.Cu")
			(hatch none 0.5)
			(connect_pads
				(clearance 0)
			)
			(min_thickness 0.25)
			(keepout
				(tracks not_allowed)
				(vias allowed)
				(pads allowed)
				(copperpour not_allowed)
				(footprints allowed)
			)
			(placement
				(enabled no)
				(sheetname "")
			)
			(fill
				(thermal_gap 0.5)
				(thermal_bridge_width 0.5)
				(island_removal_mode 0)
			)
			(polygon
				(pts
					(arc
						(start 358.078024 -162.785044)
						(mid 356.122224 -162.785044)
						(end 358.078024 -162.785044)
					)
				)
			)
		)
	)
	(footprint ""
		(layer "F.Cu")
		(at 310.4134 -340.812882 180)
		(property "Reference" "R104"
			(at 0 0 180)
			(layer "F.SilkS")
			(hide yes)
			(effects
				(font
					(size 1.27 1.27)
				)
			)
		)
		(property "Value" "0R2J-2-GP"
			(at 0.064008 -3.993896 180)
			(unlocked yes)
			(layer "F.Fab")
			(hide yes)
			(effects
				(font
					(size 1.016 1.016)
					(thickness 0.1524)
				)
			)
		)
		(property "Device Type" "R402H16"
			(at 0.064008 -5.517896 180)
			(unlocked yes)
			(layer "F.Fab")
			(hide yes)
			(effects
				(font
					(size 1.016 1.016)
					(thickness 0.1524)
				)
			)
		)
		(duplicate_pad_numbers_are_jumpers no)
		(fp_line
			(start 0.508 -0.9398)
			(end -0.508 -0.9398)
			(stroke
				(width 0.1524)
				(type default)
			)
			(layer "F.SilkS")
		)
		(fp_line
			(start -0.508 -0.9398)
			(end -0.508 0.9398)
			(stroke
				(width 0.1524)
				(type default)
			)
			(layer "F.SilkS")
		)
		(fp_rect
			(start -0.508 0.9398)
			(end 0.508 -0.9398)
			(stroke
				(width 0)
				(type default)
			)
			(fill no)
			(layer "F.CrtYd")
		)
		(fp_rect
			(start -0.508 0.9398)
			(end 0.508 -0.9398)
			(stroke
				(width 0)
				(type default)
			)
			(fill no)
			(layer "F.Fab")
		)
		(pad "1" smd custom
			(at 0 -0.4445 180)
			(size 0.1397 0.1397)
			(layers "F.Cu" "F.Mask" "F.Paste")
			(net "PWM_OUT_D_R")
			(options
				(clearance outline)
				(anchor circle)
			)
			(primitives
				(gr_poly
					(pts
						(arc
							(start -0.1778 -0.2794)
							(mid -0.249642 -0.249642)
							(end -0.2794 -0.1778)
						)
						(arc
							(start -0.2794 0.1778)
							(mid -0.249642 0.249642)
							(end -0.1778 0.2794)
						)
						(arc
							(start 0.1778 0.2794)
							(mid 0.249642 0.249642)
							(end 0.2794 0.1778)
						)
						(arc
							(start 0.2794 -0.1778)
							(mid 0.249642 -0.249642)
							(end 0.1778 -0.2794)
						)
					)
					(width 0)
					(fill yes)
				)
			)
		)
		(pad "2" smd custom
			(at 0 0.4445 180)
			(size 0.1397 0.1397)
			(layers "F.Cu" "F.Mask" "F.Paste")
			(net "PWM_OUT_D")
			(options
				(clearance outline)
				(anchor circle)
			)
			(primitives
				(gr_poly
					(pts
						(arc
							(start -0.1778 -0.2794)
							(mid -0.249642 -0.249642)
							(end -0.2794 -0.1778)
						)
						(arc
							(start -0.2794 0.1778)
							(mid -0.249642 0.249642)
							(end -0.1778 0.2794)
						)
						(arc
							(start 0.1778 0.2794)
							(mid 0.249642 0.249642)
							(end 0.2794 0.1778)
						)
						(arc
							(start 0.2794 -0.1778)
							(mid 0.249642 -0.249642)
							(end 0.1778 -0.2794)
						)
					)
					(width 0)
					(fill yes)
				)
			)
		)
	)
	(footprint ""
		(layer "F.Cu")
		(at 394.462 -12.827 -90)
		(property "Reference" "Q167"
			(at 0 0 270)
			(layer "F.SilkS")
			(hide yes)
			(effects
				(font
					(size 1.27 1.27)
				)
			)
		)
		(property "Value" "2N7002KDW-GP"
			(at -2.3622 -8.2042 270)
			(unlocked yes)
			(layer "F.Fab")
			(hide yes)
			(effects
				(font
					(size 1.016 1.016)
					(thickness 0.1524)
				)
			)
		)
		(property "Device Type" "SOT-363H44"
			(at -2.3622 -10.1092 270)
			(unlocked yes)
			(layer "F.Fab")
			(hide yes)
			(effects
				(font
					(size 1.016 1.016)
					(thickness 0.1524)
				)
			)
		)
		(duplicate_pad_numbers_are_jumpers no)
		(fp_line
			(start -1.4478 1.7018)
			(end 1.4478 1.7018)
			(stroke
				(width 0.1524)
				(type default)
			)
			(layer "F.SilkS")
		)
		(fp_line
			(start 1.4478 1.7018)
			(end 1.4478 -1.7018)
			(stroke
				(width 0.1524)
				(type default)
			)
			(layer "F.SilkS")
		)
		(fp_line
			(start -1.27 1.524)
			(end -1.27 0.6604)
			(stroke
				(width 0.4826)
				(type default)
			)
			(layer "F.SilkS")
		)
		(fp_line
			(start -1.4478 -1.7018)
			(end -1.4478 1.7018)
			(stroke
				(width 0.1524)
				(type default)
			)
			(layer "F.SilkS")
		)
		(fp_line
			(start 1.4478 -1.7018)
			(end -1.4478 -1.7018)
			(stroke
				(width 0.1524)
				(type default)
			)
			(layer "F.SilkS")
		)
		(fp_poly
			(pts
				(xy -1.524 -1.778) (xy 1.524 -1.778) (xy 1.524 1.778) (xy -1.524 1.778)
			)
			(stroke
				(width 0)
				(type default)
			)
			(fill no)
			(layer "F.CrtYd")
		)
		(fp_poly
			(pts
				(xy -1.524 -1.778) (xy 1.524 -1.778) (xy 1.524 1.778) (xy -1.524 1.778)
			)
			(stroke
				(width 0)
				(type default)
			)
			(fill no)
			(layer "F.Fab")
		)
		(pad "1" smd rect
			(at -0.65024 0.9398 270)
			(size 0.4064 1.016)
			(layers "F.Cu" "F.Mask" "F.Paste")
			(net "GND")
		)
		(pad "2" smd rect
			(at 0 0.9398 270)
			(size 0.4064 1.016)
			(layers "F.Cu" "F.Mask" "F.Paste")
			(net "SW_PWR_R_HDD32")
		)
		(pad "3" smd rect
			(at 0.65024 0.9398 270)
			(size 0.4064 1.016)
			(layers "F.Cu" "F.Mask" "F.Paste")
			(net "SW_HDD_P32")
		)
		(pad "4" smd rect
			(at 0.65024 -0.9398 270)
			(size 0.4064 1.016)
			(layers "F.Cu" "F.Mask" "F.Paste")
			(net "GND")
		)
		(pad "5" smd rect
			(at 0 -0.9398 270)
			(size 0.4064 1.016)
			(layers "F.Cu" "F.Mask" "F.Paste")
			(net "SW_HDD_G32")
		)
		(pad "6" smd rect
			(at -0.65024 -0.9398 270)
			(size 0.4064 1.016)
			(layers "F.Cu" "F.Mask" "F.Paste")
			(net "SW_HDD_R32")
		)
	)
	(footprint ""
		(layer "F.Cu")
		(at 404.400004 -23.999952)
		(property "Reference" ""
			(at 0 0 0)
			(layer "F.SilkS")
			(hide yes)
			(effects
				(font
					(size 1.27 1.27)
				)
			)
		)
		(property "Value" "*"
			(at -6.3373 -0.4572 0)
			(unlocked yes)
			(layer "F.Fab")
			(hide yes)
			(effects
				(font
					(size 1.016 1.016)
					(thickness 0.1524)
				)
			)
		)
		(duplicate_pad_numbers_are_jumpers no)
		(fp_poly
			(pts
				(arc
					(start 5.0673 0)
					(mid -5.0673 0)
					(end 5.0673 0)
				)
			)
			(stroke
				(width 0)
				(type default)
			)
			(fill no)
			(layer "B.CrtYd")
		)
		(fp_poly
			(pts
				(arc
					(start 5.0673 0)
					(mid -5.0673 0)
					(end 5.0673 0)
				)
			)
			(stroke
				(width 0)
				(type default)
			)
			(fill no)
			(layer "F.CrtYd")
		)
		(fp_poly
			(pts
				(arc
					(start 5.0673 0)
					(mid -5.0673 0)
					(end 5.0673 0)
				)
			)
			(stroke
				(width 0)
				(type default)
			)
			(fill no)
			(layer "B.Fab")
		)
		(fp_poly
			(pts
				(arc
					(start 5.0673 0)
					(mid -5.0673 0)
					(end 5.0673 0)
				)
			)
			(stroke
				(width 0)
				(type default)
			)
			(fill no)
			(layer "F.Fab")
		)
		(pad "1" thru_hole circle
			(at 0 0)
			(size 9.525 9.525)
			(drill 3.556)
			(layers "*.Cu" "*.Mask")
			(remove_unused_layers no)
			(net "Net_33")
			(clearance -2.4765)
			(thermal_gap 0.3048)
			(padstack
				(mode front_inner_back)
				(layer "Inner"
					(shape circle)
					(size 3.9624 3.9624)
					(clearance 0.3048)
				)
				(layer "B.Cu"
					(shape circle)
					(size 9.525 9.525)
					(clearance -2.4765)
				)
			)
		)
		(zone
			(layers "F.Cu" "B.Cu" "In1.Cu" "In2.Cu" "In3.Cu" "In4.Cu" "In5.Cu" "In6.Cu")
			(hatch none 0.5)
			(connect_pads
				(clearance 0)
			)
			(min_thickness 0.25)
			(keepout
				(tracks not_allowed)
				(vias allowed)
				(pads allowed)
				(copperpour not_allowed)
				(footprints allowed)
			)
			(placement
				(enabled no)
				(sheetname "")
			)
			(fill
				(thermal_gap 0.5)
				(thermal_bridge_width 0.5)
				(island_removal_mode 0)
			)
			(polygon
				(pts
					(arc
						(start 409.162504 -23.999952)
						(mid 399.637504 -23.999952)
						(end 409.162504 -23.999952)
					)
				)
			)
		)
	)
	(footprint ""
		(layer "F.Cu")
		(at 109.474 -255.524 90)
		(property "Reference" "C78"
			(at 0 0 90)
			(layer "F.SilkS")
			(hide yes)
			(effects
				(font
					(size 1.27 1.27)
				)
			)
		)
		(property "Value" "SCD033U25V2KX-GP"
			(at 1.1811 -2.7051 90)
			(unlocked yes)
			(layer "F.Fab")
			(hide yes)
			(effects
				(font
					(size 1.016 1.016)
					(thickness 0.1524)
				)
			)
		)
		(property "Device Type" "C402H22"
			(at 1.1811 -4.2291 90)
			(unlocked yes)
			(layer "F.Fab")
			(hide yes)
			(effects
				(font
					(size 1.016 1.016)
					(thickness 0.1524)
				)
			)
		)
		(duplicate_pad_numbers_are_jumpers no)
		(fp_rect
			(start -0.4318 0.9525)
			(end 0.4318 -0.9525)
			(stroke
				(width 0)
				(type default)
			)
			(fill no)
			(layer "F.CrtYd")
		)
		(fp_rect
			(start -0.4318 0.9525)
			(end 0.4318 -0.9525)
			(stroke
				(width 0)
				(type default)
			)
			(fill no)
			(layer "F.Fab")
		)
		(pad "1" smd custom
			(at 0 -0.4445 90)
			(size 0.1524 0.1524)
			(layers "F.Cu" "F.Mask" "F.Paste")
			(net "P12V_B")
			(options
				(clearance outline)
				(anchor circle)
			)
			(primitives
				(gr_poly
					(pts
						(arc
							(start 0.3048 -0.2032)
							(mid 0.275042 -0.275042)
							(end 0.2032 -0.3048)
						)
						(arc
							(start -0.2032 -0.3048)
							(mid -0.275042 -0.275042)
							(end -0.3048 -0.2032)
						)
						(arc
							(start -0.3048 0.2032)
							(mid -0.275042 0.275042)
							(end -0.2032 0.3048)
						)
						(arc
							(start 0.2032 0.3048)
							(mid 0.275042 0.275042)
							(end 0.3048 0.2032)
						)
					)
					(width 0)
					(fill yes)
				)
			)
		)
		(pad "2" smd custom
			(at 0 0.4445 90)
			(size 0.1524 0.1524)
			(layers "F.Cu" "F.Mask" "F.Paste")
			(net "SW_HDD_N3")
			(options
				(clearance outline)
				(anchor circle)
			)
			(primitives
				(gr_poly
					(pts
						(arc
							(start 0.3048 -0.2032)
							(mid 0.275042 -0.275042)
							(end 0.2032 -0.3048)
						)
						(arc
							(start -0.2032 -0.3048)
							(mid -0.275042 -0.275042)
							(end -0.3048 -0.2032)
						)
						(arc
							(start -0.3048 0.2032)
							(mid -0.275042 0.275042)
							(end -0.2032 0.3048)
						)
						(arc
							(start 0.2032 0.3048)
							(mid 0.275042 0.275042)
							(end 0.3048 0.2032)
						)
					)
					(width 0)
					(fill yes)
				)
			)
		)
	)
	(footprint ""
		(layer "F.Cu")
		(at 444.148972 -119.184928 -90)
		(property "Reference" "R1159"
			(at 0 0 270)
			(layer "F.SilkS")
			(hide yes)
			(effects
				(font
					(size 1.27 1.27)
				)
			)
		)
		(property "Value" "10KR2F-2-GP"
			(at 0.064008 -3.993896 270)
			(unlocked yes)
			(layer "F.Fab")
			(hide yes)
			(effects
				(font
					(size 1.016 1.016)
					(thickness 0.1524)
				)
			)
		)
		(property "Device Type" "R402H16"
			(at 0.064008 -5.517896 270)
			(unlocked yes)
			(layer "F.Fab")
			(hide yes)
			(effects
				(font
					(size 1.016 1.016)
					(thickness 0.1524)
				)
			)
		)
		(duplicate_pad_numbers_are_jumpers no)
		(fp_line
			(start -0.508 -0.9398)
			(end -0.508 0.9398)
			(stroke
				(width 0.1524)
				(type default)
			)
			(layer "F.SilkS")
		)
		(fp_line
			(start 0.508 -0.9398)
			(end -0.508 -0.9398)
			(stroke
				(width 0.1524)
				(type default)
			)
			(layer "F.SilkS")
		)
		(fp_rect
			(start -0.508 0.9398)
			(end 0.508 -0.9398)
			(stroke
				(width 0)
				(type default)
			)
			(fill no)
			(layer "F.CrtYd")
		)
		(fp_rect
			(start -0.508 0.9398)
			(end 0.508 -0.9398)
			(stroke
				(width 0)
				(type default)
			)
			(fill no)
			(layer "F.Fab")
		)
		(pad "1" smd custom
			(at 0 -0.4445 270)
			(size 0.1397 0.1397)
			(layers "F.Cu" "F.Mask" "F.Paste")
			(net "P5V_B_4")
			(options
				(clearance outline)
				(anchor circle)
			)
			(primitives
				(gr_poly
					(pts
						(arc
							(start -0.1778 -0.2794)
							(mid -0.249642 -0.249642)
							(end -0.2794 -0.1778)
						)
						(arc
							(start -0.2794 0.1778)
							(mid -0.249642 0.249642)
							(end -0.1778 0.2794)
						)
						(arc
							(start 0.1778 0.2794)
							(mid 0.249642 0.249642)
							(end 0.2794 0.1778)
						)
						(arc
							(start 0.2794 -0.1778)
							(mid 0.249642 -0.249642)
							(end 0.1778 -0.2794)
						)
					)
					(width 0)
					(fill yes)
				)
			)
		)
		(pad "2" smd custom
			(at 0 0.4445 270)
			(size 0.1397 0.1397)
			(layers "F.Cu" "F.Mask" "F.Paste")
			(net "P5V_B_4_PGOOD")
			(options
				(clearance outline)
				(anchor circle)
			)
			(primitives
				(gr_poly
					(pts
						(arc
							(start -0.1778 -0.2794)
							(mid -0.249642 -0.249642)
							(end -0.2794 -0.1778)
						)
						(arc
							(start -0.2794 0.1778)
							(mid -0.249642 0.249642)
							(end -0.1778 0.2794)
						)
						(arc
							(start 0.1778 0.2794)
							(mid 0.249642 0.249642)
							(end 0.2794 0.1778)
						)
						(arc
							(start 0.2794 -0.1778)
							(mid 0.249642 -0.249642)
							(end 0.1778 -0.2794)
						)
					)
					(width 0)
					(fill yes)
				)
			)
		)
	)
	(footprint ""
		(layer "F.Cu")
		(at 444.3222 -261.3406)
		(property "Reference" "R321"
			(at 0 0 0)
			(layer "F.SilkS")
			(hide yes)
			(effects
				(font
					(size 1.27 1.27)
				)
			)
		)
		(property "Value" "220R3F-1-GP"
			(at -0.0254 -2.5146 0)
			(unlocked yes)
			(layer "F.Fab")
			(hide yes)
			(effects
				(font
					(size 1.016 1.016)
					(thickness 0.1524)
				)
			)
		)
		(property "Device Type" "R603H22"
			(at -0.0254 -4.0386 0)
			(unlocked yes)
			(layer "F.Fab")
			(hide yes)
			(effects
				(font
					(size 1.016 1.016)
					(thickness 0.1524)
				)
			)
		)
		(duplicate_pad_numbers_are_jumpers no)
		(fp_line
			(start -0.4826 0)
			(end -0.2032 0)
			(stroke
				(width 0.2032)
				(type default)
			)
			(layer "F.SilkS")
		)
		(fp_line
			(start 0.2032 0)
			(end 0.4826 0)
			(stroke
				(width 0.2032)
				(type default)
			)
			(layer "F.SilkS")
		)
		(fp_rect
			(start -0.5842 1.3335)
			(end 0.5842 -1.3335)
			(stroke
				(width 0)
				(type default)
			)
			(fill no)
			(layer "F.CrtYd")
		)
		(fp_rect
			(start -0.5842 1.3335)
			(end 0.5842 -1.3335)
			(stroke
				(width 0)
				(type default)
			)
			(fill no)
			(layer "F.Fab")
		)
		(pad "1" smd custom
			(at 0 -0.762)
			(size 0.2159 0.2159)
			(layers "F.Cu" "F.Mask" "F.Paste")
			(net "HDD_PRSNT_10")
			(options
				(clearance outline)
				(anchor circle)
			)
			(primitives
				(gr_poly
					(pts
						(arc
							(start -0.3302 -0.4318)
							(mid -0.402042 -0.402042)
							(end -0.4318 -0.3302)
						)
						(arc
							(start -0.4318 0.3302)
							(mid -0.402042 0.402042)
							(end -0.3302 0.4318)
						)
						(arc
							(start 0.3302 0.4318)
							(mid 0.402042 0.402042)
							(end 0.4318 0.3302)
						)
						(arc
							(start 0.4318 -0.3302)
							(mid 0.402042 -0.402042)
							(end 0.3302 -0.4318)
						)
					)
					(width 0)
					(fill yes)
				)
			)
		)
		(pad "2" smd custom
			(at 0 0.762)
			(size 0.2159 0.2159)
			(layers "F.Cu" "F.Mask" "F.Paste")
			(net "DRIVE_B_10_INS")
			(options
				(clearance outline)
				(anchor circle)
			)
			(primitives
				(gr_poly
					(pts
						(arc
							(start -0.3302 -0.4318)
							(mid -0.402042 -0.402042)
							(end -0.4318 -0.3302)
						)
						(arc
							(start -0.4318 0.3302)
							(mid -0.402042 0.402042)
							(end -0.3302 0.4318)
						)
						(arc
							(start 0.3302 0.4318)
							(mid 0.402042 0.402042)
							(end 0.4318 0.3302)
						)
						(arc
							(start 0.4318 -0.3302)
							(mid 0.402042 -0.402042)
							(end 0.3302 -0.4318)
						)
					)
					(width 0)
					(fill yes)
				)
			)
		)
	)
	(footprint ""
		(layer "F.Cu")
		(at 265.43 -358.267 90)
		(property "Reference" "D51"
			(at 0 0 90)
			(layer "F.SilkS")
			(hide yes)
			(effects
				(font
					(size 1.27 1.27)
				)
			)
		)
		(property "Value" "MMPZ5228BPT-GP"
			(at 0 -6.7818 90)
			(unlocked yes)
			(layer "F.Fab")
			(hide yes)
			(effects
				(font
					(size 1.016 1.016)
					(thickness 0.1524)
				)
			)
		)
		(property "Device Type" "SOD323AKH40"
			(at 0 -8.6868 90)
			(unlocked yes)
			(layer "F.Fab")
			(hide yes)
			(effects
				(font
					(size 1.016 1.016)
					(thickness 0.1524)
				)
			)
		)
		(duplicate_pad_numbers_are_jumpers no)
		(fp_line
			(start 0.889 -1.9304)
			(end 0.889 2.159)
			(stroke
				(width 0.1524)
				(type default)
			)
			(layer "F.SilkS")
		)
		(fp_line
			(start -0.889 -1.9304)
			(end 0.889 -1.9304)
			(stroke
				(width 0.1524)
				(type default)
			)
			(layer "F.SilkS")
		)
		(fp_line
			(start 0.762 2.0574)
			(end -0.762 2.0574)
			(stroke
				(width 0.508)
				(type default)
			)
			(layer "F.SilkS")
		)
		(fp_line
			(start 0.889 2.159)
			(end -0.889 2.159)
			(stroke
				(width 0.1524)
				(type default)
			)
			(layer "F.SilkS")
		)
		(fp_line
			(start -0.889 2.159)
			(end -0.889 -1.9304)
			(stroke
				(width 0.1524)
				(type default)
			)
			(layer "F.SilkS")
		)
		(fp_rect
			(start -1.016 2.3114)
			(end 1.016 -2.0066)
			(stroke
				(width 0)
				(type default)
			)
			(fill no)
			(layer "F.CrtYd")
		)
		(fp_poly
			(pts
				(xy -1.016 -2.0066) (xy 1.016 -2.0066) (xy 1.016 2.3114) (xy -1.016 2.3114)
			)
			(stroke
				(width 0)
				(type default)
			)
			(fill no)
			(layer "F.Fab")
		)
		(pad "A" smd rect
			(at 0 -1.143 90)
			(size 0.5588 1.016)
			(layers "F.Cu" "F.Mask" "F.Paste")
			(net "GND")
		)
		(pad "K" smd rect
			(at 0 1.143 90)
			(size 0.5588 1.016)
			(layers "F.Cu" "F.Mask" "F.Paste")
			(net "VCCP_IN")
		)
	)
	(footprint ""
		(layer "F.Cu")
		(at 394.6398 -134.5692 90)
		(property "Reference" "R537"
			(at 0 0 90)
			(layer "F.SilkS")
			(hide yes)
			(effects
				(font
					(size 1.27 1.27)
				)
			)
		)
		(property "Value" "4K7R2J-2-GP"
			(at 0.064008 -3.993896 90)
			(unlocked yes)
			(layer "F.Fab")
			(hide yes)
			(effects
				(font
					(size 1.016 1.016)
					(thickness 0.1524)
				)
			)
		)
		(property "Device Type" "R402H16"
			(at 0.064008 -5.517896 90)
			(unlocked yes)
			(layer "F.Fab")
			(hide yes)
			(effects
				(font
					(size 1.016 1.016)
					(thickness 0.1524)
				)
			)
		)
		(duplicate_pad_numbers_are_jumpers no)
		(fp_line
			(start 0.508 -0.9398)
			(end -0.508 -0.9398)
			(stroke
				(width 0.1524)
				(type default)
			)
			(layer "F.SilkS")
		)
		(fp_line
			(start -0.508 -0.9398)
			(end -0.508 0.9398)
			(stroke
				(width 0.1524)
				(type default)
			)
			(layer "F.SilkS")
		)
		(fp_rect
			(start -0.508 0.9398)
			(end 0.508 -0.9398)
			(stroke
				(width 0)
				(type default)
			)
			(fill no)
			(layer "F.CrtYd")
		)
		(fp_rect
			(start -0.508 0.9398)
			(end 0.508 -0.9398)
			(stroke
				(width 0)
				(type default)
			)
			(fill no)
			(layer "F.Fab")
		)
		(pad "1" smd custom
			(at 0 -0.4445 90)
			(size 0.1397 0.1397)
			(layers "F.Cu" "F.Mask" "F.Paste")
			(net "P12V_B")
			(options
				(clearance outline)
				(anchor circle)
			)
			(primitives
				(gr_poly
					(pts
						(arc
							(start -0.1778 -0.2794)
							(mid -0.249642 -0.249642)
							(end -0.2794 -0.1778)
						)
						(arc
							(start -0.2794 0.1778)
							(mid -0.249642 0.249642)
							(end -0.1778 0.2794)
						)
						(arc
							(start 0.1778 0.2794)
							(mid 0.249642 0.249642)
							(end 0.2794 0.1778)
						)
						(arc
							(start 0.2794 -0.1778)
							(mid 0.249642 -0.249642)
							(end 0.1778 -0.2794)
						)
					)
					(width 0)
					(fill yes)
				)
			)
		)
		(pad "2" smd custom
			(at 0 0.4445 90)
			(size 0.1397 0.1397)
			(layers "F.Cu" "F.Mask" "F.Paste")
			(net "SW_HDD_P20")
			(options
				(clearance outline)
				(anchor circle)
			)
			(primitives
				(gr_poly
					(pts
						(arc
							(start -0.1778 -0.2794)
							(mid -0.249642 -0.249642)
							(end -0.2794 -0.1778)
						)
						(arc
							(start -0.2794 0.1778)
							(mid -0.249642 0.249642)
							(end -0.1778 0.2794)
						)
						(arc
							(start 0.1778 0.2794)
							(mid 0.249642 0.249642)
							(end 0.2794 0.1778)
						)
						(arc
							(start 0.2794 -0.1778)
							(mid 0.249642 -0.249642)
							(end 0.1778 -0.2794)
						)
					)
					(width 0)
					(fill yes)
				)
			)
		)
	)
	(footprint ""
		(layer "F.Cu")
		(at 400.431 -248.793 90)
		(property "Reference" "D8"
			(at 0 0 90)
			(layer "F.SilkS")
			(hide yes)
			(effects
				(font
					(size 1.27 1.27)
				)
			)
		)
		(property "Value" "RB551V30-GP"
			(at 0 -6.7818 90)
			(unlocked yes)
			(layer "F.Fab")
			(hide yes)
			(effects
				(font
					(size 1.016 1.016)
					(thickness 0.1524)
				)
			)
		)
		(property "Device Type" "SOD323AKH38"
			(at 0 -8.6868 90)
			(unlocked yes)
			(layer "F.Fab")
			(hide yes)
			(effects
				(font
					(size 1.016 1.016)
					(thickness 0.1524)
				)
			)
		)
		(duplicate_pad_numbers_are_jumpers no)
		(fp_line
			(start 0.889 -1.9304)
			(end 0.889 2.159)
			(stroke
				(width 0.1524)
				(type default)
			)
			(layer "F.SilkS")
		)
		(fp_line
			(start -0.889 -1.9304)
			(end 0.889 -1.9304)
			(stroke
				(width 0.1524)
				(type default)
			)
			(layer "F.SilkS")
		)
		(fp_line
			(start 0.762 2.0574)
			(end -0.762 2.0574)
			(stroke
				(width 0.508)
				(type default)
			)
			(layer "F.SilkS")
		)
		(fp_line
			(start 0.889 2.159)
			(end -0.889 2.159)
			(stroke
				(width 0.1524)
				(type default)
			)
			(layer "F.SilkS")
		)
		(fp_line
			(start -0.889 2.159)
			(end -0.889 -1.9304)
			(stroke
				(width 0.1524)
				(type default)
			)
			(layer "F.SilkS")
		)
		(fp_rect
			(start -1.016 2.3114)
			(end 1.016 -2.0066)
			(stroke
				(width 0)
				(type default)
			)
			(fill no)
			(layer "F.CrtYd")
		)
		(fp_poly
			(pts
				(xy -1.016 -2.0066) (xy 1.016 -2.0066) (xy 1.016 2.3114) (xy -1.016 2.3114)
			)
			(stroke
				(width 0)
				(type default)
			)
			(fill no)
			(layer "F.Fab")
		)
		(pad "A" smd rect
			(at 0 -1.143 90)
			(size 0.5588 1.016)
			(layers "F.Cu" "F.Mask" "F.Paste")
			(net "SW_HDD_R8")
		)
		(pad "K" smd rect
			(at 0 1.143 90)
			(size 0.5588 1.016)
			(layers "F.Cu" "F.Mask" "F.Paste")
			(net "SW_HDD_N8")
		)
	)
	(footprint ""
		(layer "F.Cu")
		(at 55.245 -33.274)
		(property "Reference" "R644"
			(at 0 0 0)
			(layer "F.SilkS")
			(hide yes)
			(effects
				(font
					(size 1.27 1.27)
				)
			)
		)
		(property "Value" "2R6F-GP"
			(at -0.0508 -4.8514 0)
			(unlocked yes)
			(layer "F.Fab")
			(hide yes)
			(effects
				(font
					(size 1.016 1.016)
					(thickness 0.1524)
				)
			)
		)
		(property "Device Type" "R1206H26"
			(at 0 -6.3754 0)
			(unlocked yes)
			(layer "F.Fab")
			(hide yes)
			(effects
				(font
					(size 1.016 1.016)
					(thickness 0.1524)
				)
			)
		)
		(duplicate_pad_numbers_are_jumpers no)
		(fp_line
			(start -1.016 -2.2352)
			(end 1.016 -2.2352)
			(stroke
				(width 0.1524)
				(type default)
			)
			(layer "F.SilkS")
		)
		(fp_line
			(start -1.016 2.2352)
			(end -1.016 -2.2352)
			(stroke
				(width 0.1524)
				(type default)
			)
			(layer "F.SilkS")
		)
		(fp_line
			(start 1.016 -2.2352)
			(end 1.016 2.2352)
			(stroke
				(width 0.1524)
				(type default)
			)
			(layer "F.SilkS")
		)
		(fp_line
			(start 1.016 2.2352)
			(end -1.016 2.2352)
			(stroke
				(width 0.1524)
				(type default)
			)
			(layer "F.SilkS")
		)
		(fp_rect
			(start -1.0922 2.3114)
			(end 1.0922 -2.3114)
			(stroke
				(width 0)
				(type default)
			)
			(fill no)
			(layer "F.CrtYd")
		)
		(fp_poly
			(pts
				(xy -1.0922 -2.3114) (xy 1.0922 -2.3114) (xy 1.0922 2.3114) (xy -1.0922 2.3114)
			)
			(stroke
				(width 0)
				(type default)
			)
			(fill no)
			(layer "F.Fab")
		)
		(pad "1" smd rect
			(at 0 -1.397)
			(size 1.651 1.27)
			(layers "F.Cu" "F.Mask" "F.Paste")
			(net "P5V_HDD25")
		)
		(pad "2" smd rect
			(at 0 1.397)
			(size 1.651 1.27)
			(layers "F.Cu" "F.Mask" "F.Paste")
			(net "5V_PRE_25")
		)
	)
	(footprint ""
		(layer "F.Cu")
		(at 166.57193 -365.358426)
		(property "Reference" "R1014"
			(at 0 0 0)
			(layer "F.SilkS")
			(hide yes)
			(effects
				(font
					(size 1.27 1.27)
				)
			)
		)
		(property "Value" "4K99R2F-L-GP"
			(at 0.064008 -3.993896 0)
			(unlocked yes)
			(layer "F.Fab")
			(hide yes)
			(effects
				(font
					(size 1.016 1.016)
					(thickness 0.1524)
				)
			)
		)
		(property "Device Type" "R402H16"
			(at 0.064008 -5.517896 0)
			(unlocked yes)
			(layer "F.Fab")
			(hide yes)
			(effects
				(font
					(size 1.016 1.016)
					(thickness 0.1524)
				)
			)
		)
		(duplicate_pad_numbers_are_jumpers no)
		(fp_line
			(start -0.508 -0.9398)
			(end -0.508 0.9398)
			(stroke
				(width 0.1524)
				(type default)
			)
			(layer "F.SilkS")
		)
		(fp_line
			(start 0.508 -0.9398)
			(end -0.508 -0.9398)
			(stroke
				(width 0.1524)
				(type default)
			)
			(layer "F.SilkS")
		)
		(fp_rect
			(start -0.508 0.9398)
			(end 0.508 -0.9398)
			(stroke
				(width 0)
				(type default)
			)
			(fill no)
			(layer "F.CrtYd")
		)
		(fp_rect
			(start -0.508 0.9398)
			(end 0.508 -0.9398)
			(stroke
				(width 0)
				(type default)
			)
			(fill no)
			(layer "F.Fab")
		)
		(pad "1" smd custom
			(at 0 -0.4445)
			(size 0.1397 0.1397)
			(layers "F.Cu" "F.Mask" "F.Paste")
			(net "MB0_CM_UV_R")
			(options
				(clearance outline)
				(anchor circle)
			)
			(primitives
				(gr_poly
					(pts
						(arc
							(start -0.1778 -0.2794)
							(mid -0.249642 -0.249642)
							(end -0.2794 -0.1778)
						)
						(arc
							(start -0.2794 0.1778)
							(mid -0.249642 0.249642)
							(end -0.1778 0.2794)
						)
						(arc
							(start 0.1778 0.2794)
							(mid 0.249642 0.249642)
							(end 0.2794 0.1778)
						)
						(arc
							(start 0.2794 -0.1778)
							(mid 0.249642 -0.249642)
							(end 0.1778 -0.2794)
						)
					)
					(width 0)
					(fill yes)
				)
			)
		)
		(pad "2" smd custom
			(at 0 0.4445)
			(size 0.1397 0.1397)
			(layers "F.Cu" "F.Mask" "F.Paste")
			(net "AGND_CURRENT_MON")
			(options
				(clearance outline)
				(anchor circle)
			)
			(primitives
				(gr_poly
					(pts
						(arc
							(start -0.1778 -0.2794)
							(mid -0.249642 -0.249642)
							(end -0.2794 -0.1778)
						)
						(arc
							(start -0.2794 0.1778)
							(mid -0.249642 0.249642)
							(end -0.1778 0.2794)
						)
						(arc
							(start 0.1778 0.2794)
							(mid 0.249642 0.249642)
							(end 0.2794 0.1778)
						)
						(arc
							(start 0.2794 -0.1778)
							(mid 0.249642 -0.249642)
							(end 0.1778 -0.2794)
						)
					)
					(width 0)
					(fill yes)
				)
			)
		)
	)
	(footprint ""
		(layer "F.Cu")
		(at 178.181 -249.555 180)
		(property "Reference" "Q19"
			(at 0 0 180)
			(layer "F.SilkS")
			(hide yes)
			(effects
				(font
					(size 1.27 1.27)
				)
			)
		)
		(property "Value" "2N7002KDW-GP"
			(at -2.3622 -8.2042 180)
			(unlocked yes)
			(layer "F.Fab")
			(hide yes)
			(effects
				(font
					(size 1.016 1.016)
					(thickness 0.1524)
				)
			)
		)
		(property "Device Type" "SOT-363H44"
			(at -2.3622 -10.1092 180)
			(unlocked yes)
			(layer "F.Fab")
			(hide yes)
			(effects
				(font
					(size 1.016 1.016)
					(thickness 0.1524)
				)
			)
		)
		(duplicate_pad_numbers_are_jumpers no)
		(fp_line
			(start 1.4478 1.7018)
			(end 1.4478 -1.7018)
			(stroke
				(width 0.1524)
				(type default)
			)
			(layer "F.SilkS")
		)
		(fp_line
			(start 1.4478 -1.7018)
			(end -1.4478 -1.7018)
			(stroke
				(width 0.1524)
				(type default)
			)
			(layer "F.SilkS")
		)
		(fp_line
			(start -1.27 1.524)
			(end -1.27 0.6604)
			(stroke
				(width 0.4826)
				(type default)
			)
			(layer "F.SilkS")
		)
		(fp_line
			(start -1.4478 1.7018)
			(end 1.4478 1.7018)
			(stroke
				(width 0.1524)
				(type default)
			)
			(layer "F.SilkS")
		)
		(fp_line
			(start -1.4478 -1.7018)
			(end -1.4478 1.7018)
			(stroke
				(width 0.1524)
				(type default)
			)
			(layer "F.SilkS")
		)
		(fp_poly
			(pts
				(xy -1.524 -1.778) (xy 1.524 -1.778) (xy 1.524 1.778) (xy -1.524 1.778)
			)
			(stroke
				(width 0)
				(type default)
			)
			(fill no)
			(layer "F.CrtYd")
		)
		(fp_poly
			(pts
				(xy -1.524 -1.778) (xy 1.524 -1.778) (xy 1.524 1.778) (xy -1.524 1.778)
			)
			(stroke
				(width 0)
				(type default)
			)
			(fill no)
			(layer "F.Fab")
		)
		(pad "1" smd rect
			(at -0.65024 0.9398 180)
			(size 0.4064 1.016)
			(layers "F.Cu" "F.Mask" "F.Paste")
			(net "GND")
		)
		(pad "2" smd rect
			(at 0 0.9398 180)
			(size 0.4064 1.016)
			(layers "F.Cu" "F.Mask" "F.Paste")
			(net "SW_PWR_R_HDD5")
		)
		(pad "3" smd rect
			(at 0.65024 0.9398 180)
			(size 0.4064 1.016)
			(layers "F.Cu" "F.Mask" "F.Paste")
			(net "SW_HDD_P5")
		)
		(pad "4" smd rect
			(at 0.65024 -0.9398 180)
			(size 0.4064 1.016)
			(layers "F.Cu" "F.Mask" "F.Paste")
			(net "GND")
		)
		(pad "5" smd rect
			(at 0 -0.9398 180)
			(size 0.4064 1.016)
			(layers "F.Cu" "F.Mask" "F.Paste")
			(net "SW_HDD_G5")
		)
		(pad "6" smd rect
			(at -0.65024 -0.9398 180)
			(size 0.4064 1.016)
			(layers "F.Cu" "F.Mask" "F.Paste")
			(net "SW_HDD_R5")
		)
	)
	(footprint ""
		(layer "F.Cu")
		(at 27.794712 -221.75089 -90)
		(property "Reference" "C626"
			(at 0 0 270)
			(layer "F.SilkS")
			(hide yes)
			(effects
				(font
					(size 1.27 1.27)
				)
			)
		)
		(property "Value" "SC2200P50V2KX-2GP"
			(at 1.1811 -2.7051 270)
			(unlocked yes)
			(layer "F.Fab")
			(hide yes)
			(effects
				(font
					(size 1.016 1.016)
					(thickness 0.1524)
				)
			)
		)
		(property "Device Type" "C402H22"
			(at 1.1811 -4.2291 270)
			(unlocked yes)
			(layer "F.Fab")
			(hide yes)
			(effects
				(font
					(size 1.016 1.016)
					(thickness 0.1524)
				)
			)
		)
		(duplicate_pad_numbers_are_jumpers no)
		(fp_rect
			(start -0.4318 0.9525)
			(end 0.4318 -0.9525)
			(stroke
				(width 0)
				(type default)
			)
			(fill no)
			(layer "F.CrtYd")
		)
		(fp_rect
			(start -0.4318 0.9525)
			(end 0.4318 -0.9525)
			(stroke
				(width 0)
				(type default)
			)
			(fill no)
			(layer "F.Fab")
		)
		(pad "1" smd custom
			(at 0 -0.4445 270)
			(size 0.1524 0.1524)
			(layers "F.Cu" "F.Mask" "F.Paste")
			(net "P5V_B_1_LL")
			(options
				(clearance outline)
				(anchor circle)
			)
			(primitives
				(gr_poly
					(pts
						(arc
							(start 0.3048 -0.2032)
							(mid 0.275042 -0.275042)
							(end 0.2032 -0.3048)
						)
						(arc
							(start -0.2032 -0.3048)
							(mid -0.275042 -0.275042)
							(end -0.3048 -0.2032)
						)
						(arc
							(start -0.3048 0.2032)
							(mid -0.275042 0.275042)
							(end -0.2032 0.3048)
						)
						(arc
							(start 0.2032 0.3048)
							(mid 0.275042 0.275042)
							(end 0.3048 0.2032)
						)
					)
					(width 0)
					(fill yes)
				)
			)
		)
		(pad "2" smd custom
			(at 0 0.4445 270)
			(size 0.1524 0.1524)
			(layers "F.Cu" "F.Mask" "F.Paste")
			(net "P5V_B_1_SNB")
			(options
				(clearance outline)
				(anchor circle)
			)
			(primitives
				(gr_poly
					(pts
						(arc
							(start 0.3048 -0.2032)
							(mid 0.275042 -0.275042)
							(end 0.2032 -0.3048)
						)
						(arc
							(start -0.2032 -0.3048)
							(mid -0.275042 -0.275042)
							(end -0.3048 -0.2032)
						)
						(arc
							(start -0.3048 0.2032)
							(mid -0.275042 0.275042)
							(end -0.2032 0.3048)
						)
						(arc
							(start 0.2032 0.3048)
							(mid 0.275042 0.275042)
							(end 0.3048 0.2032)
						)
					)
					(width 0)
					(fill yes)
				)
			)
		)
	)
	(footprint ""
		(layer "F.Cu")
		(at 469.9 -254.508 -90)
		(property "Reference" "R345"
			(at 0 0 270)
			(layer "F.SilkS")
			(hide yes)
			(effects
				(font
					(size 1.27 1.27)
				)
			)
		)
		(property "Value" "300KR2F-GP"
			(at 0.064008 -3.993896 270)
			(unlocked yes)
			(layer "F.Fab")
			(hide yes)
			(effects
				(font
					(size 1.016 1.016)
					(thickness 0.1524)
				)
			)
		)
		(property "Device Type" "R402H16"
			(at 0.064008 -5.517896 270)
			(unlocked yes)
			(layer "F.Fab")
			(hide yes)
			(effects
				(font
					(size 1.016 1.016)
					(thickness 0.1524)
				)
			)
		)
		(duplicate_pad_numbers_are_jumpers no)
		(fp_line
			(start -0.508 -0.9398)
			(end -0.508 0.9398)
			(stroke
				(width 0.1524)
				(type default)
			)
			(layer "F.SilkS")
		)
		(fp_line
			(start 0.508 -0.9398)
			(end -0.508 -0.9398)
			(stroke
				(width 0.1524)
				(type default)
			)
			(layer "F.SilkS")
		)
		(fp_rect
			(start -0.508 0.9398)
			(end 0.508 -0.9398)
			(stroke
				(width 0)
				(type default)
			)
			(fill no)
			(layer "F.CrtYd")
		)
		(fp_rect
			(start -0.508 0.9398)
			(end 0.508 -0.9398)
			(stroke
				(width 0)
				(type default)
			)
			(fill no)
			(layer "F.Fab")
		)
		(pad "1" smd custom
			(at 0 -0.4445 270)
			(size 0.1397 0.1397)
			(layers "F.Cu" "F.Mask" "F.Paste")
			(net "SW_HDD_N11")
			(options
				(clearance outline)
				(anchor circle)
			)
			(primitives
				(gr_poly
					(pts
						(arc
							(start -0.1778 -0.2794)
							(mid -0.249642 -0.249642)
							(end -0.2794 -0.1778)
						)
						(arc
							(start -0.2794 0.1778)
							(mid -0.249642 0.249642)
							(end -0.1778 0.2794)
						)
						(arc
							(start 0.1778 0.2794)
							(mid 0.249642 0.249642)
							(end 0.2794 0.1778)
						)
						(arc
							(start 0.2794 -0.1778)
							(mid 0.249642 -0.249642)
							(end 0.1778 -0.2794)
						)
					)
					(width 0)
					(fill yes)
				)
			)
		)
		(pad "2" smd custom
			(at 0 0.4445 270)
			(size 0.1397 0.1397)
			(layers "F.Cu" "F.Mask" "F.Paste")
			(net "P12V_B")
			(options
				(clearance outline)
				(anchor circle)
			)
			(primitives
				(gr_poly
					(pts
						(arc
							(start -0.1778 -0.2794)
							(mid -0.249642 -0.249642)
							(end -0.2794 -0.1778)
						)
						(arc
							(start -0.2794 0.1778)
							(mid -0.249642 0.249642)
							(end -0.1778 0.2794)
						)
						(arc
							(start 0.1778 0.2794)
							(mid 0.249642 0.249642)
							(end 0.2794 0.1778)
						)
						(arc
							(start 0.2794 -0.1778)
							(mid 0.249642 -0.249642)
							(end 0.1778 -0.2794)
						)
					)
					(width 0)
					(fill yes)
				)
			)
		)
	)
	(footprint ""
		(layer "F.Cu")
		(at 14.859 -246.634 90)
		(property "Reference" "R912"
			(at 0 0 90)
			(layer "F.SilkS")
			(hide yes)
			(effects
				(font
					(size 1.27 1.27)
				)
			)
		)
		(property "Value" "4K7R2J-2-GP"
			(at 0.064008 -3.993896 90)
			(unlocked yes)
			(layer "F.Fab")
			(hide yes)
			(effects
				(font
					(size 1.016 1.016)
					(thickness 0.1524)
				)
			)
		)
		(property "Device Type" "R402H16"
			(at 0.064008 -5.517896 90)
			(unlocked yes)
			(layer "F.Fab")
			(hide yes)
			(effects
				(font
					(size 1.016 1.016)
					(thickness 0.1524)
				)
			)
		)
		(duplicate_pad_numbers_are_jumpers no)
		(fp_line
			(start 0.508 -0.9398)
			(end -0.508 -0.9398)
			(stroke
				(width 0.1524)
				(type default)
			)
			(layer "F.SilkS")
		)
		(fp_line
			(start -0.508 -0.9398)
			(end -0.508 0.9398)
			(stroke
				(width 0.1524)
				(type default)
			)
			(layer "F.SilkS")
		)
		(fp_rect
			(start -0.508 0.9398)
			(end 0.508 -0.9398)
			(stroke
				(width 0)
				(type default)
			)
			(fill no)
			(layer "F.CrtYd")
		)
		(fp_rect
			(start -0.508 0.9398)
			(end 0.508 -0.9398)
			(stroke
				(width 0)
				(type default)
			)
			(fill no)
			(layer "F.Fab")
		)
		(pad "1" smd custom
			(at 0 -0.4445 90)
			(size 0.1397 0.1397)
			(layers "F.Cu" "F.Mask" "F.Paste")
			(net "P12V_B")
			(options
				(clearance outline)
				(anchor circle)
			)
			(primitives
				(gr_poly
					(pts
						(arc
							(start -0.1778 -0.2794)
							(mid -0.249642 -0.249642)
							(end -0.2794 -0.1778)
						)
						(arc
							(start -0.2794 0.1778)
							(mid -0.249642 0.249642)
							(end -0.1778 0.2794)
						)
						(arc
							(start 0.1778 0.2794)
							(mid 0.249642 0.249642)
							(end 0.2794 0.1778)
						)
						(arc
							(start 0.2794 -0.1778)
							(mid 0.249642 -0.249642)
							(end 0.1778 -0.2794)
						)
					)
					(width 0)
					(fill yes)
				)
			)
		)
		(pad "2" smd custom
			(at 0 0.4445 90)
			(size 0.1397 0.1397)
			(layers "F.Cu" "F.Mask" "F.Paste")
			(net "SW_HDD_R0")
			(options
				(clearance outline)
				(anchor circle)
			)
			(primitives
				(gr_poly
					(pts
						(arc
							(start -0.1778 -0.2794)
							(mid -0.249642 -0.249642)
							(end -0.2794 -0.1778)
						)
						(arc
							(start -0.2794 0.1778)
							(mid -0.249642 0.249642)
							(end -0.1778 0.2794)
						)
						(arc
							(start 0.1778 0.2794)
							(mid 0.249642 0.249642)
							(end 0.2794 0.1778)
						)
						(arc
							(start 0.2794 -0.1778)
							(mid 0.249642 -0.249642)
							(end 0.1778 -0.2794)
						)
					)
					(width 0)
					(fill yes)
				)
			)
		)
	)
	(footprint ""
		(layer "F.Cu")
		(at 37.940996 -369.697 180)
		(property "Reference" "R922"
			(at 0 0 180)
			(layer "F.SilkS")
			(hide yes)
			(effects
				(font
					(size 1.27 1.27)
				)
			)
		)
		(property "Value" "4K7R2F-GP"
			(at 0.064008 -3.993896 180)
			(unlocked yes)
			(layer "F.Fab")
			(hide yes)
			(effects
				(font
					(size 1.016 1.016)
					(thickness 0.1524)
				)
			)
		)
		(property "Device Type" "R402H16"
			(at 0.064008 -5.517896 180)
			(unlocked yes)
			(layer "F.Fab")
			(hide yes)
			(effects
				(font
					(size 1.016 1.016)
					(thickness 0.1524)
				)
			)
		)
		(duplicate_pad_numbers_are_jumpers no)
		(fp_line
			(start 0.508 -0.9398)
			(end -0.508 -0.9398)
			(stroke
				(width 0.1524)
				(type default)
			)
			(layer "F.SilkS")
		)
		(fp_line
			(start -0.508 -0.9398)
			(end -0.508 0.9398)
			(stroke
				(width 0.1524)
				(type default)
			)
			(layer "F.SilkS")
		)
		(fp_rect
			(start -0.508 0.9398)
			(end 0.508 -0.9398)
			(stroke
				(width 0)
				(type default)
			)
			(fill no)
			(layer "F.CrtYd")
		)
		(fp_rect
			(start -0.508 0.9398)
			(end 0.508 -0.9398)
			(stroke
				(width 0)
				(type default)
			)
			(fill no)
			(layer "F.Fab")
		)
		(pad "1" smd custom
			(at 0 -0.4445 180)
			(size 0.1397 0.1397)
			(layers "F.Cu" "F.Mask" "F.Paste")
			(net "P12V_IN")
			(options
				(clearance outline)
				(anchor circle)
			)
			(primitives
				(gr_poly
					(pts
						(arc
							(start -0.1778 -0.2794)
							(mid -0.249642 -0.249642)
							(end -0.2794 -0.1778)
						)
						(arc
							(start -0.2794 0.1778)
							(mid -0.249642 0.249642)
							(end -0.1778 0.2794)
						)
						(arc
							(start 0.1778 0.2794)
							(mid 0.249642 0.249642)
							(end 0.2794 0.1778)
						)
						(arc
							(start 0.2794 -0.1778)
							(mid 0.249642 -0.249642)
							(end 0.1778 -0.2794)
						)
					)
					(width 0)
					(fill yes)
				)
			)
		)
		(pad "2" smd custom
			(at 0 0.4445 180)
			(size 0.1397 0.1397)
			(layers "F.Cu" "F.Mask" "F.Paste")
			(net "FAN_0_TACH0")
			(options
				(clearance outline)
				(anchor circle)
			)
			(primitives
				(gr_poly
					(pts
						(arc
							(start -0.1778 -0.2794)
							(mid -0.249642 -0.249642)
							(end -0.2794 -0.1778)
						)
						(arc
							(start -0.2794 0.1778)
							(mid -0.249642 0.249642)
							(end -0.1778 0.2794)
						)
						(arc
							(start 0.1778 0.2794)
							(mid 0.249642 0.249642)
							(end 0.2794 0.1778)
						)
						(arc
							(start 0.2794 -0.1778)
							(mid 0.249642 -0.249642)
							(end 0.1778 -0.2794)
						)
					)
					(width 0)
					(fill yes)
				)
			)
		)
	)
	(footprint ""
		(layer "F.Cu")
		(at 64.013334 -244.660674 90)
		(property "Reference" "C42"
			(at 0 0 90)
			(layer "F.SilkS")
			(hide yes)
			(effects
				(font
					(size 1.27 1.27)
				)
			)
		)
		(property "Value" "SCD01U16V1KX-GP"
			(at -2.8321 -1.7399 90)
			(unlocked yes)
			(layer "F.Fab")
			(hide yes)
			(effects
				(font
					(size 1.016 1.016)
					(thickness 0.1524)
				)
			)
		)
		(property "Device Type" "C0201H13"
			(at -2.8321 -3.2639 90)
			(unlocked yes)
			(layer "F.Fab")
			(hide yes)
			(effects
				(font
					(size 1.016 1.016)
					(thickness 0.1524)
				)
			)
		)
		(duplicate_pad_numbers_are_jumpers no)
		(fp_rect
			(start -0.2794 0.6477)
			(end 0.2794 -0.6477)
			(stroke
				(width 0)
				(type default)
			)
			(fill no)
			(layer "F.CrtYd")
		)
		(fp_rect
			(start -0.2794 0.6477)
			(end 0.2794 -0.6477)
			(stroke
				(width 0)
				(type default)
			)
			(fill no)
			(layer "F.Fab")
		)
		(pad "1" smd custom
			(at 0 -0.2794 90)
			(size 0.0762 0.0762)
			(layers "F.Cu" "F.Mask" "F.Paste")
			(net "SAS_HDD_RX_P1")
			(options
				(clearance outline)
				(anchor circle)
			)
			(primitives
				(gr_poly
					(pts
						(arc
							(start 0.1524 -0.127)
							(mid 0.137521 -0.162921)
							(end 0.1016 -0.1778)
						)
						(arc
							(start -0.1016 -0.1778)
							(mid -0.137521 -0.162921)
							(end -0.1524 -0.127)
						)
						(arc
							(start -0.1524 0.127)
							(mid -0.137521 0.162921)
							(end -0.1016 0.1778)
						)
						(arc
							(start 0.1016 0.1778)
							(mid 0.137521 0.162921)
							(end 0.1524 0.127)
						)
					)
					(width 0)
					(fill yes)
				)
			)
		)
		(pad "2" smd custom
			(at 0 0.2794 90)
			(size 0.0762 0.0762)
			(layers "F.Cu" "F.Mask" "F.Paste")
			(net "PHY_SCC_B_TO_DRV_B_1_DP")
			(options
				(clearance outline)
				(anchor circle)
			)
			(primitives
				(gr_poly
					(pts
						(arc
							(start 0.1524 -0.127)
							(mid 0.137521 -0.162921)
							(end 0.1016 -0.1778)
						)
						(arc
							(start -0.1016 -0.1778)
							(mid -0.137521 -0.162921)
							(end -0.1524 -0.127)
						)
						(arc
							(start -0.1524 0.127)
							(mid -0.137521 0.162921)
							(end -0.1016 0.1778)
						)
						(arc
							(start 0.1016 0.1778)
							(mid 0.137521 0.162921)
							(end 0.1524 0.127)
						)
					)
					(width 0)
					(fill yes)
				)
			)
		)
	)
	(footprint ""
		(layer "F.Cu")
		(at 249.032268 -222.9612 180)
		(property "Reference" "R112"
			(at 0 0 180)
			(layer "F.SilkS")
			(hide yes)
			(effects
				(font
					(size 1.27 1.27)
				)
			)
		)
		(property "Value" "4K7R2F-GP"
			(at 0.064008 -3.993896 180)
			(unlocked yes)
			(layer "F.Fab")
			(hide yes)
			(effects
				(font
					(size 1.016 1.016)
					(thickness 0.1524)
				)
			)
		)
		(property "Device Type" "R402H16"
			(at 0.064008 -5.517896 180)
			(unlocked yes)
			(layer "F.Fab")
			(hide yes)
			(effects
				(font
					(size 1.016 1.016)
					(thickness 0.1524)
				)
			)
		)
		(duplicate_pad_numbers_are_jumpers no)
		(fp_line
			(start 0.508 -0.9398)
			(end -0.508 -0.9398)
			(stroke
				(width 0.1524)
				(type default)
			)
			(layer "F.SilkS")
		)
		(fp_line
			(start -0.508 -0.9398)
			(end -0.508 0.9398)
			(stroke
				(width 0.1524)
				(type default)
			)
			(layer "F.SilkS")
		)
		(fp_rect
			(start -0.508 0.9398)
			(end 0.508 -0.9398)
			(stroke
				(width 0)
				(type default)
			)
			(fill no)
			(layer "F.CrtYd")
		)
		(fp_rect
			(start -0.508 0.9398)
			(end 0.508 -0.9398)
			(stroke
				(width 0)
				(type default)
			)
			(fill no)
			(layer "F.Fab")
		)
		(pad "1" smd custom
			(at 0 -0.4445 180)
			(size 0.1397 0.1397)
			(layers "F.Cu" "F.Mask" "F.Paste")
			(net "EEPROM_A1")
			(options
				(clearance outline)
				(anchor circle)
			)
			(primitives
				(gr_poly
					(pts
						(arc
							(start -0.1778 -0.2794)
							(mid -0.249642 -0.249642)
							(end -0.2794 -0.1778)
						)
						(arc
							(start -0.2794 0.1778)
							(mid -0.249642 0.249642)
							(end -0.1778 0.2794)
						)
						(arc
							(start 0.1778 0.2794)
							(mid 0.249642 0.249642)
							(end 0.2794 0.1778)
						)
						(arc
							(start 0.2794 -0.1778)
							(mid 0.249642 -0.249642)
							(end 0.1778 -0.2794)
						)
					)
					(width 0)
					(fill yes)
				)
			)
		)
		(pad "2" smd custom
			(at 0 0.4445 180)
			(size 0.1397 0.1397)
			(layers "F.Cu" "F.Mask" "F.Paste")
			(net "GND")
			(options
				(clearance outline)
				(anchor circle)
			)
			(primitives
				(gr_poly
					(pts
						(arc
							(start -0.1778 -0.2794)
							(mid -0.249642 -0.249642)
							(end -0.2794 -0.1778)
						)
						(arc
							(start -0.2794 0.1778)
							(mid -0.249642 0.249642)
							(end -0.1778 0.2794)
						)
						(arc
							(start 0.1778 0.2794)
							(mid 0.249642 0.249642)
							(end 0.2794 0.1778)
						)
						(arc
							(start 0.2794 -0.1778)
							(mid 0.249642 -0.249642)
							(end 0.1778 -0.2794)
						)
					)
					(width 0)
					(fill yes)
				)
			)
		)
	)
	(footprint ""
		(layer "F.Cu")
		(at 458.216 -246.253 -90)
		(property "Reference" "Q39"
			(at 0 0 270)
			(layer "F.SilkS")
			(hide yes)
			(effects
				(font
					(size 1.27 1.27)
				)
			)
		)
		(property "Value" "2N7002KDW-GP"
			(at -2.3622 -8.2042 270)
			(unlocked yes)
			(layer "F.Fab")
			(hide yes)
			(effects
				(font
					(size 1.016 1.016)
					(thickness 0.1524)
				)
			)
		)
		(property "Device Type" "SOT-363H44"
			(at -2.3622 -10.1092 270)
			(unlocked yes)
			(layer "F.Fab")
			(hide yes)
			(effects
				(font
					(size 1.016 1.016)
					(thickness 0.1524)
				)
			)
		)
		(duplicate_pad_numbers_are_jumpers no)
		(fp_line
			(start -1.4478 1.7018)
			(end 1.4478 1.7018)
			(stroke
				(width 0.1524)
				(type default)
			)
			(layer "F.SilkS")
		)
		(fp_line
			(start 1.4478 1.7018)
			(end 1.4478 -1.7018)
			(stroke
				(width 0.1524)
				(type default)
			)
			(layer "F.SilkS")
		)
		(fp_line
			(start -1.27 1.524)
			(end -1.27 0.6604)
			(stroke
				(width 0.4826)
				(type default)
			)
			(layer "F.SilkS")
		)
		(fp_line
			(start -1.4478 -1.7018)
			(end -1.4478 1.7018)
			(stroke
				(width 0.1524)
				(type default)
			)
			(layer "F.SilkS")
		)
		(fp_line
			(start 1.4478 -1.7018)
			(end -1.4478 -1.7018)
			(stroke
				(width 0.1524)
				(type default)
			)
			(layer "F.SilkS")
		)
		(fp_poly
			(pts
				(xy -1.524 -1.778) (xy 1.524 -1.778) (xy 1.524 1.778) (xy -1.524 1.778)
			)
			(stroke
				(width 0)
				(type default)
			)
			(fill no)
			(layer "F.CrtYd")
		)
		(fp_poly
			(pts
				(xy -1.524 -1.778) (xy 1.524 -1.778) (xy 1.524 1.778) (xy -1.524 1.778)
			)
			(stroke
				(width 0)
				(type default)
			)
			(fill no)
			(layer "F.Fab")
		)
		(pad "1" smd rect
			(at -0.65024 0.9398 270)
			(size 0.4064 1.016)
			(layers "F.Cu" "F.Mask" "F.Paste")
			(net "GND")
		)
		(pad "2" smd rect
			(at 0 0.9398 270)
			(size 0.4064 1.016)
			(layers "F.Cu" "F.Mask" "F.Paste")
			(net "SW_PWR_R_HDD10")
		)
		(pad "3" smd rect
			(at 0.65024 0.9398 270)
			(size 0.4064 1.016)
			(layers "F.Cu" "F.Mask" "F.Paste")
			(net "SW_HDD_P10")
		)
		(pad "4" smd rect
			(at 0.65024 -0.9398 270)
			(size 0.4064 1.016)
			(layers "F.Cu" "F.Mask" "F.Paste")
			(net "GND")
		)
		(pad "5" smd rect
			(at 0 -0.9398 270)
			(size 0.4064 1.016)
			(layers "F.Cu" "F.Mask" "F.Paste")
			(net "SW_HDD_G10")
		)
		(pad "6" smd rect
			(at -0.65024 -0.9398 270)
			(size 0.4064 1.016)
			(layers "F.Cu" "F.Mask" "F.Paste")
			(net "SW_HDD_R10")
		)
	)
	(footprint ""
		(layer "F.Cu")
		(at 95.563436 -14.660626 90)
		(property "Reference" "C367"
			(at 0 0 90)
			(layer "F.SilkS")
			(hide yes)
			(effects
				(font
					(size 1.27 1.27)
				)
			)
		)
		(property "Value" "SCD01U16V1KX-GP"
			(at -2.8321 -1.7399 90)
			(unlocked yes)
			(layer "F.Fab")
			(hide yes)
			(effects
				(font
					(size 1.016 1.016)
					(thickness 0.1524)
				)
			)
		)
		(property "Device Type" "C0201H13"
			(at -2.8321 -3.2639 90)
			(unlocked yes)
			(layer "F.Fab")
			(hide yes)
			(effects
				(font
					(size 1.016 1.016)
					(thickness 0.1524)
				)
			)
		)
		(duplicate_pad_numbers_are_jumpers no)
		(fp_rect
			(start -0.2794 0.6477)
			(end 0.2794 -0.6477)
			(stroke
				(width 0)
				(type default)
			)
			(fill no)
			(layer "F.CrtYd")
		)
		(fp_rect
			(start -0.2794 0.6477)
			(end 0.2794 -0.6477)
			(stroke
				(width 0)
				(type default)
			)
			(fill no)
			(layer "F.Fab")
		)
		(pad "1" smd custom
			(at 0 -0.2794 90)
			(size 0.0762 0.0762)
			(layers "F.Cu" "F.Mask" "F.Paste")
			(net "SAS_HDD_RX_P26")
			(options
				(clearance outline)
				(anchor circle)
			)
			(primitives
				(gr_poly
					(pts
						(arc
							(start 0.1524 -0.127)
							(mid 0.137521 -0.162921)
							(end 0.1016 -0.1778)
						)
						(arc
							(start -0.1016 -0.1778)
							(mid -0.137521 -0.162921)
							(end -0.1524 -0.127)
						)
						(arc
							(start -0.1524 0.127)
							(mid -0.137521 0.162921)
							(end -0.1016 0.1778)
						)
						(arc
							(start 0.1016 0.1778)
							(mid 0.137521 0.162921)
							(end 0.1524 0.127)
						)
					)
					(width 0)
					(fill yes)
				)
			)
		)
		(pad "2" smd custom
			(at 0 0.2794 90)
			(size 0.0762 0.0762)
			(layers "F.Cu" "F.Mask" "F.Paste")
			(net "PHY_SCC_B_TO_DRV_B_26_DP")
			(options
				(clearance outline)
				(anchor circle)
			)
			(primitives
				(gr_poly
					(pts
						(arc
							(start 0.1524 -0.127)
							(mid 0.137521 -0.162921)
							(end 0.1016 -0.1778)
						)
						(arc
							(start -0.1016 -0.1778)
							(mid -0.137521 -0.162921)
							(end -0.1524 -0.127)
						)
						(arc
							(start -0.1524 0.127)
							(mid -0.137521 0.162921)
							(end -0.1016 0.1778)
						)
						(arc
							(start 0.1016 0.1778)
							(mid 0.137521 0.162921)
							(end 0.1524 0.127)
						)
					)
					(width 0)
					(fill yes)
				)
			)
		)
	)
	(footprint ""
		(layer "F.Cu")
		(at 459.359 -128.651 180)
		(property "Reference" "R584"
			(at 0 0 180)
			(layer "F.SilkS")
			(hide yes)
			(effects
				(font
					(size 1.27 1.27)
				)
			)
		)
		(property "Value" "1KR2F-3-GP"
			(at 0.064008 -3.993896 180)
			(unlocked yes)
			(layer "F.Fab")
			(hide yes)
			(effects
				(font
					(size 1.016 1.016)
					(thickness 0.1524)
				)
			)
		)
		(property "Device Type" "R402H16"
			(at 0.064008 -5.517896 180)
			(unlocked yes)
			(layer "F.Fab")
			(hide yes)
			(effects
				(font
					(size 1.016 1.016)
					(thickness 0.1524)
				)
			)
		)
		(duplicate_pad_numbers_are_jumpers no)
		(fp_line
			(start 0.508 -0.9398)
			(end -0.508 -0.9398)
			(stroke
				(width 0.1524)
				(type default)
			)
			(layer "F.SilkS")
		)
		(fp_line
			(start -0.508 -0.9398)
			(end -0.508 0.9398)
			(stroke
				(width 0.1524)
				(type default)
			)
			(layer "F.SilkS")
		)
		(fp_rect
			(start -0.508 0.9398)
			(end 0.508 -0.9398)
			(stroke
				(width 0)
				(type default)
			)
			(fill no)
			(layer "F.CrtYd")
		)
		(fp_rect
			(start -0.508 0.9398)
			(end 0.508 -0.9398)
			(stroke
				(width 0)
				(type default)
			)
			(fill no)
			(layer "F.Fab")
		)
		(pad "1" smd custom
			(at 0 -0.4445 180)
			(size 0.1397 0.1397)
			(layers "F.Cu" "F.Mask" "F.Paste")
			(net "P3V3_STBY_B")
			(options
				(clearance outline)
				(anchor circle)
			)
			(primitives
				(gr_poly
					(pts
						(arc
							(start -0.1778 -0.2794)
							(mid -0.249642 -0.249642)
							(end -0.2794 -0.1778)
						)
						(arc
							(start -0.2794 0.1778)
							(mid -0.249642 0.249642)
							(end -0.1778 0.2794)
						)
						(arc
							(start 0.1778 0.2794)
							(mid 0.249642 0.249642)
							(end 0.2794 0.1778)
						)
						(arc
							(start 0.2794 -0.1778)
							(mid 0.249642 -0.249642)
							(end 0.1778 -0.2794)
						)
					)
					(width 0)
					(fill yes)
				)
			)
		)
		(pad "2" smd custom
			(at 0 0.4445 180)
			(size 0.1397 0.1397)
			(layers "F.Cu" "F.Mask" "F.Paste")
			(net "SW_PWR_R_HDD22")
			(options
				(clearance outline)
				(anchor circle)
			)
			(primitives
				(gr_poly
					(pts
						(arc
							(start -0.1778 -0.2794)
							(mid -0.249642 -0.249642)
							(end -0.2794 -0.1778)
						)
						(arc
							(start -0.2794 0.1778)
							(mid -0.249642 0.249642)
							(end -0.1778 0.2794)
						)
						(arc
							(start 0.1778 0.2794)
							(mid 0.249642 0.249642)
							(end 0.2794 0.1778)
						)
						(arc
							(start 0.2794 -0.1778)
							(mid 0.249642 -0.249642)
							(end 0.1778 -0.2794)
						)
					)
					(width 0)
					(fill yes)
				)
			)
		)
	)
	(footprint ""
		(layer "F.Cu")
		(at 282.448 -343.916 -90)
		(property "Reference" "C34"
			(at 0 0 270)
			(layer "F.SilkS")
			(hide yes)
			(effects
				(font
					(size 1.27 1.27)
				)
			)
		)
		(property "Value" "SC1U16V3KX-5GP"
			(at 0 -2.8194 270)
			(unlocked yes)
			(layer "F.Fab")
			(hide yes)
			(effects
				(font
					(size 1.016 1.016)
					(thickness 0.1524)
				)
			)
		)
		(property "Device Type" "C603H36"
			(at 0 -4.3434 270)
			(unlocked yes)
			(layer "F.Fab")
			(hide yes)
			(effects
				(font
					(size 1.016 1.016)
					(thickness 0.1524)
				)
			)
		)
		(duplicate_pad_numbers_are_jumpers no)
		(fp_line
			(start 0.508 0)
			(end -0.508 0)
			(stroke
				(width 0.2032)
				(type default)
			)
			(layer "F.SilkS")
		)
		(fp_rect
			(start -0.5842 1.3335)
			(end 0.5842 -1.3335)
			(stroke
				(width 0)
				(type default)
			)
			(fill no)
			(layer "F.CrtYd")
		)
		(fp_rect
			(start -0.5842 1.3335)
			(end 0.5842 -1.3335)
			(stroke
				(width 0)
				(type default)
			)
			(fill no)
			(layer "F.Fab")
		)
		(pad "1" smd custom
			(at 0 -0.762 270)
			(size 0.2159 0.2159)
			(layers "F.Cu" "F.Mask" "F.Paste")
			(net "P12V_IN")
			(options
				(clearance outline)
				(anchor circle)
			)
			(primitives
				(gr_poly
					(pts
						(arc
							(start -0.3302 -0.4318)
							(mid -0.402042 -0.402042)
							(end -0.4318 -0.3302)
						)
						(arc
							(start -0.4318 0.3302)
							(mid -0.402042 0.402042)
							(end -0.3302 0.4318)
						)
						(arc
							(start 0.3302 0.4318)
							(mid 0.402042 0.402042)
							(end 0.4318 0.3302)
						)
						(arc
							(start 0.4318 -0.3302)
							(mid 0.402042 -0.402042)
							(end 0.3302 -0.4318)
						)
					)
					(width 0)
					(fill yes)
				)
			)
		)
		(pad "2" smd custom
			(at 0 0.762 270)
			(size 0.2159 0.2159)
			(layers "F.Cu" "F.Mask" "F.Paste")
			(net "GND")
			(options
				(clearance outline)
				(anchor circle)
			)
			(primitives
				(gr_poly
					(pts
						(arc
							(start -0.3302 -0.4318)
							(mid -0.402042 -0.402042)
							(end -0.4318 -0.3302)
						)
						(arc
							(start -0.4318 0.3302)
							(mid -0.402042 0.402042)
							(end -0.3302 0.4318)
						)
						(arc
							(start 0.3302 0.4318)
							(mid 0.402042 0.402042)
							(end 0.4318 0.3302)
						)
						(arc
							(start 0.4318 -0.3302)
							(mid 0.402042 -0.402042)
							(end 0.3302 -0.4318)
						)
					)
					(width 0)
					(fill yes)
				)
			)
		)
	)
	(footprint ""
		(layer "F.Cu")
		(at 29.127196 -378.1044 -90)
		(property "Reference" "Q204"
			(at 0 0 270)
			(layer "F.SilkS")
			(hide yes)
			(effects
				(font
					(size 1.27 1.27)
				)
			)
		)
		(property "Value" "SSM6P39TU-GP"
			(at 0.0508 -11.5824 270)
			(unlocked yes)
			(layer "F.Fab")
			(hide yes)
			(effects
				(font
					(size 1.016 1.016)
					(thickness 0.1524)
				)
			)
		)
		(property "Device Type" "UMT6H30"
			(at 0.0508 -13.1572 270)
			(unlocked yes)
			(layer "F.Fab")
			(hide yes)
			(effects
				(font
					(size 1.016 1.016)
					(thickness 0.1524)
				)
			)
		)
		(duplicate_pad_numbers_are_jumpers no)
		(fp_line
			(start 1.524 0.36449)
			(end -1.27 0.36449)
			(stroke
				(width 0.1524)
				(type default)
			)
			(layer "F.SilkS")
		)
		(fp_line
			(start 1.09347 0)
			(end 1.45796 0.36449)
			(stroke
				(width 0.1524)
				(type default)
			)
			(layer "F.SilkS")
		)
		(fp_line
			(start -1.27 -0.36449)
			(end -1.27 0.36449)
			(stroke
				(width 0.1524)
				(type default)
			)
			(layer "F.SilkS")
		)
		(fp_line
			(start -1.27 -0.36449)
			(end 1.524 -0.36449)
			(stroke
				(width 0.1524)
				(type default)
			)
			(layer "F.SilkS")
		)
		(fp_line
			(start 1.45796 -0.36449)
			(end 1.09347 0)
			(stroke
				(width 0.1524)
				(type default)
			)
			(layer "F.SilkS")
		)
		(fp_line
			(start 1.524 -0.36449)
			(end 1.524 0.36449)
			(stroke
				(width 0.1524)
				(type default)
			)
			(layer "F.SilkS")
		)
		(fp_line
			(start 1.524 -0.36449)
			(end 1.45796 -0.36449)
			(stroke
				(width 0.1524)
				(type default)
			)
			(layer "F.SilkS")
		)
		(fp_line
			(start 1.524 -0.36449)
			(end 1.524 -1.82245)
			(stroke
				(width 0.508)
				(type default)
			)
			(layer "F.SilkS")
		)
		(fp_poly
			(pts
				(xy -0.65024 0.36449) (xy -0.65024 -0.36449) (xy 0.65024 -0.36449) (xy 0.65024 0.36449)
			)
			(stroke
				(width 0)
				(type default)
			)
			(fill yes)
			(layer "F.SilkS")
		)
		(fp_poly
			(pts
				(xy 1.016 -1.0668) (xy 1.016 1.0668) (xy -1.016 1.0668) (xy -1.016 -1.0668)
			)
			(stroke
				(width 0)
				(type default)
			)
			(fill no)
			(layer "F.CrtYd")
		)
		(fp_poly
			(pts
				(xy -1.524 1.905) (xy 1.524 1.905) (xy 1.524 -1.06426) (xy 1.016 -1.06426) (xy 1.016 1.0668) (xy -1.016 1.0668)
				(xy -1.016 -1.0668) (xy 1.524 -1.0668) (xy 1.524 -1.905) (xy -1.524 -1.905)
			)
			(stroke
				(width 0)
				(type default)
			)
			(fill no)
			(layer "F.CrtYd")
		)
		(fp_poly
			(pts
				(xy -1.524 -1.905) (xy -1.524 1.905) (xy 1.524 1.905) (xy 1.524 -1.905)
			)
			(stroke
				(width 0)
				(type default)
			)
			(fill no)
			(layer "F.Fab")
		)
		(pad "1" smd rect
			(at 0.65024 -1.02489 270)
			(size 0.4064 0.8128)
			(layers "F.Cu" "F.Mask" "F.Paste")
			(net "P12V_IN")
		)
		(pad "2" smd rect
			(at 0 -1.02489 270)
			(size 0.4064 0.8128)
			(layers "F.Cu" "F.Mask" "F.Paste")
			(net "FAN_YELLOW_LED0")
		)
		(pad "3" smd rect
			(at -0.65024 -1.02489 270)
			(size 0.4064 0.8128)
			(layers "F.Cu" "F.Mask" "F.Paste")
			(net "FAN_BLUE0")
		)
		(pad "4" smd rect
			(at -0.65024 1.02489 270)
			(size 0.4064 0.8128)
			(layers "F.Cu" "F.Mask" "F.Paste")
			(net "P12V_IN")
		)
		(pad "5" smd rect
			(at 0 1.02489 270)
			(size 0.4064 0.8128)
			(layers "F.Cu" "F.Mask" "F.Paste")
			(net "FAN_BLUE_LED0")
		)
		(pad "6" smd rect
			(at 0.65024 1.02489 270)
			(size 0.4064 0.8128)
			(layers "F.Cu" "F.Mask" "F.Paste")
			(net "FAN_YELLOW_0")
		)
	)
	(footprint ""
		(layer "F.Cu")
		(at 48.514 -247.65 180)
		(property "Reference" "D1"
			(at 0 0 180)
			(layer "F.SilkS")
			(hide yes)
			(effects
				(font
					(size 1.27 1.27)
				)
			)
		)
		(property "Value" "RB551V30-GP"
			(at 0 -6.7818 180)
			(unlocked yes)
			(layer "F.Fab")
			(hide yes)
			(effects
				(font
					(size 1.016 1.016)
					(thickness 0.1524)
				)
			)
		)
		(property "Device Type" "SOD323AKH38"
			(at 0 -8.6868 180)
			(unlocked yes)
			(layer "F.Fab")
			(hide yes)
			(effects
				(font
					(size 1.016 1.016)
					(thickness 0.1524)
				)
			)
		)
		(duplicate_pad_numbers_are_jumpers no)
		(fp_line
			(start 0.889 2.159)
			(end -0.889 2.159)
			(stroke
				(width 0.1524)
				(type default)
			)
			(layer "F.SilkS")
		)
		(fp_line
			(start 0.889 -1.9304)
			(end 0.889 2.159)
			(stroke
				(width 0.1524)
				(type default)
			)
			(layer "F.SilkS")
		)
		(fp_line
			(start 0.762 2.0574)
			(end -0.762 2.0574)
			(stroke
				(width 0.508)
				(type default)
			)
			(layer "F.SilkS")
		)
		(fp_line
			(start -0.889 2.159)
			(end -0.889 -1.9304)
			(stroke
				(width 0.1524)
				(type default)
			)
			(layer "F.SilkS")
		)
		(fp_line
			(start -0.889 -1.9304)
			(end 0.889 -1.9304)
			(stroke
				(width 0.1524)
				(type default)
			)
			(layer "F.SilkS")
		)
		(fp_rect
			(start -1.016 2.3114)
			(end 1.016 -2.0066)
			(stroke
				(width 0)
				(type default)
			)
			(fill no)
			(layer "F.CrtYd")
		)
		(fp_poly
			(pts
				(xy -1.016 -2.0066) (xy 1.016 -2.0066) (xy 1.016 2.3114) (xy -1.016 2.3114)
			)
			(stroke
				(width 0)
				(type default)
			)
			(fill no)
			(layer "F.Fab")
		)
		(pad "A" smd rect
			(at 0 -1.143 180)
			(size 0.5588 1.016)
			(layers "F.Cu" "F.Mask" "F.Paste")
			(net "SW_HDD_R1")
		)
		(pad "K" smd rect
			(at 0 1.143 180)
			(size 0.5588 1.016)
			(layers "F.Cu" "F.Mask" "F.Paste")
			(net "SW_HDD_N1")
		)
	)
	(footprint ""
		(layer "F.Cu")
		(at 440.69 -99.187)
		(property "Reference" "R456"
			(at 0 0 0)
			(layer "F.SilkS")
			(hide yes)
			(effects
				(font
					(size 1.27 1.27)
				)
			)
		)
		(property "Value" "130R3F-GP"
			(at -0.0254 -2.5146 0)
			(unlocked yes)
			(layer "F.Fab")
			(hide yes)
			(effects
				(font
					(size 1.016 1.016)
					(thickness 0.1524)
				)
			)
		)
		(property "Device Type" "R603H22"
			(at -0.0254 -4.0386 0)
			(unlocked yes)
			(layer "F.Fab")
			(hide yes)
			(effects
				(font
					(size 1.016 1.016)
					(thickness 0.1524)
				)
			)
		)
		(duplicate_pad_numbers_are_jumpers no)
		(fp_line
			(start -0.4826 0)
			(end -0.2032 0)
			(stroke
				(width 0.2032)
				(type default)
			)
			(layer "F.SilkS")
		)
		(fp_line
			(start 0.2032 0)
			(end 0.4826 0)
			(stroke
				(width 0.2032)
				(type default)
			)
			(layer "F.SilkS")
		)
		(fp_rect
			(start -0.5842 1.3335)
			(end 0.5842 -1.3335)
			(stroke
				(width 0)
				(type default)
			)
			(fill no)
			(layer "F.CrtYd")
		)
		(fp_rect
			(start -0.5842 1.3335)
			(end 0.5842 -1.3335)
			(stroke
				(width 0)
				(type default)
			)
			(fill no)
			(layer "F.Fab")
		)
		(pad "1" smd custom
			(at 0 -0.762)
			(size 0.2159 0.2159)
			(layers "F.Cu" "F.Mask" "F.Paste")
			(net "P5V_B_4")
			(options
				(clearance outline)
				(anchor circle)
			)
			(primitives
				(gr_poly
					(pts
						(arc
							(start -0.3302 -0.4318)
							(mid -0.402042 -0.402042)
							(end -0.4318 -0.3302)
						)
						(arc
							(start -0.4318 0.3302)
							(mid -0.402042 0.402042)
							(end -0.3302 0.4318)
						)
						(arc
							(start 0.3302 0.4318)
							(mid 0.402042 0.402042)
							(end 0.4318 0.3302)
						)
						(arc
							(start 0.4318 -0.3302)
							(mid 0.402042 -0.402042)
							(end 0.3302 -0.4318)
						)
					)
					(width 0)
					(fill yes)
				)
			)
		)
		(pad "2" smd custom
			(at 0 0.762)
			(size 0.2159 0.2159)
			(layers "F.Cu" "F.Mask" "F.Paste")
			(net "FLT_HDD22")
			(options
				(clearance outline)
				(anchor circle)
			)
			(primitives
				(gr_poly
					(pts
						(arc
							(start -0.3302 -0.4318)
							(mid -0.402042 -0.402042)
							(end -0.4318 -0.3302)
						)
						(arc
							(start -0.4318 0.3302)
							(mid -0.402042 0.402042)
							(end -0.3302 0.4318)
						)
						(arc
							(start 0.3302 0.4318)
							(mid 0.402042 0.402042)
							(end 0.4318 0.3302)
						)
						(arc
							(start 0.4318 -0.3302)
							(mid 0.402042 -0.402042)
							(end 0.3302 -0.4318)
						)
					)
					(width 0)
					(fill yes)
				)
			)
		)
	)
	(footprint ""
		(layer "F.Cu")
		(at 214.24773 -353.792536 90)
		(property "Reference" "R152"
			(at 0 0 90)
			(layer "F.SilkS")
			(hide yes)
			(effects
				(font
					(size 1.27 1.27)
				)
			)
		)
		(property "Value" "0R5J-5-GP"
			(at 0 -8.9535 90)
			(unlocked yes)
			(layer "F.Fab")
			(hide yes)
			(effects
				(font
					(size 1.27 1.016)
					(thickness 0.1524)
				)
			)
		)
		(property "Device Type" "R805H24"
			(at 0 -10.6299 90)
			(unlocked yes)
			(layer "F.Fab")
			(hide yes)
			(effects
				(font
					(size 1.27 1.016)
					(thickness 0.1524)
				)
			)
		)
		(duplicate_pad_numbers_are_jumpers no)
		(fp_line
			(start 0.889 -1.7018)
			(end -0.889 -1.7018)
			(stroke
				(width 0.1524)
				(type default)
			)
			(layer "F.SilkS")
		)
		(fp_line
			(start 0.889 -1.7018)
			(end 0.889 -0.381)
			(stroke
				(width 0.1524)
				(type default)
			)
			(layer "F.SilkS")
		)
		(fp_line
			(start -0.889 -1.7018)
			(end -0.889 0.2794)
			(stroke
				(width 0.1524)
				(type default)
			)
			(layer "F.SilkS")
		)
		(fp_line
			(start -0.889 0.0762)
			(end -0.889 1.7018)
			(stroke
				(width 0.1524)
				(type default)
			)
			(layer "F.SilkS")
		)
		(fp_line
			(start 0.889 1.7018)
			(end 0.889 -0.508)
			(stroke
				(width 0.1524)
				(type default)
			)
			(layer "F.SilkS")
		)
		(fp_line
			(start -0.889 1.7018)
			(end 0.889 1.7018)
			(stroke
				(width 0.1524)
				(type default)
			)
			(layer "F.SilkS")
		)
		(fp_poly
			(pts
				(xy 0.9652 -1.778) (xy 0.9652 1.778) (xy -0.9652 1.778) (xy -0.9652 -1.778)
			)
			(stroke
				(width 0)
				(type default)
			)
			(fill no)
			(layer "F.CrtYd")
		)
		(fp_rect
			(start -0.9652 1.778)
			(end 0.9652 -1.778)
			(stroke
				(width 0)
				(type default)
			)
			(fill no)
			(layer "F.Fab")
		)
		(pad "1" smd rect
			(at 0 -0.9652 90)
			(size 1.397 1.143)
			(layers "F.Cu" "F.Mask" "F.Paste")
			(net "MB0_CM_GATE_R")
		)
		(pad "2" smd rect
			(at 0 0.9652 90)
			(size 1.397 1.143)
			(layers "F.Cu" "F.Mask" "F.Paste")
			(net "MB0_CM_GATE_C")
		)
	)
	(footprint ""
		(layer "F.Cu")
		(at 392.938 -152.908 180)
		(property "Reference" "C290"
			(at 0 0 180)
			(layer "F.SilkS")
			(hide yes)
			(effects
				(font
					(size 1.27 1.27)
				)
			)
		)
		(property "Value" "SC1U16V3KX-5GP"
			(at 0 -2.8194 180)
			(unlocked yes)
			(layer "F.Fab")
			(hide yes)
			(effects
				(font
					(size 1.016 1.016)
					(thickness 0.1524)
				)
			)
		)
		(property "Device Type" "C603H36"
			(at 0 -4.3434 180)
			(unlocked yes)
			(layer "F.Fab")
			(hide yes)
			(effects
				(font
					(size 1.016 1.016)
					(thickness 0.1524)
				)
			)
		)
		(duplicate_pad_numbers_are_jumpers no)
		(fp_line
			(start 0.508 0)
			(end -0.508 0)
			(stroke
				(width 0.2032)
				(type default)
			)
			(layer "F.SilkS")
		)
		(fp_rect
			(start -0.5842 1.3335)
			(end 0.5842 -1.3335)
			(stroke
				(width 0)
				(type default)
			)
			(fill no)
			(layer "F.CrtYd")
		)
		(fp_rect
			(start -0.5842 1.3335)
			(end 0.5842 -1.3335)
			(stroke
				(width 0)
				(type default)
			)
			(fill no)
			(layer "F.Fab")
		)
		(pad "1" smd custom
			(at 0 -0.762 180)
			(size 0.2159 0.2159)
			(layers "F.Cu" "F.Mask" "F.Paste")
			(net "P5V_HDD20")
			(options
				(clearance outline)
				(anchor circle)
			)
			(primitives
				(gr_poly
					(pts
						(arc
							(start -0.3302 -0.4318)
							(mid -0.402042 -0.402042)
							(end -0.4318 -0.3302)
						)
						(arc
							(start -0.4318 0.3302)
							(mid -0.402042 0.402042)
							(end -0.3302 0.4318)
						)
						(arc
							(start 0.3302 0.4318)
							(mid 0.402042 0.402042)
							(end 0.4318 0.3302)
						)
						(arc
							(start 0.4318 -0.3302)
							(mid 0.402042 -0.402042)
							(end 0.3302 -0.4318)
						)
					)
					(width 0)
					(fill yes)
				)
			)
		)
		(pad "2" smd custom
			(at 0 0.762 180)
			(size 0.2159 0.2159)
			(layers "F.Cu" "F.Mask" "F.Paste")
			(net "GND")
			(options
				(clearance outline)
				(anchor circle)
			)
			(primitives
				(gr_poly
					(pts
						(arc
							(start -0.3302 -0.4318)
							(mid -0.402042 -0.402042)
							(end -0.4318 -0.3302)
						)
						(arc
							(start -0.4318 0.3302)
							(mid -0.402042 0.402042)
							(end -0.3302 0.4318)
						)
						(arc
							(start 0.3302 0.4318)
							(mid 0.402042 0.402042)
							(end 0.4318 0.3302)
						)
						(arc
							(start 0.4318 -0.3302)
							(mid 0.402042 -0.402042)
							(end 0.3302 -0.4318)
						)
					)
					(width 0)
					(fill yes)
				)
			)
		)
	)
	(footprint ""
		(layer "F.Cu")
		(at 369.57 -20.447 90)
		(property "Reference" "R799"
			(at 0 0 90)
			(layer "F.SilkS")
			(hide yes)
			(effects
				(font
					(size 1.27 1.27)
				)
			)
		)
		(property "Value" "200KR2F-L-GP"
			(at 0.064008 -3.993896 90)
			(unlocked yes)
			(layer "F.Fab")
			(hide yes)
			(effects
				(font
					(size 1.016 1.016)
					(thickness 0.1524)
				)
			)
		)
		(property "Device Type" "R402H16"
			(at 0.064008 -5.517896 90)
			(unlocked yes)
			(layer "F.Fab")
			(hide yes)
			(effects
				(font
					(size 1.016 1.016)
					(thickness 0.1524)
				)
			)
		)
		(duplicate_pad_numbers_are_jumpers no)
		(fp_line
			(start 0.508 -0.9398)
			(end -0.508 -0.9398)
			(stroke
				(width 0.1524)
				(type default)
			)
			(layer "F.SilkS")
		)
		(fp_line
			(start -0.508 -0.9398)
			(end -0.508 0.9398)
			(stroke
				(width 0.1524)
				(type default)
			)
			(layer "F.SilkS")
		)
		(fp_rect
			(start -0.508 0.9398)
			(end 0.508 -0.9398)
			(stroke
				(width 0)
				(type default)
			)
			(fill no)
			(layer "F.CrtYd")
		)
		(fp_rect
			(start -0.508 0.9398)
			(end 0.508 -0.9398)
			(stroke
				(width 0)
				(type default)
			)
			(fill no)
			(layer "F.Fab")
		)
		(pad "1" smd custom
			(at 0 -0.4445 90)
			(size 0.1397 0.1397)
			(layers "F.Cu" "F.Mask" "F.Paste")
			(net "SW_HDD_R31")
			(options
				(clearance outline)
				(anchor circle)
			)
			(primitives
				(gr_poly
					(pts
						(arc
							(start -0.1778 -0.2794)
							(mid -0.249642 -0.249642)
							(end -0.2794 -0.1778)
						)
						(arc
							(start -0.2794 0.1778)
							(mid -0.249642 0.249642)
							(end -0.1778 0.2794)
						)
						(arc
							(start 0.1778 0.2794)
							(mid 0.249642 0.249642)
							(end 0.2794 0.1778)
						)
						(arc
							(start 0.2794 -0.1778)
							(mid 0.249642 -0.249642)
							(end 0.1778 -0.2794)
						)
					)
					(width 0)
					(fill yes)
				)
			)
		)
		(pad "2" smd custom
			(at 0 0.4445 90)
			(size 0.1397 0.1397)
			(layers "F.Cu" "F.Mask" "F.Paste")
			(net "SW_HDD_N31")
			(options
				(clearance outline)
				(anchor circle)
			)
			(primitives
				(gr_poly
					(pts
						(arc
							(start -0.1778 -0.2794)
							(mid -0.249642 -0.249642)
							(end -0.2794 -0.1778)
						)
						(arc
							(start -0.2794 0.1778)
							(mid -0.249642 0.249642)
							(end -0.1778 0.2794)
						)
						(arc
							(start 0.1778 0.2794)
							(mid 0.249642 0.249642)
							(end 0.2794 0.1778)
						)
						(arc
							(start 0.2794 -0.1778)
							(mid 0.249642 -0.249642)
							(end 0.1778 -0.2794)
						)
					)
					(width 0)
					(fill yes)
				)
			)
		)
	)
	(footprint ""
		(layer "F.Cu")
		(at 343.993978 -217.413586 -90)
		(property "Reference" "R258"
			(at 0 0 270)
			(layer "F.SilkS")
			(hide yes)
			(effects
				(font
					(size 1.27 1.27)
				)
			)
		)
		(property "Value" "4K7R2F-GP"
			(at 0.064008 -3.993896 270)
			(unlocked yes)
			(layer "F.Fab")
			(hide yes)
			(effects
				(font
					(size 1.016 1.016)
					(thickness 0.1524)
				)
			)
		)
		(property "Device Type" "R402H16"
			(at 0.064008 -5.517896 270)
			(unlocked yes)
			(layer "F.Fab")
			(hide yes)
			(effects
				(font
					(size 1.016 1.016)
					(thickness 0.1524)
				)
			)
		)
		(duplicate_pad_numbers_are_jumpers no)
		(fp_line
			(start -0.508 -0.9398)
			(end -0.508 0.9398)
			(stroke
				(width 0.1524)
				(type default)
			)
			(layer "F.SilkS")
		)
		(fp_line
			(start 0.508 -0.9398)
			(end -0.508 -0.9398)
			(stroke
				(width 0.1524)
				(type default)
			)
			(layer "F.SilkS")
		)
		(fp_rect
			(start -0.508 0.9398)
			(end 0.508 -0.9398)
			(stroke
				(width 0)
				(type default)
			)
			(fill no)
			(layer "F.CrtYd")
		)
		(fp_rect
			(start -0.508 0.9398)
			(end 0.508 -0.9398)
			(stroke
				(width 0)
				(type default)
			)
			(fill no)
			(layer "F.Fab")
		)
		(pad "1" smd custom
			(at 0 -0.4445 270)
			(size 0.1397 0.1397)
			(layers "F.Cu" "F.Mask" "F.Paste")
			(net "DRIVE_B_7_FLT_LED")
			(options
				(clearance outline)
				(anchor circle)
			)
			(primitives
				(gr_poly
					(pts
						(arc
							(start -0.1778 -0.2794)
							(mid -0.249642 -0.249642)
							(end -0.2794 -0.1778)
						)
						(arc
							(start -0.2794 0.1778)
							(mid -0.249642 0.249642)
							(end -0.1778 0.2794)
						)
						(arc
							(start 0.1778 0.2794)
							(mid 0.249642 0.249642)
							(end 0.2794 0.1778)
						)
						(arc
							(start 0.2794 -0.1778)
							(mid 0.249642 -0.249642)
							(end 0.1778 -0.2794)
						)
					)
					(width 0)
					(fill yes)
				)
			)
		)
		(pad "2" smd custom
			(at 0 0.4445 270)
			(size 0.1397 0.1397)
			(layers "F.Cu" "F.Mask" "F.Paste")
			(net "GND")
			(options
				(clearance outline)
				(anchor circle)
			)
			(primitives
				(gr_poly
					(pts
						(arc
							(start -0.1778 -0.2794)
							(mid -0.249642 -0.249642)
							(end -0.2794 -0.1778)
						)
						(arc
							(start -0.2794 0.1778)
							(mid -0.249642 0.249642)
							(end -0.1778 0.2794)
						)
						(arc
							(start 0.1778 0.2794)
							(mid 0.249642 0.249642)
							(end 0.2794 0.1778)
						)
						(arc
							(start 0.2794 -0.1778)
							(mid 0.249642 -0.249642)
							(end 0.1778 -0.2794)
						)
					)
					(width 0)
					(fill yes)
				)
			)
		)
	)
	(footprint ""
		(layer "F.Cu")
		(at 20.447 -134.493 180)
		(property "Reference" "Q47"
			(at 0 0 180)
			(layer "F.SilkS")
			(hide yes)
			(effects
				(font
					(size 1.27 1.27)
				)
			)
		)
		(property "Value" "2N7002KDW-GP"
			(at -2.3622 -8.2042 180)
			(unlocked yes)
			(layer "F.Fab")
			(hide yes)
			(effects
				(font
					(size 1.016 1.016)
					(thickness 0.1524)
				)
			)
		)
		(property "Device Type" "SOT-363H44"
			(at -2.3622 -10.1092 180)
			(unlocked yes)
			(layer "F.Fab")
			(hide yes)
			(effects
				(font
					(size 1.016 1.016)
					(thickness 0.1524)
				)
			)
		)
		(duplicate_pad_numbers_are_jumpers no)
		(fp_line
			(start 1.4478 1.7018)
			(end 1.4478 -1.7018)
			(stroke
				(width 0.1524)
				(type default)
			)
			(layer "F.SilkS")
		)
		(fp_line
			(start 1.4478 -1.7018)
			(end -1.4478 -1.7018)
			(stroke
				(width 0.1524)
				(type default)
			)
			(layer "F.SilkS")
		)
		(fp_line
			(start -1.27 1.524)
			(end -1.27 0.6604)
			(stroke
				(width 0.4826)
				(type default)
			)
			(layer "F.SilkS")
		)
		(fp_line
			(start -1.4478 1.7018)
			(end 1.4478 1.7018)
			(stroke
				(width 0.1524)
				(type default)
			)
			(layer "F.SilkS")
		)
		(fp_line
			(start -1.4478 -1.7018)
			(end -1.4478 1.7018)
			(stroke
				(width 0.1524)
				(type default)
			)
			(layer "F.SilkS")
		)
		(fp_poly
			(pts
				(xy -1.524 -1.778) (xy 1.524 -1.778) (xy 1.524 1.778) (xy -1.524 1.778)
			)
			(stroke
				(width 0)
				(type default)
			)
			(fill no)
			(layer "F.CrtYd")
		)
		(fp_poly
			(pts
				(xy -1.524 -1.778) (xy 1.524 -1.778) (xy 1.524 1.778) (xy -1.524 1.778)
			)
			(stroke
				(width 0)
				(type default)
			)
			(fill no)
			(layer "F.Fab")
		)
		(pad "1" smd rect
			(at -0.65024 0.9398 180)
			(size 0.4064 1.016)
			(layers "F.Cu" "F.Mask" "F.Paste")
			(net "GND")
		)
		(pad "2" smd rect
			(at 0 0.9398 180)
			(size 0.4064 1.016)
			(layers "F.Cu" "F.Mask" "F.Paste")
			(net "SW_PWR_R_HDD12")
		)
		(pad "3" smd rect
			(at 0.65024 0.9398 180)
			(size 0.4064 1.016)
			(layers "F.Cu" "F.Mask" "F.Paste")
			(net "SW_HDD_P12")
		)
		(pad "4" smd rect
			(at 0.65024 -0.9398 180)
			(size 0.4064 1.016)
			(layers "F.Cu" "F.Mask" "F.Paste")
			(net "GND")
		)
		(pad "5" smd rect
			(at 0 -0.9398 180)
			(size 0.4064 1.016)
			(layers "F.Cu" "F.Mask" "F.Paste")
			(net "SW_HDD_G12")
		)
		(pad "6" smd rect
			(at -0.65024 -0.9398 180)
			(size 0.4064 1.016)
			(layers "F.Cu" "F.Mask" "F.Paste")
			(net "SW_HDD_R12")
		)
	)
	(footprint ""
		(layer "F.Cu")
		(at 319.83553 -99.820476 90)
		(property "Reference" "Q260"
			(at 0 0 90)
			(layer "F.SilkS")
			(hide yes)
			(effects
				(font
					(size 1.27 1.27)
				)
			)
		)
		(property "Value" "SSM3K324R-GP"
			(at 0.127 -8.9662 90)
			(unlocked yes)
			(layer "F.Fab")
			(hide yes)
			(effects
				(font
					(size 1.016 1.016)
					(thickness 0.1524)
				)
			)
		)
		(property "Device Type" "SOT23DGS2D4H35"
			(at 0.127 -10.4902 90)
			(unlocked yes)
			(layer "F.Fab")
			(hide yes)
			(effects
				(font
					(size 1.016 1.016)
					(thickness 0.1524)
				)
			)
		)
		(duplicate_pad_numbers_are_jumpers no)
		(fp_line
			(start 1.651 -1.778)
			(end -1.651 -1.778)
			(stroke
				(width 0.1524)
				(type default)
			)
			(layer "F.SilkS")
		)
		(fp_line
			(start -1.651 -1.778)
			(end -1.651 1.778)
			(stroke
				(width 0.1524)
				(type default)
			)
			(layer "F.SilkS")
		)
		(fp_line
			(start 1.651 1.778)
			(end 1.651 -1.778)
			(stroke
				(width 0.1524)
				(type default)
			)
			(layer "F.SilkS")
		)
		(fp_line
			(start -1.651 1.778)
			(end 1.651 1.778)
			(stroke
				(width 0.1524)
				(type default)
			)
			(layer "F.SilkS")
		)
		(fp_poly
			(pts
				(xy -1.778 1.8796) (xy -1.778 -1.8796) (xy 1.778 -1.8796) (xy 1.778 1.8796)
			)
			(stroke
				(width 0)
				(type default)
			)
			(fill no)
			(layer "F.CrtYd")
		)
		(fp_poly
			(pts
				(xy -1.778 1.8796) (xy -1.778 -1.8796) (xy 1.778 -1.8796) (xy 1.778 1.8796)
			)
			(stroke
				(width 0)
				(type default)
			)
			(fill no)
			(layer "F.Fab")
		)
		(pad "D" smd custom
			(at 0 -0.9525 90)
			(size 0.1905 0.1905)
			(layers "F.Cu" "F.Mask" "F.Paste")
			(net "DRV_ACT_18_N")
			(options
				(clearance outline)
				(anchor circle)
			)
			(primitives
				(gr_poly
					(pts
						(arc
							(start -0.1778 0.5715)
							(mid -0.321484 0.511984)
							(end -0.381 0.3683)
						)
						(arc
							(start -0.381 -0.3683)
							(mid -0.321484 -0.511984)
							(end -0.1778 -0.5715)
						)
						(arc
							(start 0.1778 -0.5715)
							(mid 0.321484 -0.511984)
							(end 0.381 -0.3683)
						)
						(arc
							(start 0.381 0.3683)
							(mid 0.321484 0.511984)
							(end 0.1778 0.5715)
						)
					)
					(width 0)
					(fill yes)
				)
			)
		)
		(pad "G" smd custom
			(at -0.98425 0.9525 90)
			(size 0.1905 0.1905)
			(layers "F.Cu" "F.Mask" "F.Paste")
			(net "DRIVE_B_18_ACT")
			(options
				(clearance outline)
				(anchor circle)
			)
			(primitives
				(gr_poly
					(pts
						(arc
							(start -0.1778 0.5715)
							(mid -0.321484 0.511984)
							(end -0.381 0.3683)
						)
						(arc
							(start -0.381 -0.3683)
							(mid -0.321484 -0.511984)
							(end -0.1778 -0.5715)
						)
						(arc
							(start 0.1778 -0.5715)
							(mid 0.321484 -0.511984)
							(end 0.381 -0.3683)
						)
						(arc
							(start 0.381 0.3683)
							(mid 0.321484 0.511984)
							(end 0.1778 0.5715)
						)
					)
					(width 0)
					(fill yes)
				)
			)
		)
		(pad "S" smd custom
			(at 0.98425 0.9525 90)
			(size 0.1905 0.1905)
			(layers "F.Cu" "F.Mask" "F.Paste")
			(net "GND")
			(options
				(clearance outline)
				(anchor circle)
			)
			(primitives
				(gr_poly
					(pts
						(arc
							(start -0.1778 0.5715)
							(mid -0.321484 0.511984)
							(end -0.381 0.3683)
						)
						(arc
							(start -0.381 -0.3683)
							(mid -0.321484 -0.511984)
							(end -0.1778 -0.5715)
						)
						(arc
							(start 0.1778 -0.5715)
							(mid 0.321484 -0.511984)
							(end 0.381 -0.3683)
						)
						(arc
							(start 0.381 0.3683)
							(mid 0.321484 0.511984)
							(end 0.1778 0.5715)
						)
					)
					(width 0)
					(fill yes)
				)
			)
		)
	)
	(footprint ""
		(layer "F.Cu")
		(at 98.425 -263.144 -90)
		(property "Reference" "R191"
			(at 0 0 270)
			(layer "F.SilkS")
			(hide yes)
			(effects
				(font
					(size 1.27 1.27)
				)
			)
		)
		(property "Value" "10KR2F-2-GP"
			(at 0.064008 -3.993896 270)
			(unlocked yes)
			(layer "F.Fab")
			(hide yes)
			(effects
				(font
					(size 1.016 1.016)
					(thickness 0.1524)
				)
			)
		)
		(property "Device Type" "R402H16"
			(at 0.064008 -5.517896 270)
			(unlocked yes)
			(layer "F.Fab")
			(hide yes)
			(effects
				(font
					(size 1.016 1.016)
					(thickness 0.1524)
				)
			)
		)
		(duplicate_pad_numbers_are_jumpers no)
		(fp_line
			(start -0.508 -0.9398)
			(end -0.508 0.9398)
			(stroke
				(width 0.1524)
				(type default)
			)
			(layer "F.SilkS")
		)
		(fp_line
			(start 0.508 -0.9398)
			(end -0.508 -0.9398)
			(stroke
				(width 0.1524)
				(type default)
			)
			(layer "F.SilkS")
		)
		(fp_rect
			(start -0.508 0.9398)
			(end 0.508 -0.9398)
			(stroke
				(width 0)
				(type default)
			)
			(fill no)
			(layer "F.CrtYd")
		)
		(fp_rect
			(start -0.508 0.9398)
			(end 0.508 -0.9398)
			(stroke
				(width 0)
				(type default)
			)
			(fill no)
			(layer "F.Fab")
		)
		(pad "1" smd custom
			(at 0 -0.4445 270)
			(size 0.1397 0.1397)
			(layers "F.Cu" "F.Mask" "F.Paste")
			(net "P3V3_STBY_B")
			(options
				(clearance outline)
				(anchor circle)
			)
			(primitives
				(gr_poly
					(pts
						(arc
							(start -0.1778 -0.2794)
							(mid -0.249642 -0.249642)
							(end -0.2794 -0.1778)
						)
						(arc
							(start -0.2794 0.1778)
							(mid -0.249642 0.249642)
							(end -0.1778 0.2794)
						)
						(arc
							(start 0.1778 0.2794)
							(mid 0.249642 0.249642)
							(end 0.2794 0.1778)
						)
						(arc
							(start 0.2794 -0.1778)
							(mid 0.249642 -0.249642)
							(end 0.1778 -0.2794)
						)
					)
					(width 0)
					(fill yes)
				)
			)
		)
		(pad "2" smd custom
			(at 0 0.4445 270)
			(size 0.1397 0.1397)
			(layers "F.Cu" "F.Mask" "F.Paste")
			(net "HDD_PRSNT_2")
			(options
				(clearance outline)
				(anchor circle)
			)
			(primitives
				(gr_poly
					(pts
						(arc
							(start -0.1778 -0.2794)
							(mid -0.249642 -0.249642)
							(end -0.2794 -0.1778)
						)
						(arc
							(start -0.2794 0.1778)
							(mid -0.249642 0.249642)
							(end -0.1778 0.2794)
						)
						(arc
							(start 0.1778 0.2794)
							(mid 0.249642 0.249642)
							(end 0.2794 0.1778)
						)
						(arc
							(start 0.2794 -0.1778)
							(mid 0.249642 -0.249642)
							(end 0.1778 -0.2794)
						)
					)
					(width 0)
					(fill yes)
				)
			)
		)
	)
	(footprint ""
		(layer "F.Cu")
		(at 458.216 -131.318 -90)
		(property "Reference" "Q107"
			(at 0 0 270)
			(layer "F.SilkS")
			(hide yes)
			(effects
				(font
					(size 1.27 1.27)
				)
			)
		)
		(property "Value" "2N7002KDW-GP"
			(at -2.3622 -8.2042 270)
			(unlocked yes)
			(layer "F.Fab")
			(hide yes)
			(effects
				(font
					(size 1.016 1.016)
					(thickness 0.1524)
				)
			)
		)
		(property "Device Type" "SOT-363H44"
			(at -2.3622 -10.1092 270)
			(unlocked yes)
			(layer "F.Fab")
			(hide yes)
			(effects
				(font
					(size 1.016 1.016)
					(thickness 0.1524)
				)
			)
		)
		(duplicate_pad_numbers_are_jumpers no)
		(fp_line
			(start -1.4478 1.7018)
			(end 1.4478 1.7018)
			(stroke
				(width 0.1524)
				(type default)
			)
			(layer "F.SilkS")
		)
		(fp_line
			(start 1.4478 1.7018)
			(end 1.4478 -1.7018)
			(stroke
				(width 0.1524)
				(type default)
			)
			(layer "F.SilkS")
		)
		(fp_line
			(start -1.27 1.524)
			(end -1.27 0.6604)
			(stroke
				(width 0.4826)
				(type default)
			)
			(layer "F.SilkS")
		)
		(fp_line
			(start -1.4478 -1.7018)
			(end -1.4478 1.7018)
			(stroke
				(width 0.1524)
				(type default)
			)
			(layer "F.SilkS")
		)
		(fp_line
			(start 1.4478 -1.7018)
			(end -1.4478 -1.7018)
			(stroke
				(width 0.1524)
				(type default)
			)
			(layer "F.SilkS")
		)
		(fp_poly
			(pts
				(xy -1.524 -1.778) (xy 1.524 -1.778) (xy 1.524 1.778) (xy -1.524 1.778)
			)
			(stroke
				(width 0)
				(type default)
			)
			(fill no)
			(layer "F.CrtYd")
		)
		(fp_poly
			(pts
				(xy -1.524 -1.778) (xy 1.524 -1.778) (xy 1.524 1.778) (xy -1.524 1.778)
			)
			(stroke
				(width 0)
				(type default)
			)
			(fill no)
			(layer "F.Fab")
		)
		(pad "1" smd rect
			(at -0.65024 0.9398 270)
			(size 0.4064 1.016)
			(layers "F.Cu" "F.Mask" "F.Paste")
			(net "GND")
		)
		(pad "2" smd rect
			(at 0 0.9398 270)
			(size 0.4064 1.016)
			(layers "F.Cu" "F.Mask" "F.Paste")
			(net "SW_PWR_R_HDD22")
		)
		(pad "3" smd rect
			(at 0.65024 0.9398 270)
			(size 0.4064 1.016)
			(layers "F.Cu" "F.Mask" "F.Paste")
			(net "SW_HDD_P22")
		)
		(pad "4" smd rect
			(at 0.65024 -0.9398 270)
			(size 0.4064 1.016)
			(layers "F.Cu" "F.Mask" "F.Paste")
			(net "GND")
		)
		(pad "5" smd rect
			(at 0 -0.9398 270)
			(size 0.4064 1.016)
			(layers "F.Cu" "F.Mask" "F.Paste")
			(net "SW_HDD_G22")
		)
		(pad "6" smd rect
			(at -0.65024 -0.9398 270)
			(size 0.4064 1.016)
			(layers "F.Cu" "F.Mask" "F.Paste")
			(net "SW_HDD_R22")
		)
	)
	(footprint ""
		(layer "F.Cu")
		(at 361.315 -45.339 180)
		(property "Reference" "C439"
			(at 0 0 180)
			(layer "F.SilkS")
			(hide yes)
			(effects
				(font
					(size 1.27 1.27)
				)
			)
		)
		(property "Value" "SC1U25V3KX-GP"
			(at 0 -2.8194 180)
			(unlocked yes)
			(layer "F.Fab")
			(hide yes)
			(effects
				(font
					(size 1.016 1.016)
					(thickness 0.1524)
				)
			)
		)
		(property "Device Type" "C603H36"
			(at 0 -4.3434 180)
			(unlocked yes)
			(layer "F.Fab")
			(hide yes)
			(effects
				(font
					(size 1.016 1.016)
					(thickness 0.1524)
				)
			)
		)
		(duplicate_pad_numbers_are_jumpers no)
		(fp_line
			(start 0.508 0)
			(end -0.508 0)
			(stroke
				(width 0.2032)
				(type default)
			)
			(layer "F.SilkS")
		)
		(fp_rect
			(start -0.5842 1.3335)
			(end 0.5842 -1.3335)
			(stroke
				(width 0)
				(type default)
			)
			(fill no)
			(layer "F.CrtYd")
		)
		(fp_rect
			(start -0.5842 1.3335)
			(end 0.5842 -1.3335)
			(stroke
				(width 0)
				(type default)
			)
			(fill no)
			(layer "F.Fab")
		)
		(pad "1" smd custom
			(at 0 -0.762 180)
			(size 0.2159 0.2159)
			(layers "F.Cu" "F.Mask" "F.Paste")
			(net "P12V_HDD31")
			(options
				(clearance outline)
				(anchor circle)
			)
			(primitives
				(gr_poly
					(pts
						(arc
							(start -0.3302 -0.4318)
							(mid -0.402042 -0.402042)
							(end -0.4318 -0.3302)
						)
						(arc
							(start -0.4318 0.3302)
							(mid -0.402042 0.402042)
							(end -0.3302 0.4318)
						)
						(arc
							(start 0.3302 0.4318)
							(mid 0.402042 0.402042)
							(end 0.4318 0.3302)
						)
						(arc
							(start 0.4318 -0.3302)
							(mid 0.402042 -0.402042)
							(end 0.3302 -0.4318)
						)
					)
					(width 0)
					(fill yes)
				)
			)
		)
		(pad "2" smd custom
			(at 0 0.762 180)
			(size 0.2159 0.2159)
			(layers "F.Cu" "F.Mask" "F.Paste")
			(net "GND")
			(options
				(clearance outline)
				(anchor circle)
			)
			(primitives
				(gr_poly
					(pts
						(arc
							(start -0.3302 -0.4318)
							(mid -0.402042 -0.402042)
							(end -0.4318 -0.3302)
						)
						(arc
							(start -0.4318 0.3302)
							(mid -0.402042 0.402042)
							(end -0.3302 0.4318)
						)
						(arc
							(start 0.3302 0.4318)
							(mid 0.402042 0.402042)
							(end 0.4318 0.3302)
						)
						(arc
							(start 0.4318 -0.3302)
							(mid 0.402042 -0.402042)
							(end 0.3302 -0.4318)
						)
					)
					(width 0)
					(fill yes)
				)
			)
		)
	)
	(footprint ""
		(layer "F.Cu")
		(at 260.970522 -366.115346)
		(property "Reference" "U1"
			(at 0 0 0)
			(layer "F.SilkS")
			(hide yes)
			(effects
				(font
					(size 1.27 1.27)
				)
			)
		)
		(property "Value" "SN74LVC1G08DCKR-GP"
			(at -2.3368 -8.6868 0)
			(unlocked yes)
			(layer "F.Fab")
			(hide yes)
			(effects
				(font
					(size 1.016 1.016)
					(thickness 0.1524)
				)
			)
		)
		(property "Device Type" "SC70-5H44"
			(at -2.3114 -10.414 0)
			(unlocked yes)
			(layer "F.Fab")
			(hide yes)
			(effects
				(font
					(size 1.016 1.016)
					(thickness 0.1524)
				)
			)
		)
		(duplicate_pad_numbers_are_jumpers no)
		(fp_line
			(start -1.27 -1.7018)
			(end 1.27 -1.7018)
			(stroke
				(width 0.1524)
				(type default)
			)
			(layer "F.SilkS")
		)
		(fp_line
			(start -1.27 1.7018)
			(end -1.27 -1.7018)
			(stroke
				(width 0.1524)
				(type default)
			)
			(layer "F.SilkS")
		)
		(fp_line
			(start 0.6604 -1.8034)
			(end 1.3843 -1.8034)
			(stroke
				(width 0.3302)
				(type default)
			)
			(layer "F.SilkS")
		)
		(fp_line
			(start 1.27 -1.7018)
			(end 1.27 1.7018)
			(stroke
				(width 0.1524)
				(type default)
			)
			(layer "F.SilkS")
		)
		(fp_line
			(start 1.27 1.7018)
			(end -1.27 1.7018)
			(stroke
				(width 0.1524)
				(type default)
			)
			(layer "F.SilkS")
		)
		(fp_line
			(start 1.3843 -1.8034)
			(end 1.3843 -1.1176)
			(stroke
				(width 0.3302)
				(type default)
			)
			(layer "F.SilkS")
		)
		(fp_rect
			(start -1.524 1.9558)
			(end 1.524 -1.9558)
			(stroke
				(width 0)
				(type default)
			)
			(fill no)
			(layer "F.CrtYd")
		)
		(fp_poly
			(pts
				(xy -1.524 -1.9558) (xy 1.524 -1.9558) (xy 1.524 1.9558) (xy -1.524 1.9558)
			)
			(stroke
				(width 0)
				(type default)
			)
			(fill no)
			(layer "F.Fab")
		)
		(pad "1" smd rect
			(at 0.65024 -0.8255)
			(size 0.4064 1.2192)
			(layers "F.Cu" "F.Mask" "F.Paste")
			(net "P12V_IN_PGOOD")
		)
		(pad "2" smd rect
			(at 0 -0.8255)
			(size 0.4064 1.2192)
			(layers "F.Cu" "F.Mask" "F.Paste")
			(net "DPB_PWR_BTN_BUF_B")
		)
		(pad "3" smd rect
			(at -0.65024 -0.8255)
			(size 0.4064 1.2192)
			(layers "F.Cu" "F.Mask" "F.Paste")
			(net "GND")
		)
		(pad "4" smd rect
			(at -0.65024 0.8255)
			(size 0.4064 1.2192)
			(layers "F.Cu" "F.Mask" "F.Paste")
			(net "MB3_HS_ENABLE")
		)
		(pad "5" smd rect
			(at 0.65024 0.8255)
			(size 0.4064 1.2192)
			(layers "F.Cu" "F.Mask" "F.Paste")
			(net "P3V3_IN_BIAS")
		)
	)
	(footprint ""
		(layer "F.Cu")
		(at 375.004076 -214.757 180)
		(property "Reference" "Q227"
			(at 0 0 180)
			(layer "F.SilkS")
			(hide yes)
			(effects
				(font
					(size 1.27 1.27)
				)
			)
		)
		(property "Value" "2N7002K-2-GP"
			(at 0.127 -8.9662 180)
			(unlocked yes)
			(layer "F.Fab")
			(hide yes)
			(effects
				(font
					(size 1.016 1.016)
					(thickness 0.1524)
				)
			)
		)
		(property "Device Type" "SOT23DGS2D4H44"
			(at 0.127 -10.4902 180)
			(unlocked yes)
			(layer "F.Fab")
			(hide yes)
			(effects
				(font
					(size 1.016 1.016)
					(thickness 0.1524)
				)
			)
		)
		(duplicate_pad_numbers_are_jumpers no)
		(fp_line
			(start 1.651 1.778)
			(end 1.651 -1.778)
			(stroke
				(width 0.1524)
				(type default)
			)
			(layer "F.SilkS")
		)
		(fp_line
			(start 1.651 -1.778)
			(end -1.651 -1.778)
			(stroke
				(width 0.1524)
				(type default)
			)
			(layer "F.SilkS")
		)
		(fp_line
			(start -1.651 1.778)
			(end 1.651 1.778)
			(stroke
				(width 0.1524)
				(type default)
			)
			(layer "F.SilkS")
		)
		(fp_line
			(start -1.651 -1.778)
			(end -1.651 1.778)
			(stroke
				(width 0.1524)
				(type default)
			)
			(layer "F.SilkS")
		)
		(fp_poly
			(pts
				(xy -1.778 1.8796) (xy -1.778 -1.8796) (xy 1.778 -1.8796) (xy 1.778 1.8796)
			)
			(stroke
				(width 0)
				(type default)
			)
			(fill no)
			(layer "F.CrtYd")
		)
		(fp_poly
			(pts
				(xy -1.778 1.8796) (xy -1.778 -1.8796) (xy 1.778 -1.8796) (xy 1.778 1.8796)
			)
			(stroke
				(width 0)
				(type default)
			)
			(fill no)
			(layer "F.Fab")
		)
		(pad "D" smd custom
			(at 0 -0.9525 180)
			(size 0.1905 0.1905)
			(layers "F.Cu" "F.Mask" "F.Paste")
			(net "FLT_HDD8_N")
			(options
				(clearance outline)
				(anchor circle)
			)
			(primitives
				(gr_poly
					(pts
						(arc
							(start -0.1778 0.5715)
							(mid -0.321484 0.511984)
							(end -0.381 0.3683)
						)
						(arc
							(start -0.381 -0.3683)
							(mid -0.321484 -0.511984)
							(end -0.1778 -0.5715)
						)
						(arc
							(start 0.1778 -0.5715)
							(mid 0.321484 -0.511984)
							(end 0.381 -0.3683)
						)
						(arc
							(start 0.381 0.3683)
							(mid 0.321484 0.511984)
							(end 0.1778 0.5715)
						)
					)
					(width 0)
					(fill yes)
				)
			)
		)
		(pad "G" smd custom
			(at -0.98425 0.9525 180)
			(size 0.1905 0.1905)
			(layers "F.Cu" "F.Mask" "F.Paste")
			(net "DRIVE_B_8_FLT_LED")
			(options
				(clearance outline)
				(anchor circle)
			)
			(primitives
				(gr_poly
					(pts
						(arc
							(start -0.1778 0.5715)
							(mid -0.321484 0.511984)
							(end -0.381 0.3683)
						)
						(arc
							(start -0.381 -0.3683)
							(mid -0.321484 -0.511984)
							(end -0.1778 -0.5715)
						)
						(arc
							(start 0.1778 -0.5715)
							(mid 0.321484 -0.511984)
							(end 0.381 -0.3683)
						)
						(arc
							(start 0.381 0.3683)
							(mid 0.321484 0.511984)
							(end 0.1778 0.5715)
						)
					)
					(width 0)
					(fill yes)
				)
			)
		)
		(pad "S" smd custom
			(at 0.98425 0.9525 180)
			(size 0.1905 0.1905)
			(layers "F.Cu" "F.Mask" "F.Paste")
			(net "GND")
			(options
				(clearance outline)
				(anchor circle)
			)
			(primitives
				(gr_poly
					(pts
						(arc
							(start -0.1778 0.5715)
							(mid -0.321484 0.511984)
							(end -0.381 0.3683)
						)
						(arc
							(start -0.381 -0.3683)
							(mid -0.321484 -0.511984)
							(end -0.1778 -0.5715)
						)
						(arc
							(start 0.1778 -0.5715)
							(mid 0.321484 -0.511984)
							(end 0.381 -0.3683)
						)
						(arc
							(start 0.381 0.3683)
							(mid 0.321484 0.511984)
							(end 0.1778 0.5715)
						)
					)
					(width 0)
					(fill yes)
				)
			)
		)
	)
	(footprint ""
		(layer "F.Cu")
		(at 426.085 -262.001 -90)
		(property "Reference" "R302"
			(at 0 0 270)
			(layer "F.SilkS")
			(hide yes)
			(effects
				(font
					(size 1.27 1.27)
				)
			)
		)
		(property "Value" "2R6F-GP"
			(at -0.0508 -4.8514 270)
			(unlocked yes)
			(layer "F.Fab")
			(hide yes)
			(effects
				(font
					(size 1.016 1.016)
					(thickness 0.1524)
				)
			)
		)
		(property "Device Type" "R1206H26"
			(at 0 -6.3754 270)
			(unlocked yes)
			(layer "F.Fab")
			(hide yes)
			(effects
				(font
					(size 1.016 1.016)
					(thickness 0.1524)
				)
			)
		)
		(duplicate_pad_numbers_are_jumpers no)
		(fp_line
			(start -1.016 2.2352)
			(end -1.016 -2.2352)
			(stroke
				(width 0.1524)
				(type default)
			)
			(layer "F.SilkS")
		)
		(fp_line
			(start 1.016 2.2352)
			(end -1.016 2.2352)
			(stroke
				(width 0.1524)
				(type default)
			)
			(layer "F.SilkS")
		)
		(fp_line
			(start -1.016 -2.2352)
			(end 1.016 -2.2352)
			(stroke
				(width 0.1524)
				(type default)
			)
			(layer "F.SilkS")
		)
		(fp_line
			(start 1.016 -2.2352)
			(end 1.016 2.2352)
			(stroke
				(width 0.1524)
				(type default)
			)
			(layer "F.SilkS")
		)
		(fp_rect
			(start -1.0922 2.3114)
			(end 1.0922 -2.3114)
			(stroke
				(width 0)
				(type default)
			)
			(fill no)
			(layer "F.CrtYd")
		)
		(fp_poly
			(pts
				(xy -1.0922 -2.3114) (xy 1.0922 -2.3114) (xy 1.0922 2.3114) (xy -1.0922 2.3114)
			)
			(stroke
				(width 0)
				(type default)
			)
			(fill no)
			(layer "F.Fab")
		)
		(pad "1" smd rect
			(at 0 -1.397 270)
			(size 1.651 1.27)
			(layers "F.Cu" "F.Mask" "F.Paste")
			(net "P5V_HDD9")
		)
		(pad "2" smd rect
			(at 0 1.397 270)
			(size 1.651 1.27)
			(layers "F.Cu" "F.Mask" "F.Paste")
			(net "5V_PRE_9")
		)
	)
	(footprint ""
		(layer "F.Cu")
		(at 242.193064 -368.115088 -90)
		(property "Reference" "Q200"
			(at 0 0 270)
			(layer "F.SilkS")
			(hide yes)
			(effects
				(font
					(size 1.27 1.27)
				)
			)
		)
		(property "Value" "MMBT3904-3-GP"
			(at 0.10287 -10.29843 270)
			(unlocked yes)
			(layer "F.Fab")
			(hide yes)
			(effects
				(font
					(size 1.016 1.016)
					(thickness 0.1524)
				)
			)
		)
		(property "Device Type" "SOT23CBE2D4H44"
			(at 0.10287 -12.20343 270)
			(unlocked yes)
			(layer "F.Fab")
			(hide yes)
			(effects
				(font
					(size 1.016 1.016)
					(thickness 0.1524)
				)
			)
		)
		(duplicate_pad_numbers_are_jumpers no)
		(fp_line
			(start -1.651 1.778)
			(end 1.651 1.778)
			(stroke
				(width 0.1524)
				(type default)
			)
			(layer "F.SilkS")
		)
		(fp_line
			(start 1.651 1.778)
			(end 1.651 -1.778)
			(stroke
				(width 0.1524)
				(type default)
			)
			(layer "F.SilkS")
		)
		(fp_line
			(start -1.651 -1.778)
			(end -1.651 1.778)
			(stroke
				(width 0.1524)
				(type default)
			)
			(layer "F.SilkS")
		)
		(fp_line
			(start 1.651 -1.778)
			(end -1.651 -1.778)
			(stroke
				(width 0.1524)
				(type default)
			)
			(layer "F.SilkS")
		)
		(fp_poly
			(pts
				(xy -1.778 1.8796) (xy -1.778 -1.8796) (xy 1.778 -1.8796) (xy 1.778 1.8796)
			)
			(stroke
				(width 0)
				(type default)
			)
			(fill no)
			(layer "F.CrtYd")
		)
		(fp_poly
			(pts
				(xy -1.778 1.8796) (xy -1.778 -1.8796) (xy 1.778 -1.8796) (xy 1.778 1.8796)
			)
			(stroke
				(width 0)
				(type default)
			)
			(fill no)
			(layer "F.Fab")
		)
		(pad "B" smd custom
			(at -0.98425 0.9525 270)
			(size 0.1905 0.1905)
			(layers "F.Cu" "F.Mask" "F.Paste")
			(net "MB3_TEMP_B")
			(options
				(clearance outline)
				(anchor circle)
			)
			(primitives
				(gr_poly
					(pts
						(arc
							(start -0.1778 0.5715)
							(mid -0.321484 0.511984)
							(end -0.381 0.3683)
						)
						(arc
							(start -0.381 -0.3683)
							(mid -0.321484 -0.511984)
							(end -0.1778 -0.5715)
						)
						(arc
							(start 0.1778 -0.5715)
							(mid 0.321484 -0.511984)
							(end 0.381 -0.3683)
						)
						(arc
							(start 0.381 0.3683)
							(mid 0.321484 0.511984)
							(end 0.1778 0.5715)
						)
					)
					(width 0)
					(fill yes)
				)
			)
		)
		(pad "C" smd custom
			(at 0 -0.9525 270)
			(size 0.1905 0.1905)
			(layers "F.Cu" "F.Mask" "F.Paste")
			(net "MB3_TEMP_B")
			(options
				(clearance outline)
				(anchor circle)
			)
			(primitives
				(gr_poly
					(pts
						(arc
							(start -0.1778 0.5715)
							(mid -0.321484 0.511984)
							(end -0.381 0.3683)
						)
						(arc
							(start -0.381 -0.3683)
							(mid -0.321484 -0.511984)
							(end -0.1778 -0.5715)
						)
						(arc
							(start 0.1778 -0.5715)
							(mid 0.321484 -0.511984)
							(end 0.381 -0.3683)
						)
						(arc
							(start 0.381 0.3683)
							(mid 0.321484 0.511984)
							(end 0.1778 0.5715)
						)
					)
					(width 0)
					(fill yes)
				)
			)
		)
		(pad "E" smd custom
			(at 0.98425 0.9525 270)
			(size 0.1905 0.1905)
			(layers "F.Cu" "F.Mask" "F.Paste")
			(net "MB3_TEMP_E")
			(options
				(clearance outline)
				(anchor circle)
			)
			(primitives
				(gr_poly
					(pts
						(arc
							(start -0.1778 0.5715)
							(mid -0.321484 0.511984)
							(end -0.381 0.3683)
						)
						(arc
							(start -0.381 -0.3683)
							(mid -0.321484 -0.511984)
							(end -0.1778 -0.5715)
						)
						(arc
							(start 0.1778 -0.5715)
							(mid 0.321484 -0.511984)
							(end 0.381 -0.3683)
						)
						(arc
							(start 0.381 0.3683)
							(mid 0.321484 0.511984)
							(end 0.1778 0.5715)
						)
					)
					(width 0)
					(fill yes)
				)
			)
		)
	)
	(footprint ""
		(layer "F.Cu")
		(at 407.1366 -32.766 -90)
		(property "Reference" "R820"
			(at 0 0 270)
			(layer "F.SilkS")
			(hide yes)
			(effects
				(font
					(size 1.27 1.27)
				)
			)
		)
		(property "Value" "300KR2F-GP"
			(at 0.064008 -3.993896 270)
			(unlocked yes)
			(layer "F.Fab")
			(hide yes)
			(effects
				(font
					(size 1.016 1.016)
					(thickness 0.1524)
				)
			)
		)
		(property "Device Type" "R402H16"
			(at 0.064008 -5.517896 270)
			(unlocked yes)
			(layer "F.Fab")
			(hide yes)
			(effects
				(font
					(size 1.016 1.016)
					(thickness 0.1524)
				)
			)
		)
		(duplicate_pad_numbers_are_jumpers no)
		(fp_line
			(start -0.508 -0.9398)
			(end -0.508 0.9398)
			(stroke
				(width 0.1524)
				(type default)
			)
			(layer "F.SilkS")
		)
		(fp_line
			(start 0.508 -0.9398)
			(end -0.508 -0.9398)
			(stroke
				(width 0.1524)
				(type default)
			)
			(layer "F.SilkS")
		)
		(fp_rect
			(start -0.508 0.9398)
			(end 0.508 -0.9398)
			(stroke
				(width 0)
				(type default)
			)
			(fill no)
			(layer "F.CrtYd")
		)
		(fp_rect
			(start -0.508 0.9398)
			(end 0.508 -0.9398)
			(stroke
				(width 0)
				(type default)
			)
			(fill no)
			(layer "F.Fab")
		)
		(pad "1" smd custom
			(at 0 -0.4445 270)
			(size 0.1397 0.1397)
			(layers "F.Cu" "F.Mask" "F.Paste")
			(net "SW_HDD_N32")
			(options
				(clearance outline)
				(anchor circle)
			)
			(primitives
				(gr_poly
					(pts
						(arc
							(start -0.1778 -0.2794)
							(mid -0.249642 -0.249642)
							(end -0.2794 -0.1778)
						)
						(arc
							(start -0.2794 0.1778)
							(mid -0.249642 0.249642)
							(end -0.1778 0.2794)
						)
						(arc
							(start 0.1778 0.2794)
							(mid 0.249642 0.249642)
							(end 0.2794 0.1778)
						)
						(arc
							(start 0.2794 -0.1778)
							(mid 0.249642 -0.249642)
							(end 0.1778 -0.2794)
						)
					)
					(width 0)
					(fill yes)
				)
			)
		)
		(pad "2" smd custom
			(at 0 0.4445 270)
			(size 0.1397 0.1397)
			(layers "F.Cu" "F.Mask" "F.Paste")
			(net "P12V_B")
			(options
				(clearance outline)
				(anchor circle)
			)
			(primitives
				(gr_poly
					(pts
						(arc
							(start -0.1778 -0.2794)
							(mid -0.249642 -0.249642)
							(end -0.2794 -0.1778)
						)
						(arc
							(start -0.2794 0.1778)
							(mid -0.249642 0.249642)
							(end -0.1778 0.2794)
						)
						(arc
							(start 0.1778 0.2794)
							(mid 0.249642 0.249642)
							(end 0.2794 0.1778)
						)
						(arc
							(start 0.2794 -0.1778)
							(mid 0.249642 -0.249642)
							(end 0.1778 -0.2794)
						)
					)
					(width 0)
					(fill yes)
				)
			)
		)
	)
	(footprint ""
		(layer "F.Cu")
		(at 457.005944 -376.09526 180)
		(property "Reference" "Q218"
			(at 0 0 180)
			(layer "F.SilkS")
			(hide yes)
			(effects
				(font
					(size 1.27 1.27)
				)
			)
		)
		(property "Value" "2N7002KDW-GP"
			(at -2.3622 -8.2042 180)
			(unlocked yes)
			(layer "F.Fab")
			(hide yes)
			(effects
				(font
					(size 1.016 1.016)
					(thickness 0.1524)
				)
			)
		)
		(property "Device Type" "SOT-363H44"
			(at -2.3622 -10.1092 180)
			(unlocked yes)
			(layer "F.Fab")
			(hide yes)
			(effects
				(font
					(size 1.016 1.016)
					(thickness 0.1524)
				)
			)
		)
		(duplicate_pad_numbers_are_jumpers no)
		(fp_line
			(start 1.4478 1.7018)
			(end 1.4478 -1.7018)
			(stroke
				(width 0.1524)
				(type default)
			)
			(layer "F.SilkS")
		)
		(fp_line
			(start 1.4478 -1.7018)
			(end -1.4478 -1.7018)
			(stroke
				(width 0.1524)
				(type default)
			)
			(layer "F.SilkS")
		)
		(fp_line
			(start -1.27 1.524)
			(end -1.27 0.6604)
			(stroke
				(width 0.4826)
				(type default)
			)
			(layer "F.SilkS")
		)
		(fp_line
			(start -1.4478 1.7018)
			(end 1.4478 1.7018)
			(stroke
				(width 0.1524)
				(type default)
			)
			(layer "F.SilkS")
		)
		(fp_line
			(start -1.4478 -1.7018)
			(end -1.4478 1.7018)
			(stroke
				(width 0.1524)
				(type default)
			)
			(layer "F.SilkS")
		)
		(fp_poly
			(pts
				(xy -1.524 -1.778) (xy 1.524 -1.778) (xy 1.524 1.778) (xy -1.524 1.778)
			)
			(stroke
				(width 0)
				(type default)
			)
			(fill no)
			(layer "F.CrtYd")
		)
		(fp_poly
			(pts
				(xy -1.524 -1.778) (xy 1.524 -1.778) (xy 1.524 1.778) (xy -1.524 1.778)
			)
			(stroke
				(width 0)
				(type default)
			)
			(fill no)
			(layer "F.Fab")
		)
		(pad "1" smd rect
			(at -0.65024 0.9398 180)
			(size 0.4064 1.016)
			(layers "F.Cu" "F.Mask" "F.Paste")
			(net "GND")
		)
		(pad "2" smd rect
			(at 0 0.9398 180)
			(size 0.4064 1.016)
			(layers "F.Cu" "F.Mask" "F.Paste")
			(net "FAN_LED3_D")
		)
		(pad "3" smd rect
			(at 0.65024 0.9398 180)
			(size 0.4064 1.016)
			(layers "F.Cu" "F.Mask" "F.Paste")
			(net "FAN_LED3_D")
		)
		(pad "4" smd rect
			(at 0.65024 -0.9398 180)
			(size 0.4064 1.016)
			(layers "F.Cu" "F.Mask" "F.Paste")
			(net "GND")
		)
		(pad "5" smd rect
			(at 0 -0.9398 180)
			(size 0.4064 1.016)
			(layers "F.Cu" "F.Mask" "F.Paste")
			(net "FAN_LED3")
		)
		(pad "6" smd rect
			(at -0.65024 -0.9398 180)
			(size 0.4064 1.016)
			(layers "F.Cu" "F.Mask" "F.Paste")
			(net "FAN_LED3_D2")
		)
	)
	(footprint ""
		(layer "F.Cu")
		(at 417.966652 -17.4371)
		(property "Reference" "VIA68"
			(at 0 0 0)
			(layer "F.SilkS")
			(hide yes)
			(effects
				(font
					(size 1.27 1.27)
				)
			)
		)
		(property "Value" "100OHM-8L-2D36MM-L16-GP"
			(at -3.4036 -0.4572 0)
			(unlocked yes)
			(layer "F.Fab")
			(hide yes)
			(effects
				(font
					(size 1.016 1.016)
					(thickness 0.1524)
				)
			)
		)
		(property "Device Type" "VIA-PCIE-4P-427097"
			(at -3.4036 -1.9812 0)
			(unlocked yes)
			(layer "F.Fab")
			(hide yes)
			(effects
				(font
					(size 1.016 1.016)
					(thickness 0.1524)
				)
			)
		)
		(duplicate_pad_numbers_are_jumpers no)
		(fp_rect
			(start -2.1336 0.4826)
			(end 2.1336 -0.4826)
			(stroke
				(width 0)
				(type default)
			)
			(fill no)
			(layer "F.CrtYd")
		)
		(fp_rect
			(start -2.1336 0.4826)
			(end 2.1336 -0.4826)
			(stroke
				(width 0)
				(type default)
			)
			(fill no)
			(layer "F.Fab")
		)
		(pad "1" thru_hole circle
			(at -1.651 0)
			(size 0.508 0.508)
			(drill 0.254)
			(layers "*.Cu" "*.Mask")
			(remove_unused_layers no)
			(net "GND")
			(clearance 0.2286)
			(thermal_gap 0.2286)
		)
		(pad "2" thru_hole circle
			(at -0.635 0)
			(size 0.508 0.508)
			(drill 0.254)
			(layers "*.Cu" "*.Mask")
			(remove_unused_layers no)
			(net "PHY_DRV_B_TO_SCC_B_33_DP")
			(clearance 0.2286)
			(thermal_gap 0.2286)
		)
		(pad "3" thru_hole circle
			(at 0.635 0)
			(size 0.508 0.508)
			(drill 0.254)
			(layers "*.Cu" "*.Mask")
			(remove_unused_layers no)
			(net "PHY_DRV_B_TO_SCC_B_33_DN")
			(clearance 0.2286)
			(thermal_gap 0.2286)
		)
		(pad "4" thru_hole circle
			(at 1.651 0)
			(size 0.508 0.508)
			(drill 0.254)
			(layers "*.Cu" "*.Mask")
			(remove_unused_layers no)
			(net "GND")
			(clearance 0.2286)
			(thermal_gap 0.2286)
		)
	)
	(footprint ""
		(layer "F.Cu")
		(at 201.89952 -353.760786 90)
		(property "Reference" "Q199"
			(at 0 0 90)
			(layer "F.SilkS")
			(hide yes)
			(effects
				(font
					(size 1.27 1.27)
				)
			)
		)
		(property "Value" "IRFH8201TRPBF-GP"
			(at -4.2164 -4.3688 90)
			(unlocked yes)
			(layer "F.Fab")
			(hide yes)
			(effects
				(font
					(size 1.016 1.016)
					(thickness 0.1524)
				)
			)
		)
		(property "Device Type" "PPAK-5PH42"
			(at -4.2164 -5.8928 90)
			(unlocked yes)
			(layer "F.Fab")
			(hide yes)
			(effects
				(font
					(size 1.016 1.016)
					(thickness 0.1524)
				)
			)
		)
		(duplicate_pad_numbers_are_jumpers no)
		(fp_line
			(start 2.8956 -2.794)
			(end 2.8956 4.826)
			(stroke
				(width 0.1524)
				(type default)
			)
			(layer "F.SilkS")
		)
		(fp_line
			(start -2.8956 -2.794)
			(end 2.8956 -2.794)
			(stroke
				(width 0.1524)
				(type default)
			)
			(layer "F.SilkS")
		)
		(fp_line
			(start 2.8956 4.826)
			(end -2.8956 4.826)
			(stroke
				(width 0.1524)
				(type default)
			)
			(layer "F.SilkS")
		)
		(fp_line
			(start -2.8956 4.826)
			(end -2.8956 -2.794)
			(stroke
				(width 0.1524)
				(type default)
			)
			(layer "F.SilkS")
		)
		(fp_line
			(start -1.9431 4.9276)
			(end -3.0353 4.9276)
			(stroke
				(width 0.3302)
				(type default)
			)
			(layer "F.SilkS")
		)
		(fp_line
			(start -3.0353 4.9276)
			(end -3.0353 3.9624)
			(stroke
				(width 0.3302)
				(type default)
			)
			(layer "F.SilkS")
		)
		(fp_poly
			(pts
				(xy -2.3622 5.334) (xy -1.4986 5.334) (xy -1.9304 4.9022)
			)
			(stroke
				(width 0)
				(type default)
			)
			(fill yes)
			(layer "F.SilkS")
		)
		(fp_poly
			(pts
				(xy 0.3556 -0.3556) (xy 2.6416 -0.3556) (xy 2.6416 -2.54) (xy 0.3556 -2.54)
			)
			(stroke
				(width 0)
				(type default)
			)
			(fill yes)
			(layer "F.Paste")
		)
		(fp_poly
			(pts
				(xy -2.6416 -0.3556) (xy -0.3556 -0.3556) (xy -0.3556 -2.54) (xy -2.6416 -2.54)
			)
			(stroke
				(width 0)
				(type default)
			)
			(fill yes)
			(layer "F.Paste")
		)
		(fp_poly
			(pts
				(xy 0.3556 2.54) (xy 2.6416 2.54) (xy 2.6416 0.3556) (xy 0.3556 0.3556)
			)
			(stroke
				(width 0)
				(type default)
			)
			(fill yes)
			(layer "F.Paste")
		)
		(fp_poly
			(pts
				(xy -2.6416 2.54) (xy -0.3556 2.54) (xy -0.3556 0.3556) (xy -2.6416 0.3556)
			)
			(stroke
				(width 0)
				(type default)
			)
			(fill yes)
			(layer "F.Paste")
		)
		(fp_rect
			(start -2.5781 3.9878)
			(end 2.5781 -2.1082)
			(stroke
				(width 0)
				(type default)
			)
			(fill no)
			(layer "F.CrtYd")
		)
		(fp_poly
			(pts
				(xy -3.1496 5.08) (xy -3.1496 -3.048) (xy 3.1496 -3.048) (xy 3.1496 3.9751) (xy 2.5781 3.9751) (xy 2.5781 -2.1082)
				(xy -2.5781 -2.1082) (xy -2.5781 3.9878) (xy 3.1496 3.9878) (xy 3.1496 5.08)
			)
			(stroke
				(width 0)
				(type default)
			)
			(fill no)
			(layer "F.CrtYd")
		)
		(fp_rect
			(start -3.1496 5.08)
			(end 3.1496 -3.048)
			(stroke
				(width 0)
				(type default)
			)
			(fill no)
			(layer "F.Fab")
		)
		(pad "1" smd rect
			(at -1.905 3.81 90)
			(size 0.762 1.524)
			(layers "F.Cu" "F.Mask" "F.Paste")
			(net "P12V_IN")
		)
		(pad "2" smd rect
			(at -0.635 3.81 90)
			(size 0.762 1.524)
			(layers "F.Cu" "F.Mask" "F.Paste")
			(net "P12V_IN")
		)
		(pad "3" smd rect
			(at 0.635 3.81 90)
			(size 0.762 1.524)
			(layers "F.Cu" "F.Mask" "F.Paste")
			(net "P12V_IN")
		)
		(pad "4" smd rect
			(at 1.905 3.81 90)
			(size 0.762 1.524)
			(layers "F.Cu" "F.Mask" "F.Paste")
			(net "MB0_12V_CTRL_GATE6")
		)
		(pad "5" smd rect
			(at 0 0 90)
			(size 5.2832 5.08)
			(layers "F.Cu" "F.Mask" "F.Paste")
			(net "MB0_P12V_IN_R")
		)
		(pad "6" smd rect
			(at 0.635 -2.032 90)
			(size 0.0254 0.0254)
			(layers "F.Cu" "F.Mask" "F.Paste")
			(net "MB0_P12V_IN_R")
		)
		(pad "7" smd rect
			(at -0.635 -2.032 90)
			(size 0.0254 0.0254)
			(layers "F.Cu" "F.Mask" "F.Paste")
			(net "MB0_P12V_IN_R")
		)
		(pad "8" smd rect
			(at -1.905 -2.032 90)
			(size 0.0254 0.0254)
			(layers "F.Cu" "F.Mask" "F.Paste")
			(net "MB0_P12V_IN_R")
		)
	)
	(footprint ""
		(layer "F.Cu")
		(at 32.463486 -245.219474 90)
		(property "Reference" "C496"
			(at 0 0 90)
			(layer "F.SilkS")
			(hide yes)
			(effects
				(font
					(size 1.27 1.27)
				)
			)
		)
		(property "Value" "SCD01U16V1KX-GP"
			(at -2.8321 -1.7399 90)
			(unlocked yes)
			(layer "F.Fab")
			(hide yes)
			(effects
				(font
					(size 1.016 1.016)
					(thickness 0.1524)
				)
			)
		)
		(property "Device Type" "C0201H13"
			(at -2.8321 -3.2639 90)
			(unlocked yes)
			(layer "F.Fab")
			(hide yes)
			(effects
				(font
					(size 1.016 1.016)
					(thickness 0.1524)
				)
			)
		)
		(duplicate_pad_numbers_are_jumpers no)
		(fp_rect
			(start -0.2794 0.6477)
			(end 0.2794 -0.6477)
			(stroke
				(width 0)
				(type default)
			)
			(fill no)
			(layer "F.CrtYd")
		)
		(fp_rect
			(start -0.2794 0.6477)
			(end 0.2794 -0.6477)
			(stroke
				(width 0)
				(type default)
			)
			(fill no)
			(layer "F.Fab")
		)
		(pad "1" smd custom
			(at 0 -0.2794 90)
			(size 0.0762 0.0762)
			(layers "F.Cu" "F.Mask" "F.Paste")
			(net "SAS_HDD_RX_N0")
			(options
				(clearance outline)
				(anchor circle)
			)
			(primitives
				(gr_poly
					(pts
						(arc
							(start 0.1524 -0.127)
							(mid 0.137521 -0.162921)
							(end 0.1016 -0.1778)
						)
						(arc
							(start -0.1016 -0.1778)
							(mid -0.137521 -0.162921)
							(end -0.1524 -0.127)
						)
						(arc
							(start -0.1524 0.127)
							(mid -0.137521 0.162921)
							(end -0.1016 0.1778)
						)
						(arc
							(start 0.1016 0.1778)
							(mid 0.137521 0.162921)
							(end 0.1524 0.127)
						)
					)
					(width 0)
					(fill yes)
				)
			)
		)
		(pad "2" smd custom
			(at 0 0.2794 90)
			(size 0.0762 0.0762)
			(layers "F.Cu" "F.Mask" "F.Paste")
			(net "PHY_SCC_B_TO_DRV_B_0_DN")
			(options
				(clearance outline)
				(anchor circle)
			)
			(primitives
				(gr_poly
					(pts
						(arc
							(start 0.1524 -0.127)
							(mid 0.137521 -0.162921)
							(end 0.1016 -0.1778)
						)
						(arc
							(start -0.1016 -0.1778)
							(mid -0.137521 -0.162921)
							(end -0.1524 -0.127)
						)
						(arc
							(start -0.1524 0.127)
							(mid -0.137521 0.162921)
							(end -0.1016 0.1778)
						)
						(arc
							(start 0.1016 0.1778)
							(mid 0.137521 0.162921)
							(end 0.1524 0.127)
						)
					)
					(width 0)
					(fill yes)
				)
			)
		)
	)
	(footprint ""
		(layer "F.Cu")
		(at 254.127 -230.886 180)
		(property "Reference" "R502"
			(at 0 0 180)
			(layer "F.SilkS")
			(hide yes)
			(effects
				(font
					(size 1.27 1.27)
				)
			)
		)
		(property "Value" "10KR2F-2-GP"
			(at 0.064008 -3.993896 180)
			(unlocked yes)
			(layer "F.Fab")
			(hide yes)
			(effects
				(font
					(size 1.016 1.016)
					(thickness 0.1524)
				)
			)
		)
		(property "Device Type" "R402H16"
			(at 0.064008 -5.517896 180)
			(unlocked yes)
			(layer "F.Fab")
			(hide yes)
			(effects
				(font
					(size 1.016 1.016)
					(thickness 0.1524)
				)
			)
		)
		(duplicate_pad_numbers_are_jumpers no)
		(fp_line
			(start 0.508 -0.9398)
			(end -0.508 -0.9398)
			(stroke
				(width 0.1524)
				(type default)
			)
			(layer "F.SilkS")
		)
		(fp_line
			(start -0.508 -0.9398)
			(end -0.508 0.9398)
			(stroke
				(width 0.1524)
				(type default)
			)
			(layer "F.SilkS")
		)
		(fp_rect
			(start -0.508 0.9398)
			(end 0.508 -0.9398)
			(stroke
				(width 0)
				(type default)
			)
			(fill no)
			(layer "F.CrtYd")
		)
		(fp_rect
			(start -0.508 0.9398)
			(end 0.508 -0.9398)
			(stroke
				(width 0)
				(type default)
			)
			(fill no)
			(layer "F.Fab")
		)
		(pad "1" smd custom
			(at 0 -0.4445 180)
			(size 0.1397 0.1397)
			(layers "F.Cu" "F.Mask" "F.Paste")
			(net "P5V_B_1")
			(options
				(clearance outline)
				(anchor circle)
			)
			(primitives
				(gr_poly
					(pts
						(arc
							(start -0.1778 -0.2794)
							(mid -0.249642 -0.249642)
							(end -0.2794 -0.1778)
						)
						(arc
							(start -0.2794 0.1778)
							(mid -0.249642 0.249642)
							(end -0.1778 0.2794)
						)
						(arc
							(start 0.1778 0.2794)
							(mid 0.249642 0.249642)
							(end 0.2794 0.1778)
						)
						(arc
							(start 0.2794 -0.1778)
							(mid 0.249642 -0.249642)
							(end 0.1778 -0.2794)
						)
					)
					(width 0)
					(fill yes)
				)
			)
		)
		(pad "2" smd custom
			(at 0 0.4445 180)
			(size 0.1397 0.1397)
			(layers "F.Cu" "F.Mask" "F.Paste")
			(net "SCC_FULL_PWR_EN_5V_R")
			(options
				(clearance outline)
				(anchor circle)
			)
			(primitives
				(gr_poly
					(pts
						(arc
							(start -0.1778 -0.2794)
							(mid -0.249642 -0.249642)
							(end -0.2794 -0.1778)
						)
						(arc
							(start -0.2794 0.1778)
							(mid -0.249642 0.249642)
							(end -0.1778 0.2794)
						)
						(arc
							(start 0.1778 0.2794)
							(mid 0.249642 0.249642)
							(end 0.2794 0.1778)
						)
						(arc
							(start 0.2794 -0.1778)
							(mid 0.249642 -0.249642)
							(end 0.1778 -0.2794)
						)
					)
					(width 0)
					(fill yes)
				)
			)
		)
	)
	(footprint ""
		(layer "F.Cu")
		(at 27.448002 -231.62895 -90)
		(property "Reference" "R1099"
			(at 0 0 270)
			(layer "F.SilkS")
			(hide yes)
			(effects
				(font
					(size 1.27 1.27)
				)
			)
		)
		(property "Value" "0R2J-2-GP"
			(at 0.064008 -3.993896 270)
			(unlocked yes)
			(layer "F.Fab")
			(hide yes)
			(effects
				(font
					(size 1.016 1.016)
					(thickness 0.1524)
				)
			)
		)
		(property "Device Type" "R402H16"
			(at 0.064008 -5.517896 270)
			(unlocked yes)
			(layer "F.Fab")
			(hide yes)
			(effects
				(font
					(size 1.016 1.016)
					(thickness 0.1524)
				)
			)
		)
		(duplicate_pad_numbers_are_jumpers no)
		(fp_line
			(start -0.508 -0.9398)
			(end -0.508 0.9398)
			(stroke
				(width 0.1524)
				(type default)
			)
			(layer "F.SilkS")
		)
		(fp_line
			(start 0.508 -0.9398)
			(end -0.508 -0.9398)
			(stroke
				(width 0.1524)
				(type default)
			)
			(layer "F.SilkS")
		)
		(fp_rect
			(start -0.508 0.9398)
			(end 0.508 -0.9398)
			(stroke
				(width 0)
				(type default)
			)
			(fill no)
			(layer "F.CrtYd")
		)
		(fp_rect
			(start -0.508 0.9398)
			(end 0.508 -0.9398)
			(stroke
				(width 0)
				(type default)
			)
			(fill no)
			(layer "F.Fab")
		)
		(pad "1" smd custom
			(at 0 -0.4445 270)
			(size 0.1397 0.1397)
			(layers "F.Cu" "F.Mask" "F.Paste")
			(net "P12V_B_PGOOD")
			(options
				(clearance outline)
				(anchor circle)
			)
			(primitives
				(gr_poly
					(pts
						(arc
							(start -0.1778 -0.2794)
							(mid -0.249642 -0.249642)
							(end -0.2794 -0.1778)
						)
						(arc
							(start -0.2794 0.1778)
							(mid -0.249642 0.249642)
							(end -0.1778 0.2794)
						)
						(arc
							(start 0.1778 0.2794)
							(mid 0.249642 0.249642)
							(end 0.2794 0.1778)
						)
						(arc
							(start 0.2794 -0.1778)
							(mid 0.249642 -0.249642)
							(end 0.1778 -0.2794)
						)
					)
					(width 0)
					(fill yes)
				)
			)
		)
		(pad "2" smd custom
			(at 0 0.4445 270)
			(size 0.1397 0.1397)
			(layers "F.Cu" "F.Mask" "F.Paste")
			(net "P5V_B_1_EN_R")
			(options
				(clearance outline)
				(anchor circle)
			)
			(primitives
				(gr_poly
					(pts
						(arc
							(start -0.1778 -0.2794)
							(mid -0.249642 -0.249642)
							(end -0.2794 -0.1778)
						)
						(arc
							(start -0.2794 0.1778)
							(mid -0.249642 0.249642)
							(end -0.1778 0.2794)
						)
						(arc
							(start 0.1778 0.2794)
							(mid 0.249642 0.249642)
							(end 0.2794 0.1778)
						)
						(arc
							(start 0.2794 -0.1778)
							(mid 0.249642 -0.249642)
							(end 0.1778 -0.2794)
						)
					)
					(width 0)
					(fill yes)
				)
			)
		)
	)
	(footprint ""
		(layer "F.Cu")
		(at 410.464 -99.187)
		(property "Reference" "R450"
			(at 0 0 0)
			(layer "F.SilkS")
			(hide yes)
			(effects
				(font
					(size 1.27 1.27)
				)
			)
		)
		(property "Value" "91R3F-1-GP"
			(at -0.0254 -2.5146 0)
			(unlocked yes)
			(layer "F.Fab")
			(hide yes)
			(effects
				(font
					(size 1.016 1.016)
					(thickness 0.1524)
				)
			)
		)
		(property "Device Type" "R603H22"
			(at -0.0254 -4.0386 0)
			(unlocked yes)
			(layer "F.Fab")
			(hide yes)
			(effects
				(font
					(size 1.016 1.016)
					(thickness 0.1524)
				)
			)
		)
		(duplicate_pad_numbers_are_jumpers no)
		(fp_line
			(start -0.4826 0)
			(end -0.2032 0)
			(stroke
				(width 0.2032)
				(type default)
			)
			(layer "F.SilkS")
		)
		(fp_line
			(start 0.2032 0)
			(end 0.4826 0)
			(stroke
				(width 0.2032)
				(type default)
			)
			(layer "F.SilkS")
		)
		(fp_rect
			(start -0.5842 1.3335)
			(end 0.5842 -1.3335)
			(stroke
				(width 0)
				(type default)
			)
			(fill no)
			(layer "F.CrtYd")
		)
		(fp_rect
			(start -0.5842 1.3335)
			(end 0.5842 -1.3335)
			(stroke
				(width 0)
				(type default)
			)
			(fill no)
			(layer "F.Fab")
		)
		(pad "1" smd custom
			(at 0 -0.762)
			(size 0.2159 0.2159)
			(layers "F.Cu" "F.Mask" "F.Paste")
			(net "P5V_B_4")
			(options
				(clearance outline)
				(anchor circle)
			)
			(primitives
				(gr_poly
					(pts
						(arc
							(start -0.3302 -0.4318)
							(mid -0.402042 -0.402042)
							(end -0.4318 -0.3302)
						)
						(arc
							(start -0.4318 0.3302)
							(mid -0.402042 0.402042)
							(end -0.3302 0.4318)
						)
						(arc
							(start 0.3302 0.4318)
							(mid 0.402042 0.402042)
							(end 0.4318 0.3302)
						)
						(arc
							(start 0.4318 -0.3302)
							(mid 0.402042 -0.402042)
							(end 0.3302 -0.4318)
						)
					)
					(width 0)
					(fill yes)
				)
			)
		)
		(pad "2" smd custom
			(at 0 0.762)
			(size 0.2159 0.2159)
			(layers "F.Cu" "F.Mask" "F.Paste")
			(net "DRV_ACT_21")
			(options
				(clearance outline)
				(anchor circle)
			)
			(primitives
				(gr_poly
					(pts
						(arc
							(start -0.3302 -0.4318)
							(mid -0.402042 -0.402042)
							(end -0.4318 -0.3302)
						)
						(arc
							(start -0.4318 0.3302)
							(mid -0.402042 0.402042)
							(end -0.3302 0.4318)
						)
						(arc
							(start 0.3302 0.4318)
							(mid 0.402042 0.402042)
							(end 0.4318 0.3302)
						)
						(arc
							(start 0.4318 -0.3302)
							(mid 0.402042 -0.402042)
							(end 0.3302 -0.4318)
						)
					)
					(width 0)
					(fill yes)
				)
			)
		)
	)
	(footprint ""
		(layer "F.Cu")
		(at 118.364 -33.274)
		(property "Reference" "R690"
			(at 0 0 0)
			(layer "F.SilkS")
			(hide yes)
			(effects
				(font
					(size 1.27 1.27)
				)
			)
		)
		(property "Value" "2R6F-GP"
			(at -0.0508 -4.8514 0)
			(unlocked yes)
			(layer "F.Fab")
			(hide yes)
			(effects
				(font
					(size 1.016 1.016)
					(thickness 0.1524)
				)
			)
		)
		(property "Device Type" "R1206H26"
			(at 0 -6.3754 0)
			(unlocked yes)
			(layer "F.Fab")
			(hide yes)
			(effects
				(font
					(size 1.016 1.016)
					(thickness 0.1524)
				)
			)
		)
		(duplicate_pad_numbers_are_jumpers no)
		(fp_line
			(start -1.016 -2.2352)
			(end 1.016 -2.2352)
			(stroke
				(width 0.1524)
				(type default)
			)
			(layer "F.SilkS")
		)
		(fp_line
			(start -1.016 2.2352)
			(end -1.016 -2.2352)
			(stroke
				(width 0.1524)
				(type default)
			)
			(layer "F.SilkS")
		)
		(fp_line
			(start 1.016 -2.2352)
			(end 1.016 2.2352)
			(stroke
				(width 0.1524)
				(type default)
			)
			(layer "F.SilkS")
		)
		(fp_line
			(start 1.016 2.2352)
			(end -1.016 2.2352)
			(stroke
				(width 0.1524)
				(type default)
			)
			(layer "F.SilkS")
		)
		(fp_rect
			(start -1.0922 2.3114)
			(end 1.0922 -2.3114)
			(stroke
				(width 0)
				(type default)
			)
			(fill no)
			(layer "F.CrtYd")
		)
		(fp_poly
			(pts
				(xy -1.0922 -2.3114) (xy 1.0922 -2.3114) (xy 1.0922 2.3114) (xy -1.0922 2.3114)
			)
			(stroke
				(width 0)
				(type default)
			)
			(fill no)
			(layer "F.Fab")
		)
		(pad "1" smd rect
			(at 0 -1.397)
			(size 1.651 1.27)
			(layers "F.Cu" "F.Mask" "F.Paste")
			(net "P5V_HDD27")
		)
		(pad "2" smd rect
			(at 0 1.397)
			(size 1.651 1.27)
			(layers "F.Cu" "F.Mask" "F.Paste")
			(net "5V_PRE_27")
		)
	)
	(footprint ""
		(layer "F.Cu")
		(at 228.1682 -302.6918 90)
		(property "Reference" "C649"
			(at 0 0 90)
			(layer "F.SilkS")
			(hide yes)
			(effects
				(font
					(size 1.27 1.27)
				)
			)
		)
		(property "Value" "SCD1U16V2KX-3GP"
			(at 1.1811 -2.7051 90)
			(unlocked yes)
			(layer "F.Fab")
			(hide yes)
			(effects
				(font
					(size 1.016 1.016)
					(thickness 0.1524)
				)
			)
		)
		(property "Device Type" "C402H22"
			(at 1.1811 -4.2291 90)
			(unlocked yes)
			(layer "F.Fab")
			(hide yes)
			(effects
				(font
					(size 1.016 1.016)
					(thickness 0.1524)
				)
			)
		)
		(duplicate_pad_numbers_are_jumpers no)
		(fp_rect
			(start -0.4318 0.9525)
			(end 0.4318 -0.9525)
			(stroke
				(width 0)
				(type default)
			)
			(fill no)
			(layer "F.CrtYd")
		)
		(fp_rect
			(start -0.4318 0.9525)
			(end 0.4318 -0.9525)
			(stroke
				(width 0)
				(type default)
			)
			(fill no)
			(layer "F.Fab")
		)
		(pad "1" smd custom
			(at 0 -0.4445 90)
			(size 0.1524 0.1524)
			(layers "F.Cu" "F.Mask" "F.Paste")
			(net "P3V3_IN")
			(options
				(clearance outline)
				(anchor circle)
			)
			(primitives
				(gr_poly
					(pts
						(arc
							(start 0.3048 -0.2032)
							(mid 0.275042 -0.275042)
							(end 0.2032 -0.3048)
						)
						(arc
							(start -0.2032 -0.3048)
							(mid -0.275042 -0.275042)
							(end -0.3048 -0.2032)
						)
						(arc
							(start -0.3048 0.2032)
							(mid -0.275042 0.275042)
							(end -0.2032 0.3048)
						)
						(arc
							(start 0.2032 0.3048)
							(mid 0.275042 0.275042)
							(end 0.3048 0.2032)
						)
					)
					(width 0)
					(fill yes)
				)
			)
		)
		(pad "2" smd custom
			(at 0 0.4445 90)
			(size 0.1524 0.1524)
			(layers "F.Cu" "F.Mask" "F.Paste")
			(net "GND")
			(options
				(clearance outline)
				(anchor circle)
			)
			(primitives
				(gr_poly
					(pts
						(arc
							(start 0.3048 -0.2032)
							(mid 0.275042 -0.275042)
							(end 0.2032 -0.3048)
						)
						(arc
							(start -0.2032 -0.3048)
							(mid -0.275042 -0.275042)
							(end -0.3048 -0.2032)
						)
						(arc
							(start -0.3048 0.2032)
							(mid -0.275042 0.275042)
							(end -0.2032 0.3048)
						)
						(arc
							(start 0.2032 0.3048)
							(mid 0.275042 0.275042)
							(end 0.3048 0.2032)
						)
					)
					(width 0)
					(fill yes)
				)
			)
		)
	)
	(footprint ""
		(layer "F.Cu")
		(at 384.9116 -31.6484)
		(property "Reference" "C453"
			(at 0 0 0)
			(layer "F.SilkS")
			(hide yes)
			(effects
				(font
					(size 1.27 1.27)
				)
			)
		)
		(property "Value" "SCD01U50V2KX-1GP"
			(at 1.1811 -2.7051 0)
			(unlocked yes)
			(layer "F.Fab")
			(hide yes)
			(effects
				(font
					(size 1.016 1.016)
					(thickness 0.1524)
				)
			)
		)
		(property "Device Type" "C402H22"
			(at 1.1811 -4.2291 0)
			(unlocked yes)
			(layer "F.Fab")
			(hide yes)
			(effects
				(font
					(size 1.016 1.016)
					(thickness 0.1524)
				)
			)
		)
		(duplicate_pad_numbers_are_jumpers no)
		(fp_rect
			(start -0.4318 0.9525)
			(end 0.4318 -0.9525)
			(stroke
				(width 0)
				(type default)
			)
			(fill no)
			(layer "F.CrtYd")
		)
		(fp_rect
			(start -0.4318 0.9525)
			(end 0.4318 -0.9525)
			(stroke
				(width 0)
				(type default)
			)
			(fill no)
			(layer "F.Fab")
		)
		(pad "1" smd custom
			(at 0 -0.4445)
			(size 0.1524 0.1524)
			(layers "F.Cu" "F.Mask" "F.Paste")
			(net "HDD_PRSNT_32")
			(options
				(clearance outline)
				(anchor circle)
			)
			(primitives
				(gr_poly
					(pts
						(arc
							(start 0.3048 -0.2032)
							(mid 0.275042 -0.275042)
							(end 0.2032 -0.3048)
						)
						(arc
							(start -0.2032 -0.3048)
							(mid -0.275042 -0.275042)
							(end -0.3048 -0.2032)
						)
						(arc
							(start -0.3048 0.2032)
							(mid -0.275042 0.275042)
							(end -0.2032 0.3048)
						)
						(arc
							(start 0.2032 0.3048)
							(mid 0.275042 0.275042)
							(end 0.3048 0.2032)
						)
					)
					(width 0)
					(fill yes)
				)
			)
		)
		(pad "2" smd custom
			(at 0 0.4445)
			(size 0.1524 0.1524)
			(layers "F.Cu" "F.Mask" "F.Paste")
			(net "GND")
			(options
				(clearance outline)
				(anchor circle)
			)
			(primitives
				(gr_poly
					(pts
						(arc
							(start 0.3048 -0.2032)
							(mid 0.275042 -0.275042)
							(end 0.2032 -0.3048)
						)
						(arc
							(start -0.2032 -0.3048)
							(mid -0.275042 -0.275042)
							(end -0.3048 -0.2032)
						)
						(arc
							(start -0.3048 0.2032)
							(mid -0.275042 0.275042)
							(end -0.2032 0.3048)
						)
						(arc
							(start 0.2032 0.3048)
							(mid 0.275042 0.275042)
							(end 0.3048 0.2032)
						)
					)
					(width 0)
					(fill yes)
				)
			)
		)
	)
	(footprint ""
		(layer "F.Cu")
		(at 304.519076 -340.812882 180)
		(property "Reference" "R99"
			(at 0 0 180)
			(layer "F.SilkS")
			(hide yes)
			(effects
				(font
					(size 1.27 1.27)
				)
			)
		)
		(property "Value" "4K7R2F-GP"
			(at 0.064008 -3.993896 180)
			(unlocked yes)
			(layer "F.Fab")
			(hide yes)
			(effects
				(font
					(size 1.016 1.016)
					(thickness 0.1524)
				)
			)
		)
		(property "Device Type" "R402H16"
			(at 0.064008 -5.517896 180)
			(unlocked yes)
			(layer "F.Fab")
			(hide yes)
			(effects
				(font
					(size 1.016 1.016)
					(thickness 0.1524)
				)
			)
		)
		(duplicate_pad_numbers_are_jumpers no)
		(fp_line
			(start 0.508 -0.9398)
			(end -0.508 -0.9398)
			(stroke
				(width 0.1524)
				(type default)
			)
			(layer "F.SilkS")
		)
		(fp_line
			(start -0.508 -0.9398)
			(end -0.508 0.9398)
			(stroke
				(width 0.1524)
				(type default)
			)
			(layer "F.SilkS")
		)
		(fp_rect
			(start -0.508 0.9398)
			(end 0.508 -0.9398)
			(stroke
				(width 0)
				(type default)
			)
			(fill no)
			(layer "F.CrtYd")
		)
		(fp_rect
			(start -0.508 0.9398)
			(end 0.508 -0.9398)
			(stroke
				(width 0)
				(type default)
			)
			(fill no)
			(layer "F.Fab")
		)
		(pad "1" smd custom
			(at 0 -0.4445 180)
			(size 0.1397 0.1397)
			(layers "F.Cu" "F.Mask" "F.Paste")
			(net "THERMHOT#_C")
			(options
				(clearance outline)
				(anchor circle)
			)
			(primitives
				(gr_poly
					(pts
						(arc
							(start -0.1778 -0.2794)
							(mid -0.249642 -0.249642)
							(end -0.2794 -0.1778)
						)
						(arc
							(start -0.2794 0.1778)
							(mid -0.249642 0.249642)
							(end -0.1778 0.2794)
						)
						(arc
							(start 0.1778 0.2794)
							(mid 0.249642 0.249642)
							(end 0.2794 0.1778)
						)
						(arc
							(start 0.2794 -0.1778)
							(mid 0.249642 -0.249642)
							(end 0.1778 -0.2794)
						)
					)
					(width 0)
					(fill yes)
				)
			)
		)
		(pad "2" smd custom
			(at 0 0.4445 180)
			(size 0.1397 0.1397)
			(layers "F.Cu" "F.Mask" "F.Paste")
			(net "GND")
			(options
				(clearance outline)
				(anchor circle)
			)
			(primitives
				(gr_poly
					(pts
						(arc
							(start -0.1778 -0.2794)
							(mid -0.249642 -0.249642)
							(end -0.2794 -0.1778)
						)
						(arc
							(start -0.2794 0.1778)
							(mid -0.249642 0.249642)
							(end -0.1778 0.2794)
						)
						(arc
							(start 0.1778 0.2794)
							(mid 0.249642 0.249642)
							(end 0.2794 0.1778)
						)
						(arc
							(start 0.2794 -0.1778)
							(mid 0.249642 -0.249642)
							(end 0.1778 -0.2794)
						)
					)
					(width 0)
					(fill yes)
				)
			)
		)
	)
	(footprint ""
		(layer "F.Cu")
		(at 455.93 -152.908 180)
		(property "Reference" "C316"
			(at 0 0 180)
			(layer "F.SilkS")
			(hide yes)
			(effects
				(font
					(size 1.27 1.27)
				)
			)
		)
		(property "Value" "SC1U16V3KX-5GP"
			(at 0 -2.8194 180)
			(unlocked yes)
			(layer "F.Fab")
			(hide yes)
			(effects
				(font
					(size 1.016 1.016)
					(thickness 0.1524)
				)
			)
		)
		(property "Device Type" "C603H36"
			(at 0 -4.3434 180)
			(unlocked yes)
			(layer "F.Fab")
			(hide yes)
			(effects
				(font
					(size 1.016 1.016)
					(thickness 0.1524)
				)
			)
		)
		(duplicate_pad_numbers_are_jumpers no)
		(fp_line
			(start 0.508 0)
			(end -0.508 0)
			(stroke
				(width 0.2032)
				(type default)
			)
			(layer "F.SilkS")
		)
		(fp_rect
			(start -0.5842 1.3335)
			(end 0.5842 -1.3335)
			(stroke
				(width 0)
				(type default)
			)
			(fill no)
			(layer "F.CrtYd")
		)
		(fp_rect
			(start -0.5842 1.3335)
			(end 0.5842 -1.3335)
			(stroke
				(width 0)
				(type default)
			)
			(fill no)
			(layer "F.Fab")
		)
		(pad "1" smd custom
			(at 0 -0.762 180)
			(size 0.2159 0.2159)
			(layers "F.Cu" "F.Mask" "F.Paste")
			(net "P5V_HDD22")
			(options
				(clearance outline)
				(anchor circle)
			)
			(primitives
				(gr_poly
					(pts
						(arc
							(start -0.3302 -0.4318)
							(mid -0.402042 -0.402042)
							(end -0.4318 -0.3302)
						)
						(arc
							(start -0.4318 0.3302)
							(mid -0.402042 0.402042)
							(end -0.3302 0.4318)
						)
						(arc
							(start 0.3302 0.4318)
							(mid 0.402042 0.402042)
							(end 0.4318 0.3302)
						)
						(arc
							(start 0.4318 -0.3302)
							(mid 0.402042 -0.402042)
							(end 0.3302 -0.4318)
						)
					)
					(width 0)
					(fill yes)
				)
			)
		)
		(pad "2" smd custom
			(at 0 0.762 180)
			(size 0.2159 0.2159)
			(layers "F.Cu" "F.Mask" "F.Paste")
			(net "GND")
			(options
				(clearance outline)
				(anchor circle)
			)
			(primitives
				(gr_poly
					(pts
						(arc
							(start -0.3302 -0.4318)
							(mid -0.402042 -0.402042)
							(end -0.4318 -0.3302)
						)
						(arc
							(start -0.4318 0.3302)
							(mid -0.402042 0.402042)
							(end -0.3302 0.4318)
						)
						(arc
							(start 0.3302 0.4318)
							(mid 0.402042 0.402042)
							(end 0.4318 0.3302)
						)
						(arc
							(start 0.4318 -0.3302)
							(mid 0.402042 -0.402042)
							(end 0.3302 -0.4318)
						)
					)
					(width 0)
					(fill yes)
				)
			)
		)
	)
	(footprint ""
		(layer "F.Cu")
		(at 328.643996 -371.856 -90)
		(property "Reference" "D41"
			(at 0 0 270)
			(layer "F.SilkS")
			(hide yes)
			(effects
				(font
					(size 1.27 1.27)
				)
			)
		)
		(property "Value" "BAS16H-GP"
			(at 0 -5.5372 270)
			(unlocked yes)
			(layer "F.Fab")
			(hide yes)
			(effects
				(font
					(size 1.016 1.016)
					(thickness 0.1524)
				)
			)
		)
		(property "Device Type" "SOD123AKH48"
			(at 0 -7.0612 270)
			(unlocked yes)
			(layer "F.Fab")
			(hide yes)
			(effects
				(font
					(size 1.016 1.016)
					(thickness 0.1524)
				)
			)
		)
		(duplicate_pad_numbers_are_jumpers no)
		(fp_line
			(start 0.889 2.921)
			(end -0.889 2.921)
			(stroke
				(width 0.508)
				(type default)
			)
			(layer "F.SilkS")
		)
		(fp_line
			(start -1.016 2.667)
			(end 1.016 2.667)
			(stroke
				(width 0.1524)
				(type default)
			)
			(layer "F.SilkS")
		)
		(fp_line
			(start 1.016 2.667)
			(end 1.016 -2.667)
			(stroke
				(width 0.1524)
				(type default)
			)
			(layer "F.SilkS")
		)
		(fp_line
			(start -1.016 -2.667)
			(end -1.016 2.667)
			(stroke
				(width 0.1524)
				(type default)
			)
			(layer "F.SilkS")
		)
		(fp_line
			(start 1.016 -2.667)
			(end -1.016 -2.667)
			(stroke
				(width 0.1524)
				(type default)
			)
			(layer "F.SilkS")
		)
		(fp_rect
			(start -1.143 3.175)
			(end 1.143 -2.794)
			(stroke
				(width 0)
				(type default)
			)
			(fill no)
			(layer "F.CrtYd")
		)
		(fp_poly
			(pts
				(xy -1.143 -2.794) (xy 1.143 -2.794) (xy 1.143 3.175) (xy -1.143 3.175)
			)
			(stroke
				(width 0)
				(type default)
			)
			(fill no)
			(layer "F.Fab")
		)
		(pad "A" smd rect
			(at 0 -1.6891 270)
			(size 0.889 1.397)
			(layers "F.Cu" "F.Mask" "F.Paste")
			(net "FAN_2_TACH0")
		)
		(pad "K" smd rect
			(at 0 1.6891 270)
			(size 0.889 1.397)
			(layers "F.Cu" "F.Mask" "F.Paste")
			(net "P12V_IN")
		)
	)
	(footprint ""
		(layer "F.Cu")
		(at 150.114 -42.291)
		(property "Reference" "C399"
			(at 0 0 0)
			(layer "F.SilkS")
			(hide yes)
			(effects
				(font
					(size 1.27 1.27)
				)
			)
		)
		(property "Value" "SC4D7U25V5KX-1-GP"
			(at -0.0762 -6.1214 0)
			(unlocked yes)
			(layer "F.Fab")
			(hide yes)
			(effects
				(font
					(size 1.016 1.016)
					(thickness 0.1524)
				)
			)
		)
		(property "Device Type" "C805H58"
			(at -0.0762 -8.1534 0)
			(unlocked yes)
			(layer "F.Fab")
			(hide yes)
			(effects
				(font
					(size 1.016 1.016)
					(thickness 0.1524)
				)
			)
		)
		(duplicate_pad_numbers_are_jumpers no)
		(fp_line
			(start 0.635 0)
			(end -0.635 0)
			(stroke
				(width 0.508)
				(type default)
			)
			(layer "F.SilkS")
		)
		(fp_rect
			(start -0.9652 1.778)
			(end 0.9652 -1.778)
			(stroke
				(width 0)
				(type default)
			)
			(fill no)
			(layer "F.CrtYd")
		)
		(fp_poly
			(pts
				(xy -0.9652 -1.778) (xy 0.9652 -1.778) (xy 0.9652 1.778) (xy -0.9652 1.778)
			)
			(stroke
				(width 0)
				(type default)
			)
			(fill no)
			(layer "F.Fab")
		)
		(pad "1" smd rect
			(at 0 -0.9652)
			(size 1.397 1.143)
			(layers "F.Cu" "F.Mask" "F.Paste")
			(net "P12V_HDD28")
		)
		(pad "2" smd rect
			(at 0 0.9652)
			(size 1.397 1.143)
			(layers "F.Cu" "F.Mask" "F.Paste")
			(net "GND")
		)
	)
	(footprint ""
		(layer "F.Cu")
		(at 439.037222 -118.613682 -90)
		(property "Reference" "R1164"
			(at 0 0 270)
			(layer "F.SilkS")
			(hide yes)
			(effects
				(font
					(size 1.27 1.27)
				)
			)
		)
		(property "Value" "200KR2F-L-GP"
			(at 0.064008 -3.993896 270)
			(unlocked yes)
			(layer "F.Fab")
			(hide yes)
			(effects
				(font
					(size 1.016 1.016)
					(thickness 0.1524)
				)
			)
		)
		(property "Device Type" "R402H16"
			(at 0.064008 -5.517896 270)
			(unlocked yes)
			(layer "F.Fab")
			(hide yes)
			(effects
				(font
					(size 1.016 1.016)
					(thickness 0.1524)
				)
			)
		)
		(duplicate_pad_numbers_are_jumpers no)
		(fp_line
			(start -0.508 -0.9398)
			(end -0.508 0.9398)
			(stroke
				(width 0.1524)
				(type default)
			)
			(layer "F.SilkS")
		)
		(fp_line
			(start 0.508 -0.9398)
			(end -0.508 -0.9398)
			(stroke
				(width 0.1524)
				(type default)
			)
			(layer "F.SilkS")
		)
		(fp_rect
			(start -0.508 0.9398)
			(end 0.508 -0.9398)
			(stroke
				(width 0)
				(type default)
			)
			(fill no)
			(layer "F.CrtYd")
		)
		(fp_rect
			(start -0.508 0.9398)
			(end 0.508 -0.9398)
			(stroke
				(width 0)
				(type default)
			)
			(fill no)
			(layer "F.Fab")
		)
		(pad "1" smd custom
			(at 0 -0.4445 270)
			(size 0.1397 0.1397)
			(layers "F.Cu" "F.Mask" "F.Paste")
			(net "P5V_B_4_MODE")
			(options
				(clearance outline)
				(anchor circle)
			)
			(primitives
				(gr_poly
					(pts
						(arc
							(start -0.1778 -0.2794)
							(mid -0.249642 -0.249642)
							(end -0.2794 -0.1778)
						)
						(arc
							(start -0.2794 0.1778)
							(mid -0.249642 0.249642)
							(end -0.1778 0.2794)
						)
						(arc
							(start 0.1778 0.2794)
							(mid 0.249642 0.249642)
							(end 0.2794 0.1778)
						)
						(arc
							(start 0.2794 -0.1778)
							(mid 0.249642 -0.249642)
							(end 0.1778 -0.2794)
						)
					)
					(width 0)
					(fill yes)
				)
			)
		)
		(pad "2" smd custom
			(at 0 0.4445 270)
			(size 0.1397 0.1397)
			(layers "F.Cu" "F.Mask" "F.Paste")
			(net "P5V_B_4_PGOOD")
			(options
				(clearance outline)
				(anchor circle)
			)
			(primitives
				(gr_poly
					(pts
						(arc
							(start -0.1778 -0.2794)
							(mid -0.249642 -0.249642)
							(end -0.2794 -0.1778)
						)
						(arc
							(start -0.2794 0.1778)
							(mid -0.249642 0.249642)
							(end -0.1778 0.2794)
						)
						(arc
							(start 0.1778 0.2794)
							(mid 0.249642 0.249642)
							(end 0.2794 0.1778)
						)
						(arc
							(start 0.2794 -0.1778)
							(mid 0.249642 -0.249642)
							(end 0.1778 -0.2794)
						)
					)
					(width 0)
					(fill yes)
				)
			)
		)
	)
	(footprint ""
		(layer "F.Cu")
		(at 244.199918 -243.999766)
		(property "Reference" ""
			(at 0 0 0)
			(layer "F.SilkS")
			(hide yes)
			(effects
				(font
					(size 1.27 1.27)
				)
			)
		)
		(property "Value" "*"
			(at -8.398764 -8.057642 0)
			(unlocked yes)
			(layer "F.Fab")
			(hide yes)
			(effects
				(font
					(size 1.016 1.016)
					(thickness 0.1524)
				)
			)
		)
		(duplicate_pad_numbers_are_jumpers no)
		(fp_poly
			(pts
				(arc
					(start 7.3152 0)
					(mid 0 7.3152)
					(end -7.3152 0)
				)
				(arc
					(start -7.3152 -5.9944)
					(mid 0 -13.3096)
					(end 7.3152 -5.9944)
				)
			)
			(stroke
				(width 0)
				(type default)
			)
			(fill no)
			(layer "B.CrtYd")
		)
		(fp_poly
			(pts
				(arc
					(start 7.3152 0)
					(mid 0 7.3152)
					(end -7.3152 0)
				)
				(arc
					(start -7.3152 -5.9944)
					(mid 0 -13.3096)
					(end 7.3152 -5.9944)
				)
			)
			(stroke
				(width 0)
				(type default)
			)
			(fill no)
			(layer "F.CrtYd")
		)
		(fp_poly
			(pts
				(arc
					(start 7.3152 0)
					(mid 0 7.3152)
					(end -7.3152 0)
				)
				(arc
					(start -7.3152 -5.9944)
					(mid 0 -13.3096)
					(end 7.3152 -5.9944)
				)
			)
			(stroke
				(width 0)
				(type default)
			)
			(fill no)
			(layer "B.Fab")
		)
		(fp_poly
			(pts
				(arc
					(start 7.3152 0)
					(mid 0 7.3152)
					(end -7.3152 0)
				)
				(arc
					(start -7.3152 -5.9944)
					(mid 0 -13.3096)
					(end 7.3152 -5.9944)
				)
			)
			(stroke
				(width 0)
				(type default)
			)
			(fill no)
			(layer "F.Fab")
		)
		(pad "1" thru_hole oval
			(at 0 0)
			(size 14.0208 20.0152)
			(drill 0.0254
				(offset 0 -2.9972)
			)
			(layers "*.Cu" "*.Mask")
			(remove_unused_layers no)
			(net "Net_20")
			(clearance -1.002284)
			(thermal_gap 0.1524)
			(padstack
				(mode front_inner_back)
				(layer "Inner"
					(shape custom)
					(size 2.928012 2.928012)
					(options
						(anchor circle)
					)
					(primitives
						(gr_poly
							(pts
								(arc
									(start 4.571746 -2.084324)
									(mid 0.000333 7.430372)
									(end -4.571492 -2.084324)
								)
								(arc
									(start -4.571492 -2.084324)
									(mid -3.570296 -3.611977)
									(end -2.875026 -5.30098)
								)
								(arc
									(start -2.875026 -5.30098)
									(mid 0.000217 -7.43089)
									(end 2.87528 -5.30098)
								)
								(arc
									(start 2.87528 -5.30098)
									(mid 3.570511 -3.611956)
									(end 4.571746 -2.084324)
								)
							)
							(width 0)
							(fill yes)
						)
					)
					(clearance 0.1524)
				)
				(layer "B.Cu"
					(shape oval)
					(size 14.0208 20.0152)
					(offset 0 -2.9972)
					(clearance -1.002284)
				)
			)
		)
		(zone
			(layers "F.Cu" "B.Cu" "In1.Cu" "In2.Cu" "In3.Cu" "In4.Cu" "In5.Cu" "In6.Cu")
			(hatch none 0.5)
			(connect_pads
				(clearance 0)
			)
			(min_thickness 0.25)
			(keepout
				(tracks not_allowed)
				(vias allowed)
				(pads allowed)
				(copperpour not_allowed)
				(footprints allowed)
			)
			(placement
				(enabled no)
				(sheetname "")
			)
			(fill
				(thermal_gap 0.5)
				(thermal_bridge_width 0.5)
				(island_removal_mode 0)
			)
			(polygon
				(pts
					(arc
						(start 237.189518 -249.994166)
						(mid 244.199918 -257.004566)
						(end 251.210318 -249.994166)
					)
					(arc
						(start 251.210318 -243.999766)
						(mid 244.199918 -236.989366)
						(end 237.189518 -243.999766)
					)
				)
			)
		)
	)
	(footprint ""
		(layer "F.Cu")
		(at 469.773 -251.587 180)
		(property "Reference" "D11"
			(at 0 0 180)
			(layer "F.SilkS")
			(hide yes)
			(effects
				(font
					(size 1.27 1.27)
				)
			)
		)
		(property "Value" "RB551V30-GP"
			(at 0 -6.7818 180)
			(unlocked yes)
			(layer "F.Fab")
			(hide yes)
			(effects
				(font
					(size 1.016 1.016)
					(thickness 0.1524)
				)
			)
		)
		(property "Device Type" "SOD323AKH38"
			(at 0 -8.6868 180)
			(unlocked yes)
			(layer "F.Fab")
			(hide yes)
			(effects
				(font
					(size 1.016 1.016)
					(thickness 0.1524)
				)
			)
		)
		(duplicate_pad_numbers_are_jumpers no)
		(fp_line
			(start 0.889 2.159)
			(end -0.889 2.159)
			(stroke
				(width 0.1524)
				(type default)
			)
			(layer "F.SilkS")
		)
		(fp_line
			(start 0.889 -1.9304)
			(end 0.889 2.159)
			(stroke
				(width 0.1524)
				(type default)
			)
			(layer "F.SilkS")
		)
		(fp_line
			(start 0.762 2.0574)
			(end -0.762 2.0574)
			(stroke
				(width 0.508)
				(type default)
			)
			(layer "F.SilkS")
		)
		(fp_line
			(start -0.889 2.159)
			(end -0.889 -1.9304)
			(stroke
				(width 0.1524)
				(type default)
			)
			(layer "F.SilkS")
		)
		(fp_line
			(start -0.889 -1.9304)
			(end 0.889 -1.9304)
			(stroke
				(width 0.1524)
				(type default)
			)
			(layer "F.SilkS")
		)
		(fp_rect
			(start -1.016 2.3114)
			(end 1.016 -2.0066)
			(stroke
				(width 0)
				(type default)
			)
			(fill no)
			(layer "F.CrtYd")
		)
		(fp_poly
			(pts
				(xy -1.016 -2.0066) (xy 1.016 -2.0066) (xy 1.016 2.3114) (xy -1.016 2.3114)
			)
			(stroke
				(width 0)
				(type default)
			)
			(fill no)
			(layer "F.Fab")
		)
		(pad "A" smd rect
			(at 0 -1.143 180)
			(size 0.5588 1.016)
			(layers "F.Cu" "F.Mask" "F.Paste")
			(net "SW_HDD_R11")
		)
		(pad "K" smd rect
			(at 0 1.143 180)
			(size 0.5588 1.016)
			(layers "F.Cu" "F.Mask" "F.Paste")
			(net "SW_HDD_N11")
		)
	)
	(footprint ""
		(layer "F.Cu")
		(at 45.599858 -118.324376 180)
		(property "Reference" "R1132"
			(at 0 0 180)
			(layer "F.SilkS")
			(hide yes)
			(effects
				(font
					(size 1.27 1.27)
				)
			)
		)
		(property "Value" "0R2J-2-GP"
			(at 0.064008 -3.993896 180)
			(unlocked yes)
			(layer "F.Fab")
			(hide yes)
			(effects
				(font
					(size 1.016 1.016)
					(thickness 0.1524)
				)
			)
		)
		(property "Device Type" "R402H16"
			(at 0.064008 -5.517896 180)
			(unlocked yes)
			(layer "F.Fab")
			(hide yes)
			(effects
				(font
					(size 1.016 1.016)
					(thickness 0.1524)
				)
			)
		)
		(duplicate_pad_numbers_are_jumpers no)
		(fp_line
			(start 0.508 -0.9398)
			(end -0.508 -0.9398)
			(stroke
				(width 0.1524)
				(type default)
			)
			(layer "F.SilkS")
		)
		(fp_line
			(start -0.508 -0.9398)
			(end -0.508 0.9398)
			(stroke
				(width 0.1524)
				(type default)
			)
			(layer "F.SilkS")
		)
		(fp_rect
			(start -0.508 0.9398)
			(end 0.508 -0.9398)
			(stroke
				(width 0)
				(type default)
			)
			(fill no)
			(layer "F.CrtYd")
		)
		(fp_rect
			(start -0.508 0.9398)
			(end 0.508 -0.9398)
			(stroke
				(width 0)
				(type default)
			)
			(fill no)
			(layer "F.Fab")
		)
		(pad "1" smd custom
			(at 0 -0.4445 180)
			(size 0.1397 0.1397)
			(layers "F.Cu" "F.Mask" "F.Paste")
			(net "P5V_B_2_ROVP")
			(options
				(clearance outline)
				(anchor circle)
			)
			(primitives
				(gr_poly
					(pts
						(arc
							(start -0.1778 -0.2794)
							(mid -0.249642 -0.249642)
							(end -0.2794 -0.1778)
						)
						(arc
							(start -0.2794 0.1778)
							(mid -0.249642 0.249642)
							(end -0.1778 0.2794)
						)
						(arc
							(start 0.1778 0.2794)
							(mid 0.249642 0.249642)
							(end 0.2794 0.1778)
						)
						(arc
							(start 0.2794 -0.1778)
							(mid 0.249642 -0.249642)
							(end 0.1778 -0.2794)
						)
					)
					(width 0)
					(fill yes)
				)
			)
		)
		(pad "2" smd custom
			(at 0 0.4445 180)
			(size 0.1397 0.1397)
			(layers "F.Cu" "F.Mask" "F.Paste")
			(net "AGND_P5V_B_2")
			(options
				(clearance outline)
				(anchor circle)
			)
			(primitives
				(gr_poly
					(pts
						(arc
							(start -0.1778 -0.2794)
							(mid -0.249642 -0.249642)
							(end -0.2794 -0.1778)
						)
						(arc
							(start -0.2794 0.1778)
							(mid -0.249642 0.249642)
							(end -0.1778 0.2794)
						)
						(arc
							(start 0.1778 0.2794)
							(mid 0.249642 0.249642)
							(end 0.2794 0.1778)
						)
						(arc
							(start 0.2794 -0.1778)
							(mid 0.249642 -0.249642)
							(end 0.1778 -0.2794)
						)
					)
					(width 0)
					(fill yes)
				)
			)
		)
	)
	(footprint ""
		(layer "F.Cu")
		(at 425.228004 -371.856 -90)
		(property "Reference" "D43"
			(at 0 0 270)
			(layer "F.SilkS")
			(hide yes)
			(effects
				(font
					(size 1.27 1.27)
				)
			)
		)
		(property "Value" "BAS16H-GP"
			(at 0 -5.5372 270)
			(unlocked yes)
			(layer "F.Fab")
			(hide yes)
			(effects
				(font
					(size 1.016 1.016)
					(thickness 0.1524)
				)
			)
		)
		(property "Device Type" "SOD123AKH48"
			(at 0 -7.0612 270)
			(unlocked yes)
			(layer "F.Fab")
			(hide yes)
			(effects
				(font
					(size 1.016 1.016)
					(thickness 0.1524)
				)
			)
		)
		(duplicate_pad_numbers_are_jumpers no)
		(fp_line
			(start 0.889 2.921)
			(end -0.889 2.921)
			(stroke
				(width 0.508)
				(type default)
			)
			(layer "F.SilkS")
		)
		(fp_line
			(start -1.016 2.667)
			(end 1.016 2.667)
			(stroke
				(width 0.1524)
				(type default)
			)
			(layer "F.SilkS")
		)
		(fp_line
			(start 1.016 2.667)
			(end 1.016 -2.667)
			(stroke
				(width 0.1524)
				(type default)
			)
			(layer "F.SilkS")
		)
		(fp_line
			(start -1.016 -2.667)
			(end -1.016 2.667)
			(stroke
				(width 0.1524)
				(type default)
			)
			(layer "F.SilkS")
		)
		(fp_line
			(start 1.016 -2.667)
			(end -1.016 -2.667)
			(stroke
				(width 0.1524)
				(type default)
			)
			(layer "F.SilkS")
		)
		(fp_rect
			(start -1.143 3.175)
			(end 1.143 -2.794)
			(stroke
				(width 0)
				(type default)
			)
			(fill no)
			(layer "F.CrtYd")
		)
		(fp_poly
			(pts
				(xy -1.143 -2.794) (xy 1.143 -2.794) (xy 1.143 3.175) (xy -1.143 3.175)
			)
			(stroke
				(width 0)
				(type default)
			)
			(fill no)
			(layer "F.Fab")
		)
		(pad "A" smd rect
			(at 0 -1.6891 270)
			(size 0.889 1.397)
			(layers "F.Cu" "F.Mask" "F.Paste")
			(net "FAN_3_TACH0")
		)
		(pad "K" smd rect
			(at 0 1.6891 270)
			(size 0.889 1.397)
			(layers "F.Cu" "F.Mask" "F.Paste")
			(net "P12V_IN")
		)
	)
	(footprint ""
		(layer "F.Cu")
		(at 249.260614 -143.207994 90)
		(property "Reference" "C59"
			(at 0 0 90)
			(layer "F.SilkS")
			(hide yes)
			(effects
				(font
					(size 1.27 1.27)
				)
			)
		)
		(property "Value" "SC1U16V3KX-5GP"
			(at 0 -2.8194 90)
			(unlocked yes)
			(layer "F.Fab")
			(hide yes)
			(effects
				(font
					(size 1.016 1.016)
					(thickness 0.1524)
				)
			)
		)
		(property "Device Type" "C603H36"
			(at 0 -4.3434 90)
			(unlocked yes)
			(layer "F.Fab")
			(hide yes)
			(effects
				(font
					(size 1.016 1.016)
					(thickness 0.1524)
				)
			)
		)
		(duplicate_pad_numbers_are_jumpers no)
		(fp_line
			(start 0.508 0)
			(end -0.508 0)
			(stroke
				(width 0.2032)
				(type default)
			)
			(layer "F.SilkS")
		)
		(fp_rect
			(start -0.5842 1.3335)
			(end 0.5842 -1.3335)
			(stroke
				(width 0)
				(type default)
			)
			(fill no)
			(layer "F.CrtYd")
		)
		(fp_rect
			(start -0.5842 1.3335)
			(end 0.5842 -1.3335)
			(stroke
				(width 0)
				(type default)
			)
			(fill no)
			(layer "F.Fab")
		)
		(pad "1" smd custom
			(at 0 -0.762 90)
			(size 0.2159 0.2159)
			(layers "F.Cu" "F.Mask" "F.Paste")
			(net "P3V3_STBY_B")
			(options
				(clearance outline)
				(anchor circle)
			)
			(primitives
				(gr_poly
					(pts
						(arc
							(start -0.3302 -0.4318)
							(mid -0.402042 -0.402042)
							(end -0.4318 -0.3302)
						)
						(arc
							(start -0.4318 0.3302)
							(mid -0.402042 0.402042)
							(end -0.3302 0.4318)
						)
						(arc
							(start 0.3302 0.4318)
							(mid 0.402042 0.402042)
							(end 0.4318 0.3302)
						)
						(arc
							(start 0.4318 -0.3302)
							(mid 0.402042 -0.402042)
							(end 0.3302 -0.4318)
						)
					)
					(width 0)
					(fill yes)
				)
			)
		)
		(pad "2" smd custom
			(at 0 0.762 90)
			(size 0.2159 0.2159)
			(layers "F.Cu" "F.Mask" "F.Paste")
			(net "GND")
			(options
				(clearance outline)
				(anchor circle)
			)
			(primitives
				(gr_poly
					(pts
						(arc
							(start -0.3302 -0.4318)
							(mid -0.402042 -0.402042)
							(end -0.4318 -0.3302)
						)
						(arc
							(start -0.4318 0.3302)
							(mid -0.402042 0.402042)
							(end -0.3302 0.4318)
						)
						(arc
							(start 0.3302 0.4318)
							(mid 0.402042 0.402042)
							(end 0.4318 0.3302)
						)
						(arc
							(start 0.4318 -0.3302)
							(mid 0.402042 -0.402042)
							(end 0.3302 -0.4318)
						)
					)
					(width 0)
					(fill yes)
				)
			)
		)
	)
	(footprint ""
		(layer "F.Cu")
		(at 426.1866 -249.5042 90)
		(property "Reference" "R307"
			(at 0 0 90)
			(layer "F.SilkS")
			(hide yes)
			(effects
				(font
					(size 1.27 1.27)
				)
			)
		)
		(property "Value" "4K7R2J-2-GP"
			(at 0.064008 -3.993896 90)
			(unlocked yes)
			(layer "F.Fab")
			(hide yes)
			(effects
				(font
					(size 1.016 1.016)
					(thickness 0.1524)
				)
			)
		)
		(property "Device Type" "R402H16"
			(at 0.064008 -5.517896 90)
			(unlocked yes)
			(layer "F.Fab")
			(hide yes)
			(effects
				(font
					(size 1.016 1.016)
					(thickness 0.1524)
				)
			)
		)
		(duplicate_pad_numbers_are_jumpers no)
		(fp_line
			(start 0.508 -0.9398)
			(end -0.508 -0.9398)
			(stroke
				(width 0.1524)
				(type default)
			)
			(layer "F.SilkS")
		)
		(fp_line
			(start -0.508 -0.9398)
			(end -0.508 0.9398)
			(stroke
				(width 0.1524)
				(type default)
			)
			(layer "F.SilkS")
		)
		(fp_rect
			(start -0.508 0.9398)
			(end 0.508 -0.9398)
			(stroke
				(width 0)
				(type default)
			)
			(fill no)
			(layer "F.CrtYd")
		)
		(fp_rect
			(start -0.508 0.9398)
			(end 0.508 -0.9398)
			(stroke
				(width 0)
				(type default)
			)
			(fill no)
			(layer "F.Fab")
		)
		(pad "1" smd custom
			(at 0 -0.4445 90)
			(size 0.1397 0.1397)
			(layers "F.Cu" "F.Mask" "F.Paste")
			(net "P12V_B")
			(options
				(clearance outline)
				(anchor circle)
			)
			(primitives
				(gr_poly
					(pts
						(arc
							(start -0.1778 -0.2794)
							(mid -0.249642 -0.249642)
							(end -0.2794 -0.1778)
						)
						(arc
							(start -0.2794 0.1778)
							(mid -0.249642 0.249642)
							(end -0.1778 0.2794)
						)
						(arc
							(start 0.1778 0.2794)
							(mid 0.249642 0.249642)
							(end 0.2794 0.1778)
						)
						(arc
							(start 0.2794 -0.1778)
							(mid 0.249642 -0.249642)
							(end 0.1778 -0.2794)
						)
					)
					(width 0)
					(fill yes)
				)
			)
		)
		(pad "2" smd custom
			(at 0 0.4445 90)
			(size 0.1397 0.1397)
			(layers "F.Cu" "F.Mask" "F.Paste")
			(net "SW_HDD_P9")
			(options
				(clearance outline)
				(anchor circle)
			)
			(primitives
				(gr_poly
					(pts
						(arc
							(start -0.1778 -0.2794)
							(mid -0.249642 -0.249642)
							(end -0.2794 -0.1778)
						)
						(arc
							(start -0.2794 0.1778)
							(mid -0.249642 0.249642)
							(end -0.1778 0.2794)
						)
						(arc
							(start 0.1778 0.2794)
							(mid 0.249642 0.249642)
							(end 0.2794 0.1778)
						)
						(arc
							(start 0.2794 -0.1778)
							(mid 0.249642 -0.249642)
							(end 0.1778 -0.2794)
						)
					)
					(width 0)
					(fill yes)
				)
			)
		)
	)
	(footprint ""
		(layer "F.Cu")
		(at 167.104568 -212.314028 -90)
		(property "Reference" "R229"
			(at 0 0 270)
			(layer "F.SilkS")
			(hide yes)
			(effects
				(font
					(size 1.27 1.27)
				)
			)
		)
		(property "Value" "4K7R2F-GP"
			(at 0.064008 -3.993896 270)
			(unlocked yes)
			(layer "F.Fab")
			(hide yes)
			(effects
				(font
					(size 1.016 1.016)
					(thickness 0.1524)
				)
			)
		)
		(property "Device Type" "R402H16"
			(at 0.064008 -5.517896 270)
			(unlocked yes)
			(layer "F.Fab")
			(hide yes)
			(effects
				(font
					(size 1.016 1.016)
					(thickness 0.1524)
				)
			)
		)
		(duplicate_pad_numbers_are_jumpers no)
		(fp_line
			(start -0.508 -0.9398)
			(end -0.508 0.9398)
			(stroke
				(width 0.1524)
				(type default)
			)
			(layer "F.SilkS")
		)
		(fp_line
			(start 0.508 -0.9398)
			(end -0.508 -0.9398)
			(stroke
				(width 0.1524)
				(type default)
			)
			(layer "F.SilkS")
		)
		(fp_rect
			(start -0.508 0.9398)
			(end 0.508 -0.9398)
			(stroke
				(width 0)
				(type default)
			)
			(fill no)
			(layer "F.CrtYd")
		)
		(fp_rect
			(start -0.508 0.9398)
			(end 0.508 -0.9398)
			(stroke
				(width 0)
				(type default)
			)
			(fill no)
			(layer "F.Fab")
		)
		(pad "1" smd custom
			(at 0 -0.4445 270)
			(size 0.1397 0.1397)
			(layers "F.Cu" "F.Mask" "F.Paste")
			(net "DRIVE_B_5_ACT")
			(options
				(clearance outline)
				(anchor circle)
			)
			(primitives
				(gr_poly
					(pts
						(arc
							(start -0.1778 -0.2794)
							(mid -0.249642 -0.249642)
							(end -0.2794 -0.1778)
						)
						(arc
							(start -0.2794 0.1778)
							(mid -0.249642 0.249642)
							(end -0.1778 0.2794)
						)
						(arc
							(start 0.1778 0.2794)
							(mid 0.249642 0.249642)
							(end 0.2794 0.1778)
						)
						(arc
							(start 0.2794 -0.1778)
							(mid 0.249642 -0.249642)
							(end 0.1778 -0.2794)
						)
					)
					(width 0)
					(fill yes)
				)
			)
		)
		(pad "2" smd custom
			(at 0 0.4445 270)
			(size 0.1397 0.1397)
			(layers "F.Cu" "F.Mask" "F.Paste")
			(net "GND")
			(options
				(clearance outline)
				(anchor circle)
			)
			(primitives
				(gr_poly
					(pts
						(arc
							(start -0.1778 -0.2794)
							(mid -0.249642 -0.249642)
							(end -0.2794 -0.1778)
						)
						(arc
							(start -0.2794 0.1778)
							(mid -0.249642 0.249642)
							(end -0.1778 0.2794)
						)
						(arc
							(start 0.1778 0.2794)
							(mid 0.249642 0.249642)
							(end 0.2794 0.1778)
						)
						(arc
							(start 0.2794 -0.1778)
							(mid 0.249642 -0.249642)
							(end 0.1778 -0.2794)
						)
					)
					(width 0)
					(fill yes)
				)
			)
		)
	)
	(footprint ""
		(layer "F.Cu")
		(at 64.7446 -31.6484 180)
		(property "Reference" "R645"
			(at 0 0 180)
			(layer "F.SilkS")
			(hide yes)
			(effects
				(font
					(size 1.27 1.27)
				)
			)
		)
		(property "Value" "10KR2F-2-GP"
			(at 0.064008 -3.993896 180)
			(unlocked yes)
			(layer "F.Fab")
			(hide yes)
			(effects
				(font
					(size 1.016 1.016)
					(thickness 0.1524)
				)
			)
		)
		(property "Device Type" "R402H16"
			(at 0.064008 -5.517896 180)
			(unlocked yes)
			(layer "F.Fab")
			(hide yes)
			(effects
				(font
					(size 1.016 1.016)
					(thickness 0.1524)
				)
			)
		)
		(duplicate_pad_numbers_are_jumpers no)
		(fp_line
			(start 0.508 -0.9398)
			(end -0.508 -0.9398)
			(stroke
				(width 0.1524)
				(type default)
			)
			(layer "F.SilkS")
		)
		(fp_line
			(start -0.508 -0.9398)
			(end -0.508 0.9398)
			(stroke
				(width 0.1524)
				(type default)
			)
			(layer "F.SilkS")
		)
		(fp_rect
			(start -0.508 0.9398)
			(end 0.508 -0.9398)
			(stroke
				(width 0)
				(type default)
			)
			(fill no)
			(layer "F.CrtYd")
		)
		(fp_rect
			(start -0.508 0.9398)
			(end 0.508 -0.9398)
			(stroke
				(width 0)
				(type default)
			)
			(fill no)
			(layer "F.Fab")
		)
		(pad "1" smd custom
			(at 0 -0.4445 180)
			(size 0.1397 0.1397)
			(layers "F.Cu" "F.Mask" "F.Paste")
			(net "P3V3_STBY_B")
			(options
				(clearance outline)
				(anchor circle)
			)
			(primitives
				(gr_poly
					(pts
						(arc
							(start -0.1778 -0.2794)
							(mid -0.249642 -0.249642)
							(end -0.2794 -0.1778)
						)
						(arc
							(start -0.2794 0.1778)
							(mid -0.249642 0.249642)
							(end -0.1778 0.2794)
						)
						(arc
							(start 0.1778 0.2794)
							(mid 0.249642 0.249642)
							(end 0.2794 0.1778)
						)
						(arc
							(start 0.2794 -0.1778)
							(mid 0.249642 -0.249642)
							(end 0.1778 -0.2794)
						)
					)
					(width 0)
					(fill yes)
				)
			)
		)
		(pad "2" smd custom
			(at 0 0.4445 180)
			(size 0.1397 0.1397)
			(layers "F.Cu" "F.Mask" "F.Paste")
			(net "HDD_PRSNT_25")
			(options
				(clearance outline)
				(anchor circle)
			)
			(primitives
				(gr_poly
					(pts
						(arc
							(start -0.1778 -0.2794)
							(mid -0.249642 -0.249642)
							(end -0.2794 -0.1778)
						)
						(arc
							(start -0.2794 0.1778)
							(mid -0.249642 0.249642)
							(end -0.1778 0.2794)
						)
						(arc
							(start 0.1778 0.2794)
							(mid 0.249642 0.249642)
							(end 0.2794 0.1778)
						)
						(arc
							(start 0.2794 -0.1778)
							(mid 0.249642 -0.249642)
							(end 0.1778 -0.2794)
						)
					)
					(width 0)
					(fill yes)
				)
			)
		)
	)
	(footprint ""
		(layer "F.Cu")
		(at 15.09395 -217.413586 -90)
		(property "Reference" "R154"
			(at 0 0 270)
			(layer "F.SilkS")
			(hide yes)
			(effects
				(font
					(size 1.27 1.27)
				)
			)
		)
		(property "Value" "4K7R2F-GP"
			(at 0.064008 -3.993896 270)
			(unlocked yes)
			(layer "F.Fab")
			(hide yes)
			(effects
				(font
					(size 1.016 1.016)
					(thickness 0.1524)
				)
			)
		)
		(property "Device Type" "R402H16"
			(at 0.064008 -5.517896 270)
			(unlocked yes)
			(layer "F.Fab")
			(hide yes)
			(effects
				(font
					(size 1.016 1.016)
					(thickness 0.1524)
				)
			)
		)
		(duplicate_pad_numbers_are_jumpers no)
		(fp_line
			(start -0.508 -0.9398)
			(end -0.508 0.9398)
			(stroke
				(width 0.1524)
				(type default)
			)
			(layer "F.SilkS")
		)
		(fp_line
			(start 0.508 -0.9398)
			(end -0.508 -0.9398)
			(stroke
				(width 0.1524)
				(type default)
			)
			(layer "F.SilkS")
		)
		(fp_rect
			(start -0.508 0.9398)
			(end 0.508 -0.9398)
			(stroke
				(width 0)
				(type default)
			)
			(fill no)
			(layer "F.CrtYd")
		)
		(fp_rect
			(start -0.508 0.9398)
			(end 0.508 -0.9398)
			(stroke
				(width 0)
				(type default)
			)
			(fill no)
			(layer "F.Fab")
		)
		(pad "1" smd custom
			(at 0 -0.4445 270)
			(size 0.1397 0.1397)
			(layers "F.Cu" "F.Mask" "F.Paste")
			(net "DRIVE_B_0_FLT_LED")
			(options
				(clearance outline)
				(anchor circle)
			)
			(primitives
				(gr_poly
					(pts
						(arc
							(start -0.1778 -0.2794)
							(mid -0.249642 -0.249642)
							(end -0.2794 -0.1778)
						)
						(arc
							(start -0.2794 0.1778)
							(mid -0.249642 0.249642)
							(end -0.1778 0.2794)
						)
						(arc
							(start 0.1778 0.2794)
							(mid 0.249642 0.249642)
							(end 0.2794 0.1778)
						)
						(arc
							(start 0.2794 -0.1778)
							(mid 0.249642 -0.249642)
							(end 0.1778 -0.2794)
						)
					)
					(width 0)
					(fill yes)
				)
			)
		)
		(pad "2" smd custom
			(at 0 0.4445 270)
			(size 0.1397 0.1397)
			(layers "F.Cu" "F.Mask" "F.Paste")
			(net "GND")
			(options
				(clearance outline)
				(anchor circle)
			)
			(primitives
				(gr_poly
					(pts
						(arc
							(start -0.1778 -0.2794)
							(mid -0.249642 -0.249642)
							(end -0.2794 -0.1778)
						)
						(arc
							(start -0.2794 0.1778)
							(mid -0.249642 0.249642)
							(end -0.1778 0.2794)
						)
						(arc
							(start 0.1778 0.2794)
							(mid 0.249642 0.249642)
							(end 0.2794 0.1778)
						)
						(arc
							(start 0.2794 -0.1778)
							(mid 0.249642 -0.249642)
							(end 0.1778 -0.2794)
						)
					)
					(width 0)
					(fill yes)
				)
			)
		)
	)
	(footprint ""
		(layer "F.Cu")
		(at 361.315 -37.846 180)
		(property "Reference" "C433"
			(at 0 0 180)
			(layer "F.SilkS")
			(hide yes)
			(effects
				(font
					(size 1.27 1.27)
				)
			)
		)
		(property "Value" "SC1U16V3KX-5GP"
			(at 0 -2.8194 180)
			(unlocked yes)
			(layer "F.Fab")
			(hide yes)
			(effects
				(font
					(size 1.016 1.016)
					(thickness 0.1524)
				)
			)
		)
		(property "Device Type" "C603H36"
			(at 0 -4.3434 180)
			(unlocked yes)
			(layer "F.Fab")
			(hide yes)
			(effects
				(font
					(size 1.016 1.016)
					(thickness 0.1524)
				)
			)
		)
		(duplicate_pad_numbers_are_jumpers no)
		(fp_line
			(start 0.508 0)
			(end -0.508 0)
			(stroke
				(width 0.2032)
				(type default)
			)
			(layer "F.SilkS")
		)
		(fp_rect
			(start -0.5842 1.3335)
			(end 0.5842 -1.3335)
			(stroke
				(width 0)
				(type default)
			)
			(fill no)
			(layer "F.CrtYd")
		)
		(fp_rect
			(start -0.5842 1.3335)
			(end 0.5842 -1.3335)
			(stroke
				(width 0)
				(type default)
			)
			(fill no)
			(layer "F.Fab")
		)
		(pad "1" smd custom
			(at 0 -0.762 180)
			(size 0.2159 0.2159)
			(layers "F.Cu" "F.Mask" "F.Paste")
			(net "P5V_HDD31")
			(options
				(clearance outline)
				(anchor circle)
			)
			(primitives
				(gr_poly
					(pts
						(arc
							(start -0.3302 -0.4318)
							(mid -0.402042 -0.402042)
							(end -0.4318 -0.3302)
						)
						(arc
							(start -0.4318 0.3302)
							(mid -0.402042 0.402042)
							(end -0.3302 0.4318)
						)
						(arc
							(start 0.3302 0.4318)
							(mid 0.402042 0.402042)
							(end 0.4318 0.3302)
						)
						(arc
							(start 0.4318 -0.3302)
							(mid 0.402042 -0.402042)
							(end 0.3302 -0.4318)
						)
					)
					(width 0)
					(fill yes)
				)
			)
		)
		(pad "2" smd custom
			(at 0 0.762 180)
			(size 0.2159 0.2159)
			(layers "F.Cu" "F.Mask" "F.Paste")
			(net "GND")
			(options
				(clearance outline)
				(anchor circle)
			)
			(primitives
				(gr_poly
					(pts
						(arc
							(start -0.3302 -0.4318)
							(mid -0.402042 -0.402042)
							(end -0.4318 -0.3302)
						)
						(arc
							(start -0.4318 0.3302)
							(mid -0.402042 0.402042)
							(end -0.3302 0.4318)
						)
						(arc
							(start 0.3302 0.4318)
							(mid 0.402042 0.402042)
							(end 0.4318 0.3302)
						)
						(arc
							(start 0.4318 -0.3302)
							(mid 0.402042 -0.402042)
							(end 0.3302 -0.4318)
						)
					)
					(width 0)
					(fill yes)
				)
			)
		)
	)
	(footprint ""
		(layer "F.Cu")
		(at 127.113284 -244.660674 90)
		(property "Reference" "C68"
			(at 0 0 90)
			(layer "F.SilkS")
			(hide yes)
			(effects
				(font
					(size 1.27 1.27)
				)
			)
		)
		(property "Value" "SCD01U16V1KX-GP"
			(at -2.8321 -1.7399 90)
			(unlocked yes)
			(layer "F.Fab")
			(hide yes)
			(effects
				(font
					(size 1.016 1.016)
					(thickness 0.1524)
				)
			)
		)
		(property "Device Type" "C0201H13"
			(at -2.8321 -3.2639 90)
			(unlocked yes)
			(layer "F.Fab")
			(hide yes)
			(effects
				(font
					(size 1.016 1.016)
					(thickness 0.1524)
				)
			)
		)
		(duplicate_pad_numbers_are_jumpers no)
		(fp_rect
			(start -0.2794 0.6477)
			(end 0.2794 -0.6477)
			(stroke
				(width 0)
				(type default)
			)
			(fill no)
			(layer "F.CrtYd")
		)
		(fp_rect
			(start -0.2794 0.6477)
			(end 0.2794 -0.6477)
			(stroke
				(width 0)
				(type default)
			)
			(fill no)
			(layer "F.Fab")
		)
		(pad "1" smd custom
			(at 0 -0.2794 90)
			(size 0.0762 0.0762)
			(layers "F.Cu" "F.Mask" "F.Paste")
			(net "SAS_HDD_RX_P3")
			(options
				(clearance outline)
				(anchor circle)
			)
			(primitives
				(gr_poly
					(pts
						(arc
							(start 0.1524 -0.127)
							(mid 0.137521 -0.162921)
							(end 0.1016 -0.1778)
						)
						(arc
							(start -0.1016 -0.1778)
							(mid -0.137521 -0.162921)
							(end -0.1524 -0.127)
						)
						(arc
							(start -0.1524 0.127)
							(mid -0.137521 0.162921)
							(end -0.1016 0.1778)
						)
						(arc
							(start 0.1016 0.1778)
							(mid 0.137521 0.162921)
							(end 0.1524 0.127)
						)
					)
					(width 0)
					(fill yes)
				)
			)
		)
		(pad "2" smd custom
			(at 0 0.2794 90)
			(size 0.0762 0.0762)
			(layers "F.Cu" "F.Mask" "F.Paste")
			(net "PHY_SCC_B_TO_DRV_B_3_DP")
			(options
				(clearance outline)
				(anchor circle)
			)
			(primitives
				(gr_poly
					(pts
						(arc
							(start 0.1524 -0.127)
							(mid 0.137521 -0.162921)
							(end 0.1016 -0.1778)
						)
						(arc
							(start -0.1016 -0.1778)
							(mid -0.137521 -0.162921)
							(end -0.1524 -0.127)
						)
						(arc
							(start -0.1524 0.127)
							(mid -0.137521 0.162921)
							(end -0.1016 0.1778)
						)
						(arc
							(start 0.1016 0.1778)
							(mid 0.137521 0.162921)
							(end 0.1524 0.127)
						)
					)
					(width 0)
					(fill yes)
				)
			)
		)
	)
	(footprint ""
		(layer "F.Cu")
		(at 22.987 -249.555 90)
		(property "Reference" "R910"
			(at 0 0 90)
			(layer "F.SilkS")
			(hide yes)
			(effects
				(font
					(size 1.27 1.27)
				)
			)
		)
		(property "Value" "4K7R2F-GP"
			(at 0.064008 -3.993896 90)
			(unlocked yes)
			(layer "F.Fab")
			(hide yes)
			(effects
				(font
					(size 1.016 1.016)
					(thickness 0.1524)
				)
			)
		)
		(property "Device Type" "R402H16"
			(at 0.064008 -5.517896 90)
			(unlocked yes)
			(layer "F.Fab")
			(hide yes)
			(effects
				(font
					(size 1.016 1.016)
					(thickness 0.1524)
				)
			)
		)
		(duplicate_pad_numbers_are_jumpers no)
		(fp_line
			(start 0.508 -0.9398)
			(end -0.508 -0.9398)
			(stroke
				(width 0.1524)
				(type default)
			)
			(layer "F.SilkS")
		)
		(fp_line
			(start -0.508 -0.9398)
			(end -0.508 0.9398)
			(stroke
				(width 0.1524)
				(type default)
			)
			(layer "F.SilkS")
		)
		(fp_rect
			(start -0.508 0.9398)
			(end 0.508 -0.9398)
			(stroke
				(width 0)
				(type default)
			)
			(fill no)
			(layer "F.CrtYd")
		)
		(fp_rect
			(start -0.508 0.9398)
			(end 0.508 -0.9398)
			(stroke
				(width 0)
				(type default)
			)
			(fill no)
			(layer "F.Fab")
		)
		(pad "1" smd custom
			(at 0 -0.4445 90)
			(size 0.1397 0.1397)
			(layers "F.Cu" "F.Mask" "F.Paste")
			(net "SW_PWR_R_HDD0")
			(options
				(clearance outline)
				(anchor circle)
			)
			(primitives
				(gr_poly
					(pts
						(arc
							(start -0.1778 -0.2794)
							(mid -0.249642 -0.249642)
							(end -0.2794 -0.1778)
						)
						(arc
							(start -0.2794 0.1778)
							(mid -0.249642 0.249642)
							(end -0.1778 0.2794)
						)
						(arc
							(start 0.1778 0.2794)
							(mid 0.249642 0.249642)
							(end 0.2794 0.1778)
						)
						(arc
							(start 0.2794 -0.1778)
							(mid 0.249642 -0.249642)
							(end 0.1778 -0.2794)
						)
					)
					(width 0)
					(fill yes)
				)
			)
		)
		(pad "2" smd custom
			(at 0 0.4445 90)
			(size 0.1397 0.1397)
			(layers "F.Cu" "F.Mask" "F.Paste")
			(net "GND")
			(options
				(clearance outline)
				(anchor circle)
			)
			(primitives
				(gr_poly
					(pts
						(arc
							(start -0.1778 -0.2794)
							(mid -0.249642 -0.249642)
							(end -0.2794 -0.1778)
						)
						(arc
							(start -0.2794 0.1778)
							(mid -0.249642 0.249642)
							(end -0.1778 0.2794)
						)
						(arc
							(start 0.1778 0.2794)
							(mid 0.249642 0.249642)
							(end 0.2794 0.1778)
						)
						(arc
							(start 0.2794 -0.1778)
							(mid 0.249642 -0.249642)
							(end 0.1778 -0.2794)
						)
					)
					(width 0)
					(fill yes)
				)
			)
		)
	)
	(footprint ""
		(layer "F.Cu")
		(at 269.80007 -378.000006 90)
		(property "Reference" "Q208"
			(at 0 0 90)
			(layer "F.SilkS")
			(hide yes)
			(effects
				(font
					(size 1.27 1.27)
				)
			)
		)
		(property "Value" "SENSOR-2P-10-GP"
			(at -0.0127 -6.0325 90)
			(unlocked yes)
			(layer "F.Fab")
			(hide yes)
			(effects
				(font
					(size 1.016 1.016)
					(thickness 0.1524)
				)
			)
		)
		(property "Device Type" "SNR2N4036H168"
			(at -0.0127 -7.5565 90)
			(unlocked yes)
			(layer "F.Fab")
			(hide yes)
			(effects
				(font
					(size 1.016 1.016)
					(thickness 0.1524)
				)
			)
		)
		(duplicate_pad_numbers_are_jumpers no)
		(fp_line
			(start 2.2479 -2.1336)
			(end 2.2479 2.0574)
			(stroke
				(width 0.1524)
				(type default)
			)
			(layer "F.SilkS")
		)
		(fp_line
			(start -2.2479 -2.1336)
			(end 2.2479 -2.1336)
			(stroke
				(width 0.1524)
				(type default)
			)
			(layer "F.SilkS")
		)
		(fp_line
			(start 2.2479 2.0574)
			(end -2.2479 2.0574)
			(stroke
				(width 0.1524)
				(type default)
			)
			(layer "F.SilkS")
		)
		(fp_line
			(start -2.2479 2.0574)
			(end -2.2479 -2.1336)
			(stroke
				(width 0.1524)
				(type default)
			)
			(layer "F.SilkS")
		)
		(fp_poly
			(pts
				(xy -1.8796 -2.7178) (xy -1.8796 -2.2098) (xy -1.3716 -2.2098) (xy -1.3716 -2.7178)
			)
			(stroke
				(width 0)
				(type default)
			)
			(fill yes)
			(layer "F.SilkS")
		)
		(fp_rect
			(start -1.9939 1.8034)
			(end 1.9939 -1.8034)
			(stroke
				(width 0)
				(type default)
			)
			(fill no)
			(layer "F.CrtYd")
		)
		(fp_poly
			(pts
				(xy -2.5019 2.3114) (xy -2.5019 -2.3876) (xy 2.5019 -2.3876) (xy 2.5019 -0.4445) (xy 1.9939 -0.4445)
				(xy 1.9939 -1.8034) (xy -1.9939 -1.8034) (xy -1.9939 1.8034) (xy 1.9939 1.8034) (xy 1.9939 -0.4318)
				(xy 2.5019 -0.4318) (xy 2.5019 2.3114)
			)
			(stroke
				(width 0)
				(type default)
			)
			(fill no)
			(layer "F.CrtYd")
		)
		(fp_rect
			(start -2.5019 2.3114)
			(end 2.5019 -2.3876)
			(stroke
				(width 0)
				(type default)
			)
			(fill no)
			(layer "F.Fab")
		)
		(fp_text user "E"
			(at 2.466594 -0.28067 90)
			(unlocked yes)
			(layer "F.SilkS")
			(effects
				(font
					(size 1.016 1.016)
					(thickness 0.1524)
				)
				(justify left)
			)
		)
		(fp_text user "C"
			(at -3.426206 -0.20447 90)
			(unlocked yes)
			(layer "F.SilkS")
			(effects
				(font
					(size 1.016 1.016)
					(thickness 0.1524)
				)
				(justify left)
			)
		)
		(pad "C" smd rect
			(at -1.27 -0.374904 90)
			(size 1.1938 2.9972)
			(layers "F.Cu" "F.Mask" "F.Paste")
			(net "IR_SWITCH_C")
		)
		(pad "E" smd rect
			(at 1.27 -0.374904 90)
			(size 1.1938 2.9972)
			(layers "F.Cu" "F.Mask" "F.Paste")
			(net "IR_SWITCH_E")
		)
	)
	(footprint ""
		(layer "F.Cu")
		(at 362.966 -44.958 180)
		(property "Reference" "C437"
			(at 0 0 180)
			(layer "F.SilkS")
			(hide yes)
			(effects
				(font
					(size 1.27 1.27)
				)
			)
		)
		(property "Value" "SC4D7U25V5KX-1-GP"
			(at -0.0762 -6.1214 180)
			(unlocked yes)
			(layer "F.Fab")
			(hide yes)
			(effects
				(font
					(size 1.016 1.016)
					(thickness 0.1524)
				)
			)
		)
		(property "Device Type" "C805H58"
			(at -0.0762 -8.1534 180)
			(unlocked yes)
			(layer "F.Fab")
			(hide yes)
			(effects
				(font
					(size 1.016 1.016)
					(thickness 0.1524)
				)
			)
		)
		(duplicate_pad_numbers_are_jumpers no)
		(fp_line
			(start 0.635 0)
			(end -0.635 0)
			(stroke
				(width 0.508)
				(type default)
			)
			(layer "F.SilkS")
		)
		(fp_rect
			(start -0.9652 1.778)
			(end 0.9652 -1.778)
			(stroke
				(width 0)
				(type default)
			)
			(fill no)
			(layer "F.CrtYd")
		)
		(fp_poly
			(pts
				(xy -0.9652 -1.778) (xy 0.9652 -1.778) (xy 0.9652 1.778) (xy -0.9652 1.778)
			)
			(stroke
				(width 0)
				(type default)
			)
			(fill no)
			(layer "F.Fab")
		)
		(pad "1" smd rect
			(at 0 -0.9652 180)
			(size 1.397 1.143)
			(layers "F.Cu" "F.Mask" "F.Paste")
			(net "P12V_HDD31")
		)
		(pad "2" smd rect
			(at 0 0.9652 180)
			(size 1.397 1.143)
			(layers "F.Cu" "F.Mask" "F.Paste")
			(net "GND")
		)
	)
	(footprint ""
		(layer "F.Cu")
		(at 231.267 -196.596 -90)
		(property "Reference" "R76"
			(at 0 0 270)
			(layer "F.SilkS")
			(hide yes)
			(effects
				(font
					(size 1.27 1.27)
				)
			)
		)
		(property "Value" "0R2J-2-GP"
			(at 0.064008 -3.993896 270)
			(unlocked yes)
			(layer "F.Fab")
			(hide yes)
			(effects
				(font
					(size 1.016 1.016)
					(thickness 0.1524)
				)
			)
		)
		(property "Device Type" "R402H16"
			(at 0.064008 -5.517896 270)
			(unlocked yes)
			(layer "F.Fab")
			(hide yes)
			(effects
				(font
					(size 1.016 1.016)
					(thickness 0.1524)
				)
			)
		)
		(duplicate_pad_numbers_are_jumpers no)
		(fp_line
			(start -0.508 -0.9398)
			(end -0.508 0.9398)
			(stroke
				(width 0.1524)
				(type default)
			)
			(layer "F.SilkS")
		)
		(fp_line
			(start 0.508 -0.9398)
			(end -0.508 -0.9398)
			(stroke
				(width 0.1524)
				(type default)
			)
			(layer "F.SilkS")
		)
		(fp_rect
			(start -0.508 0.9398)
			(end 0.508 -0.9398)
			(stroke
				(width 0)
				(type default)
			)
			(fill no)
			(layer "F.CrtYd")
		)
		(fp_rect
			(start -0.508 0.9398)
			(end 0.508 -0.9398)
			(stroke
				(width 0)
				(type default)
			)
			(fill no)
			(layer "F.Fab")
		)
		(pad "1" smd custom
			(at 0 -0.4445 270)
			(size 0.1397 0.1397)
			(layers "F.Cu" "F.Mask" "F.Paste")
			(net "IO_EXP2_SCL")
			(options
				(clearance outline)
				(anchor circle)
			)
			(primitives
				(gr_poly
					(pts
						(arc
							(start -0.1778 -0.2794)
							(mid -0.249642 -0.249642)
							(end -0.2794 -0.1778)
						)
						(arc
							(start -0.2794 0.1778)
							(mid -0.249642 0.249642)
							(end -0.1778 0.2794)
						)
						(arc
							(start 0.1778 0.2794)
							(mid 0.249642 0.249642)
							(end 0.2794 0.1778)
						)
						(arc
							(start 0.2794 -0.1778)
							(mid 0.249642 -0.249642)
							(end 0.1778 -0.2794)
						)
					)
					(width 0)
					(fill yes)
				)
			)
		)
		(pad "2" smd custom
			(at 0 0.4445 270)
			(size 0.1397 0.1397)
			(layers "F.Cu" "F.Mask" "F.Paste")
			(net "I2C_DRIVE_B_PWR_SCL")
			(options
				(clearance outline)
				(anchor circle)
			)
			(primitives
				(gr_poly
					(pts
						(arc
							(start -0.1778 -0.2794)
							(mid -0.249642 -0.249642)
							(end -0.2794 -0.1778)
						)
						(arc
							(start -0.2794 0.1778)
							(mid -0.249642 0.249642)
							(end -0.1778 0.2794)
						)
						(arc
							(start 0.1778 0.2794)
							(mid 0.249642 0.249642)
							(end 0.2794 0.1778)
						)
						(arc
							(start 0.2794 -0.1778)
							(mid 0.249642 -0.249642)
							(end 0.1778 -0.2794)
						)
					)
					(width 0)
					(fill yes)
				)
			)
		)
	)
	(footprint ""
		(layer "F.Cu")
		(at 459.7908 -270.5862 -90)
		(property "Reference" "R320"
			(at 0 0 270)
			(layer "F.SilkS")
			(hide yes)
			(effects
				(font
					(size 1.27 1.27)
				)
			)
		)
		(property "Value" "2R6F-GP"
			(at -0.0508 -4.8514 270)
			(unlocked yes)
			(layer "F.Fab")
			(hide yes)
			(effects
				(font
					(size 1.016 1.016)
					(thickness 0.1524)
				)
			)
		)
		(property "Device Type" "R1206H26"
			(at 0 -6.3754 270)
			(unlocked yes)
			(layer "F.Fab")
			(hide yes)
			(effects
				(font
					(size 1.016 1.016)
					(thickness 0.1524)
				)
			)
		)
		(duplicate_pad_numbers_are_jumpers no)
		(fp_line
			(start -1.016 2.2352)
			(end -1.016 -2.2352)
			(stroke
				(width 0.1524)
				(type default)
			)
			(layer "F.SilkS")
		)
		(fp_line
			(start 1.016 2.2352)
			(end -1.016 2.2352)
			(stroke
				(width 0.1524)
				(type default)
			)
			(layer "F.SilkS")
		)
		(fp_line
			(start -1.016 -2.2352)
			(end 1.016 -2.2352)
			(stroke
				(width 0.1524)
				(type default)
			)
			(layer "F.SilkS")
		)
		(fp_line
			(start 1.016 -2.2352)
			(end 1.016 2.2352)
			(stroke
				(width 0.1524)
				(type default)
			)
			(layer "F.SilkS")
		)
		(fp_rect
			(start -1.0922 2.3114)
			(end 1.0922 -2.3114)
			(stroke
				(width 0)
				(type default)
			)
			(fill no)
			(layer "F.CrtYd")
		)
		(fp_poly
			(pts
				(xy -1.0922 -2.3114) (xy 1.0922 -2.3114) (xy 1.0922 2.3114) (xy -1.0922 2.3114)
			)
			(stroke
				(width 0)
				(type default)
			)
			(fill no)
			(layer "F.Fab")
		)
		(pad "1" smd rect
			(at 0 -1.397 270)
			(size 1.651 1.27)
			(layers "F.Cu" "F.Mask" "F.Paste")
			(net "P12V_HDD10")
		)
		(pad "2" smd rect
			(at 0 1.397 270)
			(size 1.651 1.27)
			(layers "F.Cu" "F.Mask" "F.Paste")
			(net "12V_PRE_10")
		)
	)
	(footprint ""
		(layer "F.Cu")
		(at 79.883 -138.049 90)
		(property "Reference" "R399"
			(at 0 0 90)
			(layer "F.SilkS")
			(hide yes)
			(effects
				(font
					(size 1.27 1.27)
				)
			)
		)
		(property "Value" "4K7R2J-2-GP"
			(at 0.064008 -3.993896 90)
			(unlocked yes)
			(layer "F.Fab")
			(hide yes)
			(effects
				(font
					(size 1.016 1.016)
					(thickness 0.1524)
				)
			)
		)
		(property "Device Type" "R402H16"
			(at 0.064008 -5.517896 90)
			(unlocked yes)
			(layer "F.Fab")
			(hide yes)
			(effects
				(font
					(size 1.016 1.016)
					(thickness 0.1524)
				)
			)
		)
		(duplicate_pad_numbers_are_jumpers no)
		(fp_line
			(start 0.508 -0.9398)
			(end -0.508 -0.9398)
			(stroke
				(width 0.1524)
				(type default)
			)
			(layer "F.SilkS")
		)
		(fp_line
			(start -0.508 -0.9398)
			(end -0.508 0.9398)
			(stroke
				(width 0.1524)
				(type default)
			)
			(layer "F.SilkS")
		)
		(fp_rect
			(start -0.508 0.9398)
			(end 0.508 -0.9398)
			(stroke
				(width 0)
				(type default)
			)
			(fill no)
			(layer "F.CrtYd")
		)
		(fp_rect
			(start -0.508 0.9398)
			(end 0.508 -0.9398)
			(stroke
				(width 0)
				(type default)
			)
			(fill no)
			(layer "F.Fab")
		)
		(pad "1" smd custom
			(at 0 -0.4445 90)
			(size 0.1397 0.1397)
			(layers "F.Cu" "F.Mask" "F.Paste")
			(net "P12V_B")
			(options
				(clearance outline)
				(anchor circle)
			)
			(primitives
				(gr_poly
					(pts
						(arc
							(start -0.1778 -0.2794)
							(mid -0.249642 -0.249642)
							(end -0.2794 -0.1778)
						)
						(arc
							(start -0.2794 0.1778)
							(mid -0.249642 0.249642)
							(end -0.1778 0.2794)
						)
						(arc
							(start 0.1778 0.2794)
							(mid 0.249642 0.249642)
							(end 0.2794 0.1778)
						)
						(arc
							(start 0.2794 -0.1778)
							(mid 0.249642 -0.249642)
							(end 0.1778 -0.2794)
						)
					)
					(width 0)
					(fill yes)
				)
			)
		)
		(pad "2" smd custom
			(at 0 0.4445 90)
			(size 0.1397 0.1397)
			(layers "F.Cu" "F.Mask" "F.Paste")
			(net "SW_HDD_P14")
			(options
				(clearance outline)
				(anchor circle)
			)
			(primitives
				(gr_poly
					(pts
						(arc
							(start -0.1778 -0.2794)
							(mid -0.249642 -0.249642)
							(end -0.2794 -0.1778)
						)
						(arc
							(start -0.2794 0.1778)
							(mid -0.249642 0.249642)
							(end -0.1778 0.2794)
						)
						(arc
							(start 0.1778 0.2794)
							(mid 0.249642 0.249642)
							(end 0.2794 0.1778)
						)
						(arc
							(start 0.2794 -0.1778)
							(mid 0.249642 -0.249642)
							(end 0.1778 -0.2794)
						)
					)
					(width 0)
					(fill yes)
				)
			)
		)
	)
	(footprint ""
		(layer "F.Cu")
		(at 129.921 -263.144 -90)
		(property "Reference" "R207"
			(at 0 0 270)
			(layer "F.SilkS")
			(hide yes)
			(effects
				(font
					(size 1.27 1.27)
				)
			)
		)
		(property "Value" "10KR2F-2-GP"
			(at 0.064008 -3.993896 270)
			(unlocked yes)
			(layer "F.Fab")
			(hide yes)
			(effects
				(font
					(size 1.016 1.016)
					(thickness 0.1524)
				)
			)
		)
		(property "Device Type" "R402H16"
			(at 0.064008 -5.517896 270)
			(unlocked yes)
			(layer "F.Fab")
			(hide yes)
			(effects
				(font
					(size 1.016 1.016)
					(thickness 0.1524)
				)
			)
		)
		(duplicate_pad_numbers_are_jumpers no)
		(fp_line
			(start -0.508 -0.9398)
			(end -0.508 0.9398)
			(stroke
				(width 0.1524)
				(type default)
			)
			(layer "F.SilkS")
		)
		(fp_line
			(start 0.508 -0.9398)
			(end -0.508 -0.9398)
			(stroke
				(width 0.1524)
				(type default)
			)
			(layer "F.SilkS")
		)
		(fp_rect
			(start -0.508 0.9398)
			(end 0.508 -0.9398)
			(stroke
				(width 0)
				(type default)
			)
			(fill no)
			(layer "F.CrtYd")
		)
		(fp_rect
			(start -0.508 0.9398)
			(end 0.508 -0.9398)
			(stroke
				(width 0)
				(type default)
			)
			(fill no)
			(layer "F.Fab")
		)
		(pad "1" smd custom
			(at 0 -0.4445 270)
			(size 0.1397 0.1397)
			(layers "F.Cu" "F.Mask" "F.Paste")
			(net "P3V3_STBY_B")
			(options
				(clearance outline)
				(anchor circle)
			)
			(primitives
				(gr_poly
					(pts
						(arc
							(start -0.1778 -0.2794)
							(mid -0.249642 -0.249642)
							(end -0.2794 -0.1778)
						)
						(arc
							(start -0.2794 0.1778)
							(mid -0.249642 0.249642)
							(end -0.1778 0.2794)
						)
						(arc
							(start 0.1778 0.2794)
							(mid 0.249642 0.249642)
							(end 0.2794 0.1778)
						)
						(arc
							(start 0.2794 -0.1778)
							(mid 0.249642 -0.249642)
							(end 0.1778 -0.2794)
						)
					)
					(width 0)
					(fill yes)
				)
			)
		)
		(pad "2" smd custom
			(at 0 0.4445 270)
			(size 0.1397 0.1397)
			(layers "F.Cu" "F.Mask" "F.Paste")
			(net "HDD_PRSNT_3")
			(options
				(clearance outline)
				(anchor circle)
			)
			(primitives
				(gr_poly
					(pts
						(arc
							(start -0.1778 -0.2794)
							(mid -0.249642 -0.249642)
							(end -0.2794 -0.1778)
						)
						(arc
							(start -0.2794 0.1778)
							(mid -0.249642 0.249642)
							(end -0.1778 0.2794)
						)
						(arc
							(start 0.1778 0.2794)
							(mid 0.249642 0.249642)
							(end 0.2794 0.1778)
						)
						(arc
							(start 0.2794 -0.1778)
							(mid 0.249642 -0.249642)
							(end 0.1778 -0.2794)
						)
					)
					(width 0)
					(fill yes)
				)
			)
		)
	)
	(footprint ""
		(layer "F.Cu")
		(at 331.4954 -135.636 -90)
		(property "Reference" "C272"
			(at 0 0 270)
			(layer "F.SilkS")
			(hide yes)
			(effects
				(font
					(size 1.27 1.27)
				)
			)
		)
		(property "Value" "SCD033U25V2KX-GP"
			(at 1.1811 -2.7051 270)
			(unlocked yes)
			(layer "F.Fab")
			(hide yes)
			(effects
				(font
					(size 1.016 1.016)
					(thickness 0.1524)
				)
			)
		)
		(property "Device Type" "C402H22"
			(at 1.1811 -4.2291 270)
			(unlocked yes)
			(layer "F.Fab")
			(hide yes)
			(effects
				(font
					(size 1.016 1.016)
					(thickness 0.1524)
				)
			)
		)
		(duplicate_pad_numbers_are_jumpers no)
		(fp_rect
			(start -0.4318 0.9525)
			(end 0.4318 -0.9525)
			(stroke
				(width 0)
				(type default)
			)
			(fill no)
			(layer "F.CrtYd")
		)
		(fp_rect
			(start -0.4318 0.9525)
			(end 0.4318 -0.9525)
			(stroke
				(width 0)
				(type default)
			)
			(fill no)
			(layer "F.Fab")
		)
		(pad "1" smd custom
			(at 0 -0.4445 270)
			(size 0.1524 0.1524)
			(layers "F.Cu" "F.Mask" "F.Paste")
			(net "SW_HDD_P18")
			(options
				(clearance outline)
				(anchor circle)
			)
			(primitives
				(gr_poly
					(pts
						(arc
							(start 0.3048 -0.2032)
							(mid 0.275042 -0.275042)
							(end 0.2032 -0.3048)
						)
						(arc
							(start -0.2032 -0.3048)
							(mid -0.275042 -0.275042)
							(end -0.3048 -0.2032)
						)
						(arc
							(start -0.3048 0.2032)
							(mid -0.275042 0.275042)
							(end -0.2032 0.3048)
						)
						(arc
							(start 0.2032 0.3048)
							(mid 0.275042 0.275042)
							(end 0.3048 0.2032)
						)
					)
					(width 0)
					(fill yes)
				)
			)
		)
		(pad "2" smd custom
			(at 0 0.4445 270)
			(size 0.1524 0.1524)
			(layers "F.Cu" "F.Mask" "F.Paste")
			(net "GND")
			(options
				(clearance outline)
				(anchor circle)
			)
			(primitives
				(gr_poly
					(pts
						(arc
							(start 0.3048 -0.2032)
							(mid 0.275042 -0.275042)
							(end 0.2032 -0.3048)
						)
						(arc
							(start -0.2032 -0.3048)
							(mid -0.275042 -0.275042)
							(end -0.3048 -0.2032)
						)
						(arc
							(start -0.3048 0.2032)
							(mid -0.275042 0.275042)
							(end -0.2032 0.3048)
						)
						(arc
							(start 0.2032 0.3048)
							(mid 0.275042 0.275042)
							(end 0.3048 0.2032)
						)
					)
					(width 0)
					(fill yes)
				)
			)
		)
	)
	(footprint ""
		(layer "F.Cu")
		(at 218.515692 -104.671368)
		(property "Reference" "R15"
			(at 0 0 0)
			(layer "F.SilkS")
			(hide yes)
			(effects
				(font
					(size 1.27 1.27)
				)
			)
		)
		(property "Value" "1KR2F-3-GP"
			(at 0.064008 -3.993896 0)
			(unlocked yes)
			(layer "F.Fab")
			(hide yes)
			(effects
				(font
					(size 1.016 1.016)
					(thickness 0.1524)
				)
			)
		)
		(property "Device Type" "R402H16"
			(at 0.064008 -5.517896 0)
			(unlocked yes)
			(layer "F.Fab")
			(hide yes)
			(effects
				(font
					(size 1.016 1.016)
					(thickness 0.1524)
				)
			)
		)
		(duplicate_pad_numbers_are_jumpers no)
		(fp_line
			(start -0.508 -0.9398)
			(end -0.508 0.9398)
			(stroke
				(width 0.1524)
				(type default)
			)
			(layer "F.SilkS")
		)
		(fp_line
			(start 0.508 -0.9398)
			(end -0.508 -0.9398)
			(stroke
				(width 0.1524)
				(type default)
			)
			(layer "F.SilkS")
		)
		(fp_rect
			(start -0.508 0.9398)
			(end 0.508 -0.9398)
			(stroke
				(width 0)
				(type default)
			)
			(fill no)
			(layer "F.CrtYd")
		)
		(fp_rect
			(start -0.508 0.9398)
			(end 0.508 -0.9398)
			(stroke
				(width 0)
				(type default)
			)
			(fill no)
			(layer "F.Fab")
		)
		(pad "1" smd custom
			(at 0 -0.4445)
			(size 0.1397 0.1397)
			(layers "F.Cu" "F.Mask" "F.Paste")
			(net "P3V3_STBY_B")
			(options
				(clearance outline)
				(anchor circle)
			)
			(primitives
				(gr_poly
					(pts
						(arc
							(start -0.1778 -0.2794)
							(mid -0.249642 -0.249642)
							(end -0.2794 -0.1778)
						)
						(arc
							(start -0.2794 0.1778)
							(mid -0.249642 0.249642)
							(end -0.1778 0.2794)
						)
						(arc
							(start 0.1778 0.2794)
							(mid 0.249642 0.249642)
							(end 0.2794 0.1778)
						)
						(arc
							(start 0.2794 -0.1778)
							(mid 0.249642 -0.249642)
							(end 0.1778 -0.2794)
						)
					)
					(width 0)
					(fill yes)
				)
			)
		)
		(pad "2" smd custom
			(at 0 0.4445)
			(size 0.1397 0.1397)
			(layers "F.Cu" "F.Mask" "F.Paste")
			(net "I2C_BMC_A_EXP_B_SDA")
			(options
				(clearance outline)
				(anchor circle)
			)
			(primitives
				(gr_poly
					(pts
						(arc
							(start -0.1778 -0.2794)
							(mid -0.249642 -0.249642)
							(end -0.2794 -0.1778)
						)
						(arc
							(start -0.2794 0.1778)
							(mid -0.249642 0.249642)
							(end -0.1778 0.2794)
						)
						(arc
							(start 0.1778 0.2794)
							(mid 0.249642 0.249642)
							(end 0.2794 0.1778)
						)
						(arc
							(start 0.2794 -0.1778)
							(mid 0.249642 -0.249642)
							(end 0.1778 -0.2794)
						)
					)
					(width 0)
					(fill yes)
				)
			)
		)
	)
	(footprint ""
		(layer "F.Cu")
		(at 286.639 -329.3618 -90)
		(property "Reference" "R162"
			(at 0 0 270)
			(layer "F.SilkS")
			(hide yes)
			(effects
				(font
					(size 1.27 1.27)
				)
			)
		)
		(property "Value" "4K7R2F-GP"
			(at 0.064008 -3.993896 270)
			(unlocked yes)
			(layer "F.Fab")
			(hide yes)
			(effects
				(font
					(size 1.016 1.016)
					(thickness 0.1524)
				)
			)
		)
		(property "Device Type" "R402H16"
			(at 0.064008 -5.517896 270)
			(unlocked yes)
			(layer "F.Fab")
			(hide yes)
			(effects
				(font
					(size 1.016 1.016)
					(thickness 0.1524)
				)
			)
		)
		(duplicate_pad_numbers_are_jumpers no)
		(fp_line
			(start -0.508 -0.9398)
			(end -0.508 0.9398)
			(stroke
				(width 0.1524)
				(type default)
			)
			(layer "F.SilkS")
		)
		(fp_line
			(start 0.508 -0.9398)
			(end -0.508 -0.9398)
			(stroke
				(width 0.1524)
				(type default)
			)
			(layer "F.SilkS")
		)
		(fp_rect
			(start -0.508 0.9398)
			(end 0.508 -0.9398)
			(stroke
				(width 0)
				(type default)
			)
			(fill no)
			(layer "F.CrtYd")
		)
		(fp_rect
			(start -0.508 0.9398)
			(end 0.508 -0.9398)
			(stroke
				(width 0)
				(type default)
			)
			(fill no)
			(layer "F.Fab")
		)
		(pad "1" smd custom
			(at 0 -0.4445 270)
			(size 0.1397 0.1397)
			(layers "F.Cu" "F.Mask" "F.Paste")
			(net "P3V3_IN")
			(options
				(clearance outline)
				(anchor circle)
			)
			(primitives
				(gr_poly
					(pts
						(arc
							(start -0.1778 -0.2794)
							(mid -0.249642 -0.249642)
							(end -0.2794 -0.1778)
						)
						(arc
							(start -0.2794 0.1778)
							(mid -0.249642 0.249642)
							(end -0.1778 0.2794)
						)
						(arc
							(start 0.1778 0.2794)
							(mid 0.249642 0.249642)
							(end 0.2794 0.1778)
						)
						(arc
							(start 0.2794 -0.1778)
							(mid 0.249642 -0.249642)
							(end 0.1778 -0.2794)
						)
					)
					(width 0)
					(fill yes)
				)
			)
		)
		(pad "2" smd custom
			(at 0 0.4445 270)
			(size 0.1397 0.1397)
			(layers "F.Cu" "F.Mask" "F.Paste")
			(net "PWM_OUT_D")
			(options
				(clearance outline)
				(anchor circle)
			)
			(primitives
				(gr_poly
					(pts
						(arc
							(start -0.1778 -0.2794)
							(mid -0.249642 -0.249642)
							(end -0.2794 -0.1778)
						)
						(arc
							(start -0.2794 0.1778)
							(mid -0.249642 0.249642)
							(end -0.1778 0.2794)
						)
						(arc
							(start 0.1778 0.2794)
							(mid 0.249642 0.249642)
							(end 0.2794 0.1778)
						)
						(arc
							(start 0.2794 -0.1778)
							(mid 0.249642 -0.249642)
							(end 0.1778 -0.2794)
						)
					)
					(width 0)
					(fill yes)
				)
			)
		)
	)
	(footprint ""
		(layer "F.Cu")
		(at 430.403 -131.826 180)
		(property "Reference" "R570"
			(at 0 0 180)
			(layer "F.SilkS")
			(hide yes)
			(effects
				(font
					(size 1.27 1.27)
				)
			)
		)
		(property "Value" "0R2J-2-GP"
			(at 0.064008 -3.993896 180)
			(unlocked yes)
			(layer "F.Fab")
			(hide yes)
			(effects
				(font
					(size 1.016 1.016)
					(thickness 0.1524)
				)
			)
		)
		(property "Device Type" "R402H16"
			(at 0.064008 -5.517896 180)
			(unlocked yes)
			(layer "F.Fab")
			(hide yes)
			(effects
				(font
					(size 1.016 1.016)
					(thickness 0.1524)
				)
			)
		)
		(duplicate_pad_numbers_are_jumpers no)
		(fp_line
			(start 0.508 -0.9398)
			(end -0.508 -0.9398)
			(stroke
				(width 0.1524)
				(type default)
			)
			(layer "F.SilkS")
		)
		(fp_line
			(start -0.508 -0.9398)
			(end -0.508 0.9398)
			(stroke
				(width 0.1524)
				(type default)
			)
			(layer "F.SilkS")
		)
		(fp_rect
			(start -0.508 0.9398)
			(end 0.508 -0.9398)
			(stroke
				(width 0)
				(type default)
			)
			(fill no)
			(layer "F.CrtYd")
		)
		(fp_rect
			(start -0.508 0.9398)
			(end 0.508 -0.9398)
			(stroke
				(width 0)
				(type default)
			)
			(fill no)
			(layer "F.Fab")
		)
		(pad "1" smd custom
			(at 0 -0.4445 180)
			(size 0.1397 0.1397)
			(layers "F.Cu" "F.Mask" "F.Paste")
			(net "SW_HDD_G21")
			(options
				(clearance outline)
				(anchor circle)
			)
			(primitives
				(gr_poly
					(pts
						(arc
							(start -0.1778 -0.2794)
							(mid -0.249642 -0.249642)
							(end -0.2794 -0.1778)
						)
						(arc
							(start -0.2794 0.1778)
							(mid -0.249642 0.249642)
							(end -0.1778 0.2794)
						)
						(arc
							(start 0.1778 0.2794)
							(mid 0.249642 0.249642)
							(end 0.2794 0.1778)
						)
						(arc
							(start 0.2794 -0.1778)
							(mid 0.249642 -0.249642)
							(end 0.1778 -0.2794)
						)
					)
					(width 0)
					(fill yes)
				)
			)
		)
		(pad "2" smd custom
			(at 0 0.4445 180)
			(size 0.1397 0.1397)
			(layers "F.Cu" "F.Mask" "F.Paste")
			(net "SW_HDD_R21")
			(options
				(clearance outline)
				(anchor circle)
			)
			(primitives
				(gr_poly
					(pts
						(arc
							(start -0.1778 -0.2794)
							(mid -0.249642 -0.249642)
							(end -0.2794 -0.1778)
						)
						(arc
							(start -0.2794 0.1778)
							(mid -0.249642 0.249642)
							(end -0.1778 0.2794)
						)
						(arc
							(start 0.1778 0.2794)
							(mid 0.249642 0.249642)
							(end 0.2794 0.1778)
						)
						(arc
							(start 0.2794 -0.1778)
							(mid 0.249642 -0.249642)
							(end 0.1778 -0.2794)
						)
					)
					(width 0)
					(fill yes)
				)
			)
		)
	)
	(footprint ""
		(layer "F.Cu")
		(at 251.572522 -360.146346 90)
		(property "Reference" "R1043"
			(at 0 0 90)
			(layer "F.SilkS")
			(hide yes)
			(effects
				(font
					(size 1.27 1.27)
				)
			)
		)
		(property "Value" "100KR2F-L1-GP"
			(at 0.064008 -3.993896 90)
			(unlocked yes)
			(layer "F.Fab")
			(hide yes)
			(effects
				(font
					(size 1.016 1.016)
					(thickness 0.1524)
				)
			)
		)
		(property "Device Type" "R402H16"
			(at 0.064008 -5.517896 90)
			(unlocked yes)
			(layer "F.Fab")
			(hide yes)
			(effects
				(font
					(size 1.016 1.016)
					(thickness 0.1524)
				)
			)
		)
		(duplicate_pad_numbers_are_jumpers no)
		(fp_line
			(start 0.508 -0.9398)
			(end -0.508 -0.9398)
			(stroke
				(width 0.1524)
				(type default)
			)
			(layer "F.SilkS")
		)
		(fp_line
			(start -0.508 -0.9398)
			(end -0.508 0.9398)
			(stroke
				(width 0.1524)
				(type default)
			)
			(layer "F.SilkS")
		)
		(fp_rect
			(start -0.508 0.9398)
			(end 0.508 -0.9398)
			(stroke
				(width 0)
				(type default)
			)
			(fill no)
			(layer "F.CrtYd")
		)
		(fp_rect
			(start -0.508 0.9398)
			(end 0.508 -0.9398)
			(stroke
				(width 0)
				(type default)
			)
			(fill no)
			(layer "F.Fab")
		)
		(pad "1" smd custom
			(at 0 -0.4445 90)
			(size 0.1397 0.1397)
			(layers "F.Cu" "F.Mask" "F.Paste")
			(net "MB3_VCAP_R")
			(options
				(clearance outline)
				(anchor circle)
			)
			(primitives
				(gr_poly
					(pts
						(arc
							(start -0.1778 -0.2794)
							(mid -0.249642 -0.249642)
							(end -0.2794 -0.1778)
						)
						(arc
							(start -0.2794 0.1778)
							(mid -0.249642 0.249642)
							(end -0.1778 0.2794)
						)
						(arc
							(start 0.1778 0.2794)
							(mid 0.249642 0.249642)
							(end 0.2794 0.1778)
						)
						(arc
							(start 0.2794 -0.1778)
							(mid 0.249642 -0.249642)
							(end 0.1778 -0.2794)
						)
					)
					(width 0)
					(fill yes)
				)
			)
		)
		(pad "2" smd custom
			(at 0 0.4445 90)
			(size 0.1397 0.1397)
			(layers "F.Cu" "F.Mask" "F.Paste")
			(net "MB3_ISET_R")
			(options
				(clearance outline)
				(anchor circle)
			)
			(primitives
				(gr_poly
					(pts
						(arc
							(start -0.1778 -0.2794)
							(mid -0.249642 -0.249642)
							(end -0.2794 -0.1778)
						)
						(arc
							(start -0.2794 0.1778)
							(mid -0.249642 0.249642)
							(end -0.1778 0.2794)
						)
						(arc
							(start 0.1778 0.2794)
							(mid 0.249642 0.249642)
							(end 0.2794 0.1778)
						)
						(arc
							(start 0.2794 -0.1778)
							(mid 0.249642 -0.249642)
							(end 0.1778 -0.2794)
						)
					)
					(width 0)
					(fill yes)
				)
			)
		)
	)
	(footprint ""
		(layer "F.Cu")
		(at 109.474 -260.858)
		(property "Reference" "Q12"
			(at 0 0 0)
			(layer "F.SilkS")
			(hide yes)
			(effects
				(font
					(size 1.27 1.27)
				)
			)
		)
		(property "Value" "AO4407AL-GP"
			(at -3.707384 -1.5367 0)
			(unlocked yes)
			(layer "F.Fab")
			(hide yes)
			(effects
				(font
					(size 1.016 1.016)
					(thickness 0.1524)
				)
			)
		)
		(property "Device Type" "SOIC8H69"
			(at -3.707384 -3.0607 0)
			(unlocked yes)
			(layer "F.Fab")
			(hide yes)
			(effects
				(font
					(size 1.016 1.016)
					(thickness 0.1524)
				)
			)
		)
		(duplicate_pad_numbers_are_jumpers no)
		(fp_line
			(start -2.7432 -1.4224)
			(end -2.7432 1.4224)
			(stroke
				(width 0.1524)
				(type default)
			)
			(layer "F.SilkS")
		)
		(fp_line
			(start -2.7432 1.4224)
			(end -2.6416 1.4224)
			(stroke
				(width 0.1524)
				(type default)
			)
			(layer "F.SilkS")
		)
		(fp_line
			(start -2.7432 1.4224)
			(end 2.1336 1.4224)
			(stroke
				(width 0.1524)
				(type default)
			)
			(layer "F.SilkS")
		)
		(fp_line
			(start -2.7178 -0.508)
			(end -2.1844 -0.0508)
			(stroke
				(width 0.1524)
				(type default)
			)
			(layer "F.SilkS")
		)
		(fp_line
			(start -2.6289 3.4417)
			(end -2.6289 1.4732)
			(stroke
				(width 0.381)
				(type default)
			)
			(layer "F.SilkS")
		)
		(fp_line
			(start -2.1844 -0.0508)
			(end -2.7178 0.508)
			(stroke
				(width 0.1524)
				(type default)
			)
			(layer "F.SilkS")
		)
		(fp_line
			(start 2.1336 -1.4224)
			(end -2.7432 -1.4224)
			(stroke
				(width 0.1524)
				(type default)
			)
			(layer "F.SilkS")
		)
		(fp_line
			(start 2.1336 1.4224)
			(end 2.1336 -1.4224)
			(stroke
				(width 0.1524)
				(type default)
			)
			(layer "F.SilkS")
		)
		(fp_poly
			(pts
				(xy -2.2098 -1.4224) (xy -2.2098 1.4224) (xy 2.2098 1.4224) (xy 2.2098 -1.4224)
			)
			(stroke
				(width 0)
				(type default)
			)
			(fill yes)
			(layer "F.SilkS")
		)
		(fp_rect
			(start -2.450084 2.999994)
			(end 2.450084 -2.999994)
			(stroke
				(width 0)
				(type default)
			)
			(fill no)
			(layer "F.CrtYd")
		)
		(fp_poly
			(pts
				(xy -2.8194 3.6322) (xy -2.8194 -3.6322) (xy 2.8194 -3.6322) (xy 2.8194 1.18364) (xy 2.450084 1.18364)
				(xy 2.450084 -2.999994) (xy -2.450084 -2.999994) (xy -2.450084 2.999994) (xy 2.450084 2.999994)
				(xy 2.450084 1.18618) (xy 2.8194 1.18618) (xy 2.8194 3.6322)
			)
			(stroke
				(width 0)
				(type default)
			)
			(fill no)
			(layer "F.CrtYd")
		)
		(fp_rect
			(start -2.8194 3.6322)
			(end 2.8194 -3.6322)
			(stroke
				(width 0)
				(type default)
			)
			(fill no)
			(layer "F.Fab")
		)
		(pad "1" smd rect
			(at -1.905 2.54)
			(size 0.635 1.651)
			(layers "F.Cu" "F.Mask" "F.Paste")
			(net "P12V_B")
		)
		(pad "2" smd rect
			(at -0.635 2.54)
			(size 0.635 1.651)
			(layers "F.Cu" "F.Mask" "F.Paste")
			(net "P12V_B")
		)
		(pad "3" smd rect
			(at 0.635 2.54)
			(size 0.635 1.651)
			(layers "F.Cu" "F.Mask" "F.Paste")
			(net "P12V_B")
		)
		(pad "4" smd rect
			(at 1.905 2.54)
			(size 0.635 1.651)
			(layers "F.Cu" "F.Mask" "F.Paste")
			(net "SW_HDD_N3")
		)
		(pad "5" smd rect
			(at 1.905 -2.54)
			(size 0.635 1.651)
			(layers "F.Cu" "F.Mask" "F.Paste")
			(net "P12V_HDD3")
		)
		(pad "6" smd rect
			(at 0.635 -2.54)
			(size 0.635 1.651)
			(layers "F.Cu" "F.Mask" "F.Paste")
			(net "P12V_HDD3")
		)
		(pad "7" smd rect
			(at -0.635 -2.54)
			(size 0.635 1.651)
			(layers "F.Cu" "F.Mask" "F.Paste")
			(net "P12V_HDD3")
		)
		(pad "8" smd rect
			(at -1.905 -2.54)
			(size 0.635 1.651)
			(layers "F.Cu" "F.Mask" "F.Paste")
			(net "P12V_HDD3")
		)
	)
	(footprint ""
		(layer "F.Cu")
		(at 78.359 -18.161 180)
		(property "Reference" "R684"
			(at 0 0 180)
			(layer "F.SilkS")
			(hide yes)
			(effects
				(font
					(size 1.27 1.27)
				)
			)
		)
		(property "Value" "200KR2F-L-GP"
			(at 0.064008 -3.993896 180)
			(unlocked yes)
			(layer "F.Fab")
			(hide yes)
			(effects
				(font
					(size 1.016 1.016)
					(thickness 0.1524)
				)
			)
		)
		(property "Device Type" "R402H16"
			(at 0.064008 -5.517896 180)
			(unlocked yes)
			(layer "F.Fab")
			(hide yes)
			(effects
				(font
					(size 1.016 1.016)
					(thickness 0.1524)
				)
			)
		)
		(duplicate_pad_numbers_are_jumpers no)
		(fp_line
			(start 0.508 -0.9398)
			(end -0.508 -0.9398)
			(stroke
				(width 0.1524)
				(type default)
			)
			(layer "F.SilkS")
		)
		(fp_line
			(start -0.508 -0.9398)
			(end -0.508 0.9398)
			(stroke
				(width 0.1524)
				(type default)
			)
			(layer "F.SilkS")
		)
		(fp_rect
			(start -0.508 0.9398)
			(end 0.508 -0.9398)
			(stroke
				(width 0)
				(type default)
			)
			(fill no)
			(layer "F.CrtYd")
		)
		(fp_rect
			(start -0.508 0.9398)
			(end 0.508 -0.9398)
			(stroke
				(width 0)
				(type default)
			)
			(fill no)
			(layer "F.Fab")
		)
		(pad "1" smd custom
			(at 0 -0.4445 180)
			(size 0.1397 0.1397)
			(layers "F.Cu" "F.Mask" "F.Paste")
			(net "SW_HDD_R26")
			(options
				(clearance outline)
				(anchor circle)
			)
			(primitives
				(gr_poly
					(pts
						(arc
							(start -0.1778 -0.2794)
							(mid -0.249642 -0.249642)
							(end -0.2794 -0.1778)
						)
						(arc
							(start -0.2794 0.1778)
							(mid -0.249642 0.249642)
							(end -0.1778 0.2794)
						)
						(arc
							(start 0.1778 0.2794)
							(mid 0.249642 0.249642)
							(end 0.2794 0.1778)
						)
						(arc
							(start 0.2794 -0.1778)
							(mid 0.249642 -0.249642)
							(end 0.1778 -0.2794)
						)
					)
					(width 0)
					(fill yes)
				)
			)
		)
		(pad "2" smd custom
			(at 0 0.4445 180)
			(size 0.1397 0.1397)
			(layers "F.Cu" "F.Mask" "F.Paste")
			(net "SW_HDD_N26")
			(options
				(clearance outline)
				(anchor circle)
			)
			(primitives
				(gr_poly
					(pts
						(arc
							(start -0.1778 -0.2794)
							(mid -0.249642 -0.249642)
							(end -0.2794 -0.1778)
						)
						(arc
							(start -0.2794 0.1778)
							(mid -0.249642 0.249642)
							(end -0.1778 0.2794)
						)
						(arc
							(start 0.1778 0.2794)
							(mid 0.249642 0.249642)
							(end 0.2794 0.1778)
						)
						(arc
							(start 0.2794 -0.1778)
							(mid 0.249642 -0.249642)
							(end 0.1778 -0.2794)
						)
					)
					(width 0)
					(fill yes)
				)
			)
		)
	)
	(footprint ""
		(layer "F.Cu")
		(at 67.183 -151.003 90)
		(property "Reference" "R373"
			(at 0 0 90)
			(layer "F.SilkS")
			(hide yes)
			(effects
				(font
					(size 1.27 1.27)
				)
			)
		)
		(property "Value" "220R3F-1-GP"
			(at -0.0254 -2.5146 90)
			(unlocked yes)
			(layer "F.Fab")
			(hide yes)
			(effects
				(font
					(size 1.016 1.016)
					(thickness 0.1524)
				)
			)
		)
		(property "Device Type" "R603H22"
			(at -0.0254 -4.0386 90)
			(unlocked yes)
			(layer "F.Fab")
			(hide yes)
			(effects
				(font
					(size 1.016 1.016)
					(thickness 0.1524)
				)
			)
		)
		(duplicate_pad_numbers_are_jumpers no)
		(fp_line
			(start 0.2032 0)
			(end 0.4826 0)
			(stroke
				(width 0.2032)
				(type default)
			)
			(layer "F.SilkS")
		)
		(fp_line
			(start -0.4826 0)
			(end -0.2032 0)
			(stroke
				(width 0.2032)
				(type default)
			)
			(layer "F.SilkS")
		)
		(fp_rect
			(start -0.5842 1.3335)
			(end 0.5842 -1.3335)
			(stroke
				(width 0)
				(type default)
			)
			(fill no)
			(layer "F.CrtYd")
		)
		(fp_rect
			(start -0.5842 1.3335)
			(end 0.5842 -1.3335)
			(stroke
				(width 0)
				(type default)
			)
			(fill no)
			(layer "F.Fab")
		)
		(pad "1" smd custom
			(at 0 -0.762 90)
			(size 0.2159 0.2159)
			(layers "F.Cu" "F.Mask" "F.Paste")
			(net "HDD_PRSNT_13")
			(options
				(clearance outline)
				(anchor circle)
			)
			(primitives
				(gr_poly
					(pts
						(arc
							(start -0.3302 -0.4318)
							(mid -0.402042 -0.402042)
							(end -0.4318 -0.3302)
						)
						(arc
							(start -0.4318 0.3302)
							(mid -0.402042 0.402042)
							(end -0.3302 0.4318)
						)
						(arc
							(start 0.3302 0.4318)
							(mid 0.402042 0.402042)
							(end 0.4318 0.3302)
						)
						(arc
							(start 0.4318 -0.3302)
							(mid 0.402042 -0.402042)
							(end 0.3302 -0.4318)
						)
					)
					(width 0)
					(fill yes)
				)
			)
		)
		(pad "2" smd custom
			(at 0 0.762 90)
			(size 0.2159 0.2159)
			(layers "F.Cu" "F.Mask" "F.Paste")
			(net "DRIVE_B_13_INS")
			(options
				(clearance outline)
				(anchor circle)
			)
			(primitives
				(gr_poly
					(pts
						(arc
							(start -0.3302 -0.4318)
							(mid -0.402042 -0.402042)
							(end -0.4318 -0.3302)
						)
						(arc
							(start -0.4318 0.3302)
							(mid -0.402042 0.402042)
							(end -0.3302 0.4318)
						)
						(arc
							(start 0.3302 0.4318)
							(mid 0.402042 0.402042)
							(end 0.4318 0.3302)
						)
						(arc
							(start 0.4318 -0.3302)
							(mid 0.402042 -0.402042)
							(end 0.3302 -0.4318)
						)
					)
					(width 0)
					(fill yes)
				)
			)
		)
	)
	(footprint ""
		(layer "F.Cu")
		(at 477.52 -20.701 90)
		(property "Reference" "C492"
			(at 0 0 90)
			(layer "F.SilkS")
			(hide yes)
			(effects
				(font
					(size 1.27 1.27)
				)
			)
		)
		(property "Value" "SCD01U50V2KX-1GP"
			(at 1.1811 -2.7051 90)
			(unlocked yes)
			(layer "F.Fab")
			(hide yes)
			(effects
				(font
					(size 1.016 1.016)
					(thickness 0.1524)
				)
			)
		)
		(property "Device Type" "C402H22"
			(at 1.1811 -4.2291 90)
			(unlocked yes)
			(layer "F.Fab")
			(hide yes)
			(effects
				(font
					(size 1.016 1.016)
					(thickness 0.1524)
				)
			)
		)
		(duplicate_pad_numbers_are_jumpers no)
		(fp_rect
			(start -0.4318 0.9525)
			(end 0.4318 -0.9525)
			(stroke
				(width 0)
				(type default)
			)
			(fill no)
			(layer "F.CrtYd")
		)
		(fp_rect
			(start -0.4318 0.9525)
			(end 0.4318 -0.9525)
			(stroke
				(width 0)
				(type default)
			)
			(fill no)
			(layer "F.Fab")
		)
		(pad "1" smd custom
			(at 0 -0.4445 90)
			(size 0.1524 0.1524)
			(layers "F.Cu" "F.Mask" "F.Paste")
			(net "HDD_PRSNT_35")
			(options
				(clearance outline)
				(anchor circle)
			)
			(primitives
				(gr_poly
					(pts
						(arc
							(start 0.3048 -0.2032)
							(mid 0.275042 -0.275042)
							(end 0.2032 -0.3048)
						)
						(arc
							(start -0.2032 -0.3048)
							(mid -0.275042 -0.275042)
							(end -0.3048 -0.2032)
						)
						(arc
							(start -0.3048 0.2032)
							(mid -0.275042 0.275042)
							(end -0.2032 0.3048)
						)
						(arc
							(start 0.2032 0.3048)
							(mid 0.275042 0.275042)
							(end 0.3048 0.2032)
						)
					)
					(width 0)
					(fill yes)
				)
			)
		)
		(pad "2" smd custom
			(at 0 0.4445 90)
			(size 0.1524 0.1524)
			(layers "F.Cu" "F.Mask" "F.Paste")
			(net "GND")
			(options
				(clearance outline)
				(anchor circle)
			)
			(primitives
				(gr_poly
					(pts
						(arc
							(start 0.3048 -0.2032)
							(mid 0.275042 -0.275042)
							(end 0.2032 -0.3048)
						)
						(arc
							(start -0.2032 -0.3048)
							(mid -0.275042 -0.275042)
							(end -0.3048 -0.2032)
						)
						(arc
							(start -0.3048 0.2032)
							(mid -0.275042 0.275042)
							(end -0.2032 0.3048)
						)
						(arc
							(start 0.2032 0.3048)
							(mid 0.275042 0.275042)
							(end 0.3048 0.2032)
						)
					)
					(width 0)
					(fill yes)
				)
			)
		)
	)
	(footprint ""
		(layer "F.Cu")
		(at 259.6515 -380.190756 90)
		(property "Reference" "R1064"
			(at 0 0 90)
			(layer "F.SilkS")
			(hide yes)
			(effects
				(font
					(size 1.27 1.27)
				)
			)
		)
		(property "Value" "100KR2F-L1-GP"
			(at 0.064008 -3.993896 90)
			(unlocked yes)
			(layer "F.Fab")
			(hide yes)
			(effects
				(font
					(size 1.016 1.016)
					(thickness 0.1524)
				)
			)
		)
		(property "Device Type" "R402H16"
			(at 0.064008 -5.517896 90)
			(unlocked yes)
			(layer "F.Fab")
			(hide yes)
			(effects
				(font
					(size 1.016 1.016)
					(thickness 0.1524)
				)
			)
		)
		(duplicate_pad_numbers_are_jumpers no)
		(fp_line
			(start 0.508 -0.9398)
			(end -0.508 -0.9398)
			(stroke
				(width 0.1524)
				(type default)
			)
			(layer "F.SilkS")
		)
		(fp_line
			(start -0.508 -0.9398)
			(end -0.508 0.9398)
			(stroke
				(width 0.1524)
				(type default)
			)
			(layer "F.SilkS")
		)
		(fp_rect
			(start -0.508 0.9398)
			(end 0.508 -0.9398)
			(stroke
				(width 0)
				(type default)
			)
			(fill no)
			(layer "F.CrtYd")
		)
		(fp_rect
			(start -0.508 0.9398)
			(end 0.508 -0.9398)
			(stroke
				(width 0)
				(type default)
			)
			(fill no)
			(layer "F.Fab")
		)
		(pad "1" smd custom
			(at 0 -0.4445 90)
			(size 0.1397 0.1397)
			(layers "F.Cu" "F.Mask" "F.Paste")
			(net "P3V3_IN")
			(options
				(clearance outline)
				(anchor circle)
			)
			(primitives
				(gr_poly
					(pts
						(arc
							(start -0.1778 -0.2794)
							(mid -0.249642 -0.249642)
							(end -0.2794 -0.1778)
						)
						(arc
							(start -0.2794 0.1778)
							(mid -0.249642 0.249642)
							(end -0.1778 0.2794)
						)
						(arc
							(start 0.1778 0.2794)
							(mid 0.249642 0.249642)
							(end 0.2794 0.1778)
						)
						(arc
							(start 0.2794 -0.1778)
							(mid 0.249642 -0.249642)
							(end 0.1778 -0.2794)
						)
					)
					(width 0)
					(fill yes)
				)
			)
		)
		(pad "2" smd custom
			(at 0 0.4445 90)
			(size 0.1397 0.1397)
			(layers "F.Cu" "F.Mask" "F.Paste")
			(net "DRAWER_OUT#_C")
			(options
				(clearance outline)
				(anchor circle)
			)
			(primitives
				(gr_poly
					(pts
						(arc
							(start -0.1778 -0.2794)
							(mid -0.249642 -0.249642)
							(end -0.2794 -0.1778)
						)
						(arc
							(start -0.2794 0.1778)
							(mid -0.249642 0.249642)
							(end -0.1778 0.2794)
						)
						(arc
							(start 0.1778 0.2794)
							(mid 0.249642 0.249642)
							(end 0.2794 0.1778)
						)
						(arc
							(start 0.2794 -0.1778)
							(mid 0.249642 -0.249642)
							(end 0.1778 -0.2794)
						)
					)
					(width 0)
					(fill yes)
				)
			)
		)
	)
	(footprint ""
		(layer "F.Cu")
		(at 273.5834 -332.61173 90)
		(property "Reference" "R89"
			(at 0 0 90)
			(layer "F.SilkS")
			(hide yes)
			(effects
				(font
					(size 1.27 1.27)
				)
			)
		)
		(property "Value" "4K7R2F-GP"
			(at 0.064008 -3.993896 90)
			(unlocked yes)
			(layer "F.Fab")
			(hide yes)
			(effects
				(font
					(size 1.016 1.016)
					(thickness 0.1524)
				)
			)
		)
		(property "Device Type" "R402H16"
			(at 0.064008 -5.517896 90)
			(unlocked yes)
			(layer "F.Fab")
			(hide yes)
			(effects
				(font
					(size 1.016 1.016)
					(thickness 0.1524)
				)
			)
		)
		(duplicate_pad_numbers_are_jumpers no)
		(fp_line
			(start 0.508 -0.9398)
			(end -0.508 -0.9398)
			(stroke
				(width 0.1524)
				(type default)
			)
			(layer "F.SilkS")
		)
		(fp_line
			(start -0.508 -0.9398)
			(end -0.508 0.9398)
			(stroke
				(width 0.1524)
				(type default)
			)
			(layer "F.SilkS")
		)
		(fp_rect
			(start -0.508 0.9398)
			(end 0.508 -0.9398)
			(stroke
				(width 0)
				(type default)
			)
			(fill no)
			(layer "F.CrtYd")
		)
		(fp_rect
			(start -0.508 0.9398)
			(end 0.508 -0.9398)
			(stroke
				(width 0)
				(type default)
			)
			(fill no)
			(layer "F.Fab")
		)
		(pad "1" smd custom
			(at 0 -0.4445 90)
			(size 0.1397 0.1397)
			(layers "F.Cu" "F.Mask" "F.Paste")
			(net "P3V3_IN")
			(options
				(clearance outline)
				(anchor circle)
			)
			(primitives
				(gr_poly
					(pts
						(arc
							(start -0.1778 -0.2794)
							(mid -0.249642 -0.249642)
							(end -0.2794 -0.1778)
						)
						(arc
							(start -0.2794 0.1778)
							(mid -0.249642 0.249642)
							(end -0.1778 0.2794)
						)
						(arc
							(start 0.1778 0.2794)
							(mid 0.249642 0.249642)
							(end 0.2794 0.1778)
						)
						(arc
							(start 0.2794 -0.1778)
							(mid 0.249642 -0.249642)
							(end 0.1778 -0.2794)
						)
					)
					(width 0)
					(fill yes)
				)
			)
		)
		(pad "2" smd custom
			(at 0 0.4445 90)
			(size 0.1397 0.1397)
			(layers "F.Cu" "F.Mask" "F.Paste")
			(net "PWM_OUT_C")
			(options
				(clearance outline)
				(anchor circle)
			)
			(primitives
				(gr_poly
					(pts
						(arc
							(start -0.1778 -0.2794)
							(mid -0.249642 -0.249642)
							(end -0.2794 -0.1778)
						)
						(arc
							(start -0.2794 0.1778)
							(mid -0.249642 0.249642)
							(end -0.1778 0.2794)
						)
						(arc
							(start 0.1778 0.2794)
							(mid 0.249642 0.249642)
							(end 0.2794 0.1778)
						)
						(arc
							(start 0.2794 -0.1778)
							(mid 0.249642 -0.249642)
							(end 0.1778 -0.2794)
						)
					)
					(width 0)
					(fill yes)
				)
			)
		)
	)
	(footprint ""
		(layer "F.Cu")
		(at 472.899994 -180.399944)
		(property "Reference" "LED12"
			(at 0 0 0)
			(layer "F.SilkS")
			(hide yes)
			(effects
				(font
					(size 1.27 1.27)
				)
			)
		)
		(property "Value" "LED-BY-19-GP"
			(at -2.132076 1.414018 0)
			(unlocked yes)
			(layer "F.Fab")
			(hide yes)
			(effects
				(font
					(size 1.016 1.016)
					(thickness 0.1524)
				)
			)
		)
		(property "Device Type" "LED-1615-4PH26"
			(at -2.132076 -0.109982 0)
			(unlocked yes)
			(layer "F.Fab")
			(hide yes)
			(effects
				(font
					(size 1.016 1.016)
					(thickness 0.1524)
				)
			)
		)
		(duplicate_pad_numbers_are_jumpers no)
		(fp_line
			(start -1.2954 0.254)
			(end -1.2954 1.6002)
			(stroke
				(width 0.508)
				(type default)
			)
			(layer "F.SilkS")
		)
		(fp_line
			(start -1.2954 1.6002)
			(end 1.2954 1.6002)
			(stroke
				(width 0.508)
				(type default)
			)
			(layer "F.SilkS")
		)
		(fp_line
			(start -1.1176 -1.4224)
			(end 1.1176 -1.4224)
			(stroke
				(width 0.1524)
				(type default)
			)
			(layer "F.SilkS")
		)
		(fp_line
			(start -1.1176 1.4224)
			(end -1.1176 -1.4224)
			(stroke
				(width 0.1524)
				(type default)
			)
			(layer "F.SilkS")
		)
		(fp_line
			(start 1.1176 -1.4224)
			(end 1.1176 1.4224)
			(stroke
				(width 0.1524)
				(type default)
			)
			(layer "F.SilkS")
		)
		(fp_line
			(start 1.1176 1.4224)
			(end -1.1176 1.4224)
			(stroke
				(width 0.1524)
				(type default)
			)
			(layer "F.SilkS")
		)
		(fp_line
			(start 1.2954 1.6002)
			(end 1.2954 0.254)
			(stroke
				(width 0.508)
				(type default)
			)
			(layer "F.SilkS")
		)
		(fp_rect
			(start -0.7493 0.8001)
			(end 0.7493 -0.8001)
			(stroke
				(width 0)
				(type default)
			)
			(fill no)
			(layer "F.CrtYd")
		)
		(fp_poly
			(pts
				(xy -1.3716 1.6764) (xy -1.3716 -1.6764) (xy 1.3716 -1.6764) (xy 1.3716 0.0635) (xy 0.7493 0.0635)
				(xy 0.7493 -0.8001) (xy -0.7493 -0.8001) (xy -0.7493 0.8001) (xy 0.7493 0.8001) (xy 0.7493 0.0762)
				(xy 1.3716 0.0762) (xy 1.3716 1.6764)
			)
			(stroke
				(width 0)
				(type default)
			)
			(fill no)
			(layer "F.CrtYd")
		)
		(fp_rect
			(start -1.3716 1.6764)
			(end 1.3716 -1.6764)
			(stroke
				(width 0)
				(type default)
			)
			(fill no)
			(layer "F.Fab")
		)
		(pad "1" smd rect
			(at 0.50038 -0.73025)
			(size 0.7112 0.8636)
			(layers "F.Cu" "F.Mask" "F.Paste")
			(net "DRV_ACT_11")
		)
		(pad "2" smd rect
			(at -0.50038 -0.73025)
			(size 0.7112 0.8636)
			(layers "F.Cu" "F.Mask" "F.Paste")
			(net "FLT_HDD11")
		)
		(pad "3" smd rect
			(at 0.50038 0.73025)
			(size 0.7112 0.8636)
			(layers "F.Cu" "F.Mask" "F.Paste")
			(net "DRV_ACT_11_N")
		)
		(pad "4" smd rect
			(at -0.50038 0.73025)
			(size 0.7112 0.8636)
			(layers "F.Cu" "F.Mask" "F.Paste")
			(net "FLT_HDD11_N")
		)
	)
	(footprint ""
		(layer "F.Cu")
		(at 109.65815 -217.337386 -90)
		(property "Reference" "R194"
			(at 0 0 270)
			(layer "F.SilkS")
			(hide yes)
			(effects
				(font
					(size 1.27 1.27)
				)
			)
		)
		(property "Value" "4K7R2F-GP"
			(at 0.064008 -3.993896 270)
			(unlocked yes)
			(layer "F.Fab")
			(hide yes)
			(effects
				(font
					(size 1.016 1.016)
					(thickness 0.1524)
				)
			)
		)
		(property "Device Type" "R402H16"
			(at 0.064008 -5.517896 270)
			(unlocked yes)
			(layer "F.Fab")
			(hide yes)
			(effects
				(font
					(size 1.016 1.016)
					(thickness 0.1524)
				)
			)
		)
		(duplicate_pad_numbers_are_jumpers no)
		(fp_line
			(start -0.508 -0.9398)
			(end -0.508 0.9398)
			(stroke
				(width 0.1524)
				(type default)
			)
			(layer "F.SilkS")
		)
		(fp_line
			(start 0.508 -0.9398)
			(end -0.508 -0.9398)
			(stroke
				(width 0.1524)
				(type default)
			)
			(layer "F.SilkS")
		)
		(fp_rect
			(start -0.508 0.9398)
			(end 0.508 -0.9398)
			(stroke
				(width 0)
				(type default)
			)
			(fill no)
			(layer "F.CrtYd")
		)
		(fp_rect
			(start -0.508 0.9398)
			(end 0.508 -0.9398)
			(stroke
				(width 0)
				(type default)
			)
			(fill no)
			(layer "F.Fab")
		)
		(pad "1" smd custom
			(at 0 -0.4445 270)
			(size 0.1397 0.1397)
			(layers "F.Cu" "F.Mask" "F.Paste")
			(net "DRIVE_B_3_FLT_LED")
			(options
				(clearance outline)
				(anchor circle)
			)
			(primitives
				(gr_poly
					(pts
						(arc
							(start -0.1778 -0.2794)
							(mid -0.249642 -0.249642)
							(end -0.2794 -0.1778)
						)
						(arc
							(start -0.2794 0.1778)
							(mid -0.249642 0.249642)
							(end -0.1778 0.2794)
						)
						(arc
							(start 0.1778 0.2794)
							(mid 0.249642 0.249642)
							(end 0.2794 0.1778)
						)
						(arc
							(start 0.2794 -0.1778)
							(mid 0.249642 -0.249642)
							(end 0.1778 -0.2794)
						)
					)
					(width 0)
					(fill yes)
				)
			)
		)
		(pad "2" smd custom
			(at 0 0.4445 270)
			(size 0.1397 0.1397)
			(layers "F.Cu" "F.Mask" "F.Paste")
			(net "GND")
			(options
				(clearance outline)
				(anchor circle)
			)
			(primitives
				(gr_poly
					(pts
						(arc
							(start -0.1778 -0.2794)
							(mid -0.249642 -0.249642)
							(end -0.2794 -0.1778)
						)
						(arc
							(start -0.2794 0.1778)
							(mid -0.249642 0.249642)
							(end -0.1778 0.2794)
						)
						(arc
							(start 0.1778 0.2794)
							(mid 0.249642 0.249642)
							(end 0.2794 0.1778)
						)
						(arc
							(start 0.2794 -0.1778)
							(mid 0.249642 -0.249642)
							(end 0.1778 -0.2794)
						)
					)
					(width 0)
					(fill yes)
				)
			)
		)
	)
	(footprint ""
		(layer "F.Cu")
		(at 469.9 -139.446 -90)
		(property "Reference" "R614"
			(at 0 0 270)
			(layer "F.SilkS")
			(hide yes)
			(effects
				(font
					(size 1.27 1.27)
				)
			)
		)
		(property "Value" "300KR2F-GP"
			(at 0.064008 -3.993896 270)
			(unlocked yes)
			(layer "F.Fab")
			(hide yes)
			(effects
				(font
					(size 1.016 1.016)
					(thickness 0.1524)
				)
			)
		)
		(property "Device Type" "R402H16"
			(at 0.064008 -5.517896 270)
			(unlocked yes)
			(layer "F.Fab")
			(hide yes)
			(effects
				(font
					(size 1.016 1.016)
					(thickness 0.1524)
				)
			)
		)
		(duplicate_pad_numbers_are_jumpers no)
		(fp_line
			(start -0.508 -0.9398)
			(end -0.508 0.9398)
			(stroke
				(width 0.1524)
				(type default)
			)
			(layer "F.SilkS")
		)
		(fp_line
			(start 0.508 -0.9398)
			(end -0.508 -0.9398)
			(stroke
				(width 0.1524)
				(type default)
			)
			(layer "F.SilkS")
		)
		(fp_rect
			(start -0.508 0.9398)
			(end 0.508 -0.9398)
			(stroke
				(width 0)
				(type default)
			)
			(fill no)
			(layer "F.CrtYd")
		)
		(fp_rect
			(start -0.508 0.9398)
			(end 0.508 -0.9398)
			(stroke
				(width 0)
				(type default)
			)
			(fill no)
			(layer "F.Fab")
		)
		(pad "1" smd custom
			(at 0 -0.4445 270)
			(size 0.1397 0.1397)
			(layers "F.Cu" "F.Mask" "F.Paste")
			(net "SW_HDD_N23")
			(options
				(clearance outline)
				(anchor circle)
			)
			(primitives
				(gr_poly
					(pts
						(arc
							(start -0.1778 -0.2794)
							(mid -0.249642 -0.249642)
							(end -0.2794 -0.1778)
						)
						(arc
							(start -0.2794 0.1778)
							(mid -0.249642 0.249642)
							(end -0.1778 0.2794)
						)
						(arc
							(start 0.1778 0.2794)
							(mid 0.249642 0.249642)
							(end 0.2794 0.1778)
						)
						(arc
							(start 0.2794 -0.1778)
							(mid 0.249642 -0.249642)
							(end 0.1778 -0.2794)
						)
					)
					(width 0)
					(fill yes)
				)
			)
		)
		(pad "2" smd custom
			(at 0 0.4445 270)
			(size 0.1397 0.1397)
			(layers "F.Cu" "F.Mask" "F.Paste")
			(net "P12V_B")
			(options
				(clearance outline)
				(anchor circle)
			)
			(primitives
				(gr_poly
					(pts
						(arc
							(start -0.1778 -0.2794)
							(mid -0.249642 -0.249642)
							(end -0.2794 -0.1778)
						)
						(arc
							(start -0.2794 0.1778)
							(mid -0.249642 0.249642)
							(end -0.1778 0.2794)
						)
						(arc
							(start 0.1778 0.2794)
							(mid 0.249642 0.249642)
							(end 0.2794 0.1778)
						)
						(arc
							(start 0.2794 -0.1778)
							(mid 0.249642 -0.249642)
							(end 0.1778 -0.2794)
						)
					)
					(width 0)
					(fill yes)
				)
			)
		)
	)
	(footprint ""
		(layer "F.Cu")
		(at 172.466 -150.622 -90)
		(property "Reference" "C254"
			(at 0 0 270)
			(layer "F.SilkS")
			(hide yes)
			(effects
				(font
					(size 1.27 1.27)
				)
			)
		)
		(property "Value" "SC4D7U25V5KX-1-GP"
			(at -0.0762 -6.1214 270)
			(unlocked yes)
			(layer "F.Fab")
			(hide yes)
			(effects
				(font
					(size 1.016 1.016)
					(thickness 0.1524)
				)
			)
		)
		(property "Device Type" "C805H58"
			(at -0.0762 -8.1534 270)
			(unlocked yes)
			(layer "F.Fab")
			(hide yes)
			(effects
				(font
					(size 1.016 1.016)
					(thickness 0.1524)
				)
			)
		)
		(duplicate_pad_numbers_are_jumpers no)
		(fp_line
			(start 0.635 0)
			(end -0.635 0)
			(stroke
				(width 0.508)
				(type default)
			)
			(layer "F.SilkS")
		)
		(fp_rect
			(start -0.9652 1.778)
			(end 0.9652 -1.778)
			(stroke
				(width 0)
				(type default)
			)
			(fill no)
			(layer "F.CrtYd")
		)
		(fp_poly
			(pts
				(xy -0.9652 -1.778) (xy 0.9652 -1.778) (xy 0.9652 1.778) (xy -0.9652 1.778)
			)
			(stroke
				(width 0)
				(type default)
			)
			(fill no)
			(layer "F.Fab")
		)
		(pad "1" smd rect
			(at 0 -0.9652 270)
			(size 1.397 1.143)
			(layers "F.Cu" "F.Mask" "F.Paste")
			(net "P12V_HDD17")
		)
		(pad "2" smd rect
			(at 0 0.9652 270)
			(size 1.397 1.143)
			(layers "F.Cu" "F.Mask" "F.Paste")
			(net "GND")
		)
	)
	(footprint ""
		(layer "F.Cu")
		(at 394.589 -274.955 180)
		(property "Reference" "C138"
			(at 0 0 180)
			(layer "F.SilkS")
			(hide yes)
			(effects
				(font
					(size 1.27 1.27)
				)
			)
		)
		(property "Value" "SC4D7U25V5KX-1-GP"
			(at -0.0762 -6.1214 180)
			(unlocked yes)
			(layer "F.Fab")
			(hide yes)
			(effects
				(font
					(size 1.016 1.016)
					(thickness 0.1524)
				)
			)
		)
		(property "Device Type" "C805H58"
			(at -0.0762 -8.1534 180)
			(unlocked yes)
			(layer "F.Fab")
			(hide yes)
			(effects
				(font
					(size 1.016 1.016)
					(thickness 0.1524)
				)
			)
		)
		(duplicate_pad_numbers_are_jumpers no)
		(fp_line
			(start 0.635 0)
			(end -0.635 0)
			(stroke
				(width 0.508)
				(type default)
			)
			(layer "F.SilkS")
		)
		(fp_rect
			(start -0.9652 1.778)
			(end 0.9652 -1.778)
			(stroke
				(width 0)
				(type default)
			)
			(fill no)
			(layer "F.CrtYd")
		)
		(fp_poly
			(pts
				(xy -0.9652 -1.778) (xy 0.9652 -1.778) (xy 0.9652 1.778) (xy -0.9652 1.778)
			)
			(stroke
				(width 0)
				(type default)
			)
			(fill no)
			(layer "F.Fab")
		)
		(pad "1" smd rect
			(at 0 -0.9652 180)
			(size 1.397 1.143)
			(layers "F.Cu" "F.Mask" "F.Paste")
			(net "P12V_HDD8")
		)
		(pad "2" smd rect
			(at 0 0.9652 180)
			(size 1.397 1.143)
			(layers "F.Cu" "F.Mask" "F.Paste")
			(net "GND")
		)
	)
	(footprint ""
		(layer "F.Cu")
		(at 190.258954 -133.75005 -90)
		(property "Reference" "VIA36"
			(at 0 0 270)
			(layer "F.SilkS")
			(hide yes)
			(effects
				(font
					(size 1.27 1.27)
				)
			)
		)
		(property "Value" "100OHM-8L-2D36MM-L16-GP"
			(at -3.4036 -0.4572 270)
			(unlocked yes)
			(layer "F.Fab")
			(hide yes)
			(effects
				(font
					(size 1.016 1.016)
					(thickness 0.1524)
				)
			)
		)
		(property "Device Type" "VIA-PCIE-4P-427097"
			(at -3.4036 -1.9812 270)
			(unlocked yes)
			(layer "F.Fab")
			(hide yes)
			(effects
				(font
					(size 1.016 1.016)
					(thickness 0.1524)
				)
			)
		)
		(duplicate_pad_numbers_are_jumpers no)
		(fp_rect
			(start -2.1336 0.4826)
			(end 2.1336 -0.4826)
			(stroke
				(width 0)
				(type default)
			)
			(fill no)
			(layer "F.CrtYd")
		)
		(fp_rect
			(start -2.1336 0.4826)
			(end 2.1336 -0.4826)
			(stroke
				(width 0)
				(type default)
			)
			(fill no)
			(layer "F.Fab")
		)
		(pad "1" thru_hole circle
			(at -1.651 0 270)
			(size 0.508 0.508)
			(drill 0.254)
			(layers "*.Cu" "*.Mask")
			(remove_unused_layers no)
			(net "GND")
			(clearance 0.2286)
			(thermal_gap 0.2286)
		)
		(pad "2" thru_hole circle
			(at -0.635 0 270)
			(size 0.508 0.508)
			(drill 0.254)
			(layers "*.Cu" "*.Mask")
			(remove_unused_layers no)
			(net "PHY_DRV_B_TO_SCC_B_17_DP")
			(clearance 0.2286)
			(thermal_gap 0.2286)
		)
		(pad "3" thru_hole circle
			(at 0.635 0 270)
			(size 0.508 0.508)
			(drill 0.254)
			(layers "*.Cu" "*.Mask")
			(remove_unused_layers no)
			(net "PHY_DRV_B_TO_SCC_B_17_DN")
			(clearance 0.2286)
			(thermal_gap 0.2286)
		)
		(pad "4" thru_hole circle
			(at 1.651 0 270)
			(size 0.508 0.508)
			(drill 0.254)
			(layers "*.Cu" "*.Mask")
			(remove_unused_layers no)
			(net "GND")
			(clearance 0.2286)
			(thermal_gap 0.2286)
		)
	)
	(footprint ""
		(layer "F.Cu")
		(at 321.634612 -130.21945 -90)
		(property "Reference" "C262"
			(at 0 0 270)
			(layer "F.SilkS")
			(hide yes)
			(effects
				(font
					(size 1.27 1.27)
				)
			)
		)
		(property "Value" "SCD01U16V1KX-GP"
			(at -2.8321 -1.7399 270)
			(unlocked yes)
			(layer "F.Fab")
			(hide yes)
			(effects
				(font
					(size 1.016 1.016)
					(thickness 0.1524)
				)
			)
		)
		(property "Device Type" "C0201H13"
			(at -2.8321 -3.2639 270)
			(unlocked yes)
			(layer "F.Fab")
			(hide yes)
			(effects
				(font
					(size 1.016 1.016)
					(thickness 0.1524)
				)
			)
		)
		(duplicate_pad_numbers_are_jumpers no)
		(fp_rect
			(start -0.2794 0.6477)
			(end 0.2794 -0.6477)
			(stroke
				(width 0)
				(type default)
			)
			(fill no)
			(layer "F.CrtYd")
		)
		(fp_rect
			(start -0.2794 0.6477)
			(end 0.2794 -0.6477)
			(stroke
				(width 0)
				(type default)
			)
			(fill no)
			(layer "F.Fab")
		)
		(pad "1" smd custom
			(at 0 -0.2794 270)
			(size 0.0762 0.0762)
			(layers "F.Cu" "F.Mask" "F.Paste")
			(net "SAS_HDD_RX_N18")
			(options
				(clearance outline)
				(anchor circle)
			)
			(primitives
				(gr_poly
					(pts
						(arc
							(start 0.1524 -0.127)
							(mid 0.137521 -0.162921)
							(end 0.1016 -0.1778)
						)
						(arc
							(start -0.1016 -0.1778)
							(mid -0.137521 -0.162921)
							(end -0.1524 -0.127)
						)
						(arc
							(start -0.1524 0.127)
							(mid -0.137521 0.162921)
							(end -0.1016 0.1778)
						)
						(arc
							(start 0.1016 0.1778)
							(mid 0.137521 0.162921)
							(end 0.1524 0.127)
						)
					)
					(width 0)
					(fill yes)
				)
			)
		)
		(pad "2" smd custom
			(at 0 0.2794 270)
			(size 0.0762 0.0762)
			(layers "F.Cu" "F.Mask" "F.Paste")
			(net "PHY_SCC_B_TO_DRV_B_18_DN")
			(options
				(clearance outline)
				(anchor circle)
			)
			(primitives
				(gr_poly
					(pts
						(arc
							(start 0.1524 -0.127)
							(mid 0.137521 -0.162921)
							(end 0.1016 -0.1778)
						)
						(arc
							(start -0.1016 -0.1778)
							(mid -0.137521 -0.162921)
							(end -0.1524 -0.127)
						)
						(arc
							(start -0.1524 0.127)
							(mid -0.137521 0.162921)
							(end -0.1016 0.1778)
						)
						(arc
							(start 0.1016 0.1778)
							(mid 0.137521 0.162921)
							(end 0.1524 0.127)
						)
					)
					(width 0)
					(fill yes)
				)
			)
		)
	)
	(footprint ""
		(layer "F.Cu")
		(at 449.5165 -132.437124)
		(property "Reference" "VIA46"
			(at 0 0 0)
			(layer "F.SilkS")
			(hide yes)
			(effects
				(font
					(size 1.27 1.27)
				)
			)
		)
		(property "Value" "100OHM-8L-2D36MM-L16-GP"
			(at -3.4036 -0.4572 0)
			(unlocked yes)
			(layer "F.Fab")
			(hide yes)
			(effects
				(font
					(size 1.016 1.016)
					(thickness 0.1524)
				)
			)
		)
		(property "Device Type" "VIA-PCIE-4P-427097"
			(at -3.4036 -1.9812 0)
			(unlocked yes)
			(layer "F.Fab")
			(hide yes)
			(effects
				(font
					(size 1.016 1.016)
					(thickness 0.1524)
				)
			)
		)
		(duplicate_pad_numbers_are_jumpers no)
		(fp_rect
			(start -2.1336 0.4826)
			(end 2.1336 -0.4826)
			(stroke
				(width 0)
				(type default)
			)
			(fill no)
			(layer "F.CrtYd")
		)
		(fp_rect
			(start -2.1336 0.4826)
			(end 2.1336 -0.4826)
			(stroke
				(width 0)
				(type default)
			)
			(fill no)
			(layer "F.Fab")
		)
		(pad "1" thru_hole circle
			(at -1.651 0)
			(size 0.508 0.508)
			(drill 0.254)
			(layers "*.Cu" "*.Mask")
			(remove_unused_layers no)
			(net "GND")
			(clearance 0.2286)
			(thermal_gap 0.2286)
		)
		(pad "2" thru_hole circle
			(at -0.635 0)
			(size 0.508 0.508)
			(drill 0.254)
			(layers "*.Cu" "*.Mask")
			(remove_unused_layers no)
			(net "PHY_DRV_B_TO_SCC_B_22_DP")
			(clearance 0.2286)
			(thermal_gap 0.2286)
		)
		(pad "3" thru_hole circle
			(at 0.635 0)
			(size 0.508 0.508)
			(drill 0.254)
			(layers "*.Cu" "*.Mask")
			(remove_unused_layers no)
			(net "PHY_DRV_B_TO_SCC_B_22_DN")
			(clearance 0.2286)
			(thermal_gap 0.2286)
		)
		(pad "4" thru_hole circle
			(at 1.651 0)
			(size 0.508 0.508)
			(drill 0.254)
			(layers "*.Cu" "*.Mask")
			(remove_unused_layers no)
			(net "GND")
			(clearance 0.2286)
			(thermal_gap 0.2286)
		)
	)
	(footprint ""
		(layer "F.Cu")
		(at 473.202 -131.826 90)
		(property "Reference" "Q113"
			(at 0 0 90)
			(layer "F.SilkS")
			(hide yes)
			(effects
				(font
					(size 1.27 1.27)
				)
			)
		)
		(property "Value" "2N7002KDW-GP"
			(at -2.3622 -8.2042 90)
			(unlocked yes)
			(layer "F.Fab")
			(hide yes)
			(effects
				(font
					(size 1.016 1.016)
					(thickness 0.1524)
				)
			)
		)
		(property "Device Type" "SOT-363H44"
			(at -2.3622 -10.1092 90)
			(unlocked yes)
			(layer "F.Fab")
			(hide yes)
			(effects
				(font
					(size 1.016 1.016)
					(thickness 0.1524)
				)
			)
		)
		(duplicate_pad_numbers_are_jumpers no)
		(fp_line
			(start 1.4478 -1.7018)
			(end -1.4478 -1.7018)
			(stroke
				(width 0.1524)
				(type default)
			)
			(layer "F.SilkS")
		)
		(fp_line
			(start -1.4478 -1.7018)
			(end -1.4478 1.7018)
			(stroke
				(width 0.1524)
				(type default)
			)
			(layer "F.SilkS")
		)
		(fp_line
			(start -1.27 1.524)
			(end -1.27 0.6604)
			(stroke
				(width 0.4826)
				(type default)
			)
			(layer "F.SilkS")
		)
		(fp_line
			(start 1.4478 1.7018)
			(end 1.4478 -1.7018)
			(stroke
				(width 0.1524)
				(type default)
			)
			(layer "F.SilkS")
		)
		(fp_line
			(start -1.4478 1.7018)
			(end 1.4478 1.7018)
			(stroke
				(width 0.1524)
				(type default)
			)
			(layer "F.SilkS")
		)
		(fp_poly
			(pts
				(xy -1.524 -1.778) (xy 1.524 -1.778) (xy 1.524 1.778) (xy -1.524 1.778)
			)
			(stroke
				(width 0)
				(type default)
			)
			(fill no)
			(layer "F.CrtYd")
		)
		(fp_poly
			(pts
				(xy -1.524 -1.778) (xy 1.524 -1.778) (xy 1.524 1.778) (xy -1.524 1.778)
			)
			(stroke
				(width 0)
				(type default)
			)
			(fill no)
			(layer "F.Fab")
		)
		(pad "1" smd rect
			(at -0.65024 0.9398 90)
			(size 0.4064 1.016)
			(layers "F.Cu" "F.Mask" "F.Paste")
			(net "GND")
		)
		(pad "2" smd rect
			(at 0 0.9398 90)
			(size 0.4064 1.016)
			(layers "F.Cu" "F.Mask" "F.Paste")
			(net "SW_PWR_R_HDD23")
		)
		(pad "3" smd rect
			(at 0.65024 0.9398 90)
			(size 0.4064 1.016)
			(layers "F.Cu" "F.Mask" "F.Paste")
			(net "SW_HDD_P23")
		)
		(pad "4" smd rect
			(at 0.65024 -0.9398 90)
			(size 0.4064 1.016)
			(layers "F.Cu" "F.Mask" "F.Paste")
			(net "GND")
		)
		(pad "5" smd rect
			(at 0 -0.9398 90)
			(size 0.4064 1.016)
			(layers "F.Cu" "F.Mask" "F.Paste")
			(net "SW_HDD_G23")
		)
		(pad "6" smd rect
			(at -0.65024 -0.9398 90)
			(size 0.4064 1.016)
			(layers "F.Cu" "F.Mask" "F.Paste")
			(net "SW_HDD_R23")
		)
	)
	(footprint ""
		(layer "F.Cu")
		(at 188.120528 -374.531636 -90)
		(property "Reference" "Q205"
			(at 0 0 270)
			(layer "F.SilkS")
			(hide yes)
			(effects
				(font
					(size 1.27 1.27)
				)
			)
		)
		(property "Value" "SSM6P39TU-GP"
			(at 0.0508 -11.5824 270)
			(unlocked yes)
			(layer "F.Fab")
			(hide yes)
			(effects
				(font
					(size 1.016 1.016)
					(thickness 0.1524)
				)
			)
		)
		(property "Device Type" "UMT6H30"
			(at 0.0508 -13.1572 270)
			(unlocked yes)
			(layer "F.Fab")
			(hide yes)
			(effects
				(font
					(size 1.016 1.016)
					(thickness 0.1524)
				)
			)
		)
		(duplicate_pad_numbers_are_jumpers no)
		(fp_line
			(start 1.524 0.36449)
			(end -1.27 0.36449)
			(stroke
				(width 0.1524)
				(type default)
			)
			(layer "F.SilkS")
		)
		(fp_line
			(start 1.09347 0)
			(end 1.45796 0.36449)
			(stroke
				(width 0.1524)
				(type default)
			)
			(layer "F.SilkS")
		)
		(fp_line
			(start -1.27 -0.36449)
			(end -1.27 0.36449)
			(stroke
				(width 0.1524)
				(type default)
			)
			(layer "F.SilkS")
		)
		(fp_line
			(start -1.27 -0.36449)
			(end 1.524 -0.36449)
			(stroke
				(width 0.1524)
				(type default)
			)
			(layer "F.SilkS")
		)
		(fp_line
			(start 1.45796 -0.36449)
			(end 1.09347 0)
			(stroke
				(width 0.1524)
				(type default)
			)
			(layer "F.SilkS")
		)
		(fp_line
			(start 1.524 -0.36449)
			(end 1.524 0.36449)
			(stroke
				(width 0.1524)
				(type default)
			)
			(layer "F.SilkS")
		)
		(fp_line
			(start 1.524 -0.36449)
			(end 1.45796 -0.36449)
			(stroke
				(width 0.1524)
				(type default)
			)
			(layer "F.SilkS")
		)
		(fp_line
			(start 1.524 -0.36449)
			(end 1.524 -1.82245)
			(stroke
				(width 0.508)
				(type default)
			)
			(layer "F.SilkS")
		)
		(fp_poly
			(pts
				(xy -0.65024 0.36449) (xy -0.65024 -0.36449) (xy 0.65024 -0.36449) (xy 0.65024 0.36449)
			)
			(stroke
				(width 0)
				(type default)
			)
			(fill yes)
			(layer "F.SilkS")
		)
		(fp_poly
			(pts
				(xy 1.016 -1.0668) (xy 1.016 1.0668) (xy -1.016 1.0668) (xy -1.016 -1.0668)
			)
			(stroke
				(width 0)
				(type default)
			)
			(fill no)
			(layer "F.CrtYd")
		)
		(fp_poly
			(pts
				(xy -1.524 1.905) (xy 1.524 1.905) (xy 1.524 -1.06426) (xy 1.016 -1.06426) (xy 1.016 1.0668) (xy -1.016 1.0668)
				(xy -1.016 -1.0668) (xy 1.524 -1.0668) (xy 1.524 -1.905) (xy -1.524 -1.905)
			)
			(stroke
				(width 0)
				(type default)
			)
			(fill no)
			(layer "F.CrtYd")
		)
		(fp_poly
			(pts
				(xy -1.524 -1.905) (xy -1.524 1.905) (xy 1.524 1.905) (xy 1.524 -1.905)
			)
			(stroke
				(width 0)
				(type default)
			)
			(fill no)
			(layer "F.Fab")
		)
		(pad "1" smd rect
			(at 0.65024 -1.02489 270)
			(size 0.4064 0.8128)
			(layers "F.Cu" "F.Mask" "F.Paste")
			(net "P12V_IN")
		)
		(pad "2" smd rect
			(at 0 -1.02489 270)
			(size 0.4064 0.8128)
			(layers "F.Cu" "F.Mask" "F.Paste")
			(net "FAN_YELLOW_LED1")
		)
		(pad "3" smd rect
			(at -0.65024 -1.02489 270)
			(size 0.4064 0.8128)
			(layers "F.Cu" "F.Mask" "F.Paste")
			(net "FAN_BLUE1")
		)
		(pad "4" smd rect
			(at -0.65024 1.02489 270)
			(size 0.4064 0.8128)
			(layers "F.Cu" "F.Mask" "F.Paste")
			(net "P12V_IN")
		)
		(pad "5" smd rect
			(at 0 1.02489 270)
			(size 0.4064 0.8128)
			(layers "F.Cu" "F.Mask" "F.Paste")
			(net "FAN_BLUE_LED1")
		)
		(pad "6" smd rect
			(at 0.65024 1.02489 270)
			(size 0.4064 0.8128)
			(layers "F.Cu" "F.Mask" "F.Paste")
			(net "FAN_YELLOW_1")
		)
	)
	(footprint ""
		(layer "F.Cu")
		(at 423.958004 -370.078 90)
		(property "Reference" "R956"
			(at 0 0 90)
			(layer "F.SilkS")
			(hide yes)
			(effects
				(font
					(size 1.27 1.27)
				)
			)
		)
		(property "Value" "27KR3F-GP"
			(at -0.0254 -2.5146 90)
			(unlocked yes)
			(layer "F.Fab")
			(hide yes)
			(effects
				(font
					(size 1.016 1.016)
					(thickness 0.1524)
				)
			)
		)
		(property "Device Type" "R603H22"
			(at -0.0254 -4.0386 90)
			(unlocked yes)
			(layer "F.Fab")
			(hide yes)
			(effects
				(font
					(size 1.016 1.016)
					(thickness 0.1524)
				)
			)
		)
		(duplicate_pad_numbers_are_jumpers no)
		(fp_line
			(start 0.2032 0)
			(end 0.4826 0)
			(stroke
				(width 0.2032)
				(type default)
			)
			(layer "F.SilkS")
		)
		(fp_line
			(start -0.4826 0)
			(end -0.2032 0)
			(stroke
				(width 0.2032)
				(type default)
			)
			(layer "F.SilkS")
		)
		(fp_rect
			(start -0.5842 1.3335)
			(end 0.5842 -1.3335)
			(stroke
				(width 0)
				(type default)
			)
			(fill no)
			(layer "F.CrtYd")
		)
		(fp_rect
			(start -0.5842 1.3335)
			(end 0.5842 -1.3335)
			(stroke
				(width 0)
				(type default)
			)
			(fill no)
			(layer "F.Fab")
		)
		(pad "1" smd custom
			(at 0 -0.762 90)
			(size 0.2159 0.2159)
			(layers "F.Cu" "F.Mask" "F.Paste")
			(net "FANTACH_R3")
			(options
				(clearance outline)
				(anchor circle)
			)
			(primitives
				(gr_poly
					(pts
						(arc
							(start -0.3302 -0.4318)
							(mid -0.402042 -0.402042)
							(end -0.4318 -0.3302)
						)
						(arc
							(start -0.4318 0.3302)
							(mid -0.402042 0.402042)
							(end -0.3302 0.4318)
						)
						(arc
							(start 0.3302 0.4318)
							(mid 0.402042 0.402042)
							(end 0.4318 0.3302)
						)
						(arc
							(start 0.4318 -0.3302)
							(mid 0.402042 -0.402042)
							(end 0.3302 -0.4318)
						)
					)
					(width 0)
					(fill yes)
				)
			)
		)
		(pad "2" smd custom
			(at 0 0.762 90)
			(size 0.2159 0.2159)
			(layers "F.Cu" "F.Mask" "F.Paste")
			(net "FAN_3_TACH0")
			(options
				(clearance outline)
				(anchor circle)
			)
			(primitives
				(gr_poly
					(pts
						(arc
							(start -0.3302 -0.4318)
							(mid -0.402042 -0.402042)
							(end -0.4318 -0.3302)
						)
						(arc
							(start -0.4318 0.3302)
							(mid -0.402042 0.402042)
							(end -0.3302 0.4318)
						)
						(arc
							(start 0.3302 0.4318)
							(mid 0.402042 0.402042)
							(end 0.4318 0.3302)
						)
						(arc
							(start 0.4318 -0.3302)
							(mid 0.402042 -0.402042)
							(end 0.3302 -0.4318)
						)
					)
					(width 0)
					(fill yes)
				)
			)
		)
	)
	(footprint ""
		(layer "F.Cu")
		(at 83.566 -134.493 180)
		(property "Reference" "Q59"
			(at 0 0 180)
			(layer "F.SilkS")
			(hide yes)
			(effects
				(font
					(size 1.27 1.27)
				)
			)
		)
		(property "Value" "2N7002KDW-GP"
			(at -2.3622 -8.2042 180)
			(unlocked yes)
			(layer "F.Fab")
			(hide yes)
			(effects
				(font
					(size 1.016 1.016)
					(thickness 0.1524)
				)
			)
		)
		(property "Device Type" "SOT-363H44"
			(at -2.3622 -10.1092 180)
			(unlocked yes)
			(layer "F.Fab")
			(hide yes)
			(effects
				(font
					(size 1.016 1.016)
					(thickness 0.1524)
				)
			)
		)
		(duplicate_pad_numbers_are_jumpers no)
		(fp_line
			(start 1.4478 1.7018)
			(end 1.4478 -1.7018)
			(stroke
				(width 0.1524)
				(type default)
			)
			(layer "F.SilkS")
		)
		(fp_line
			(start 1.4478 -1.7018)
			(end -1.4478 -1.7018)
			(stroke
				(width 0.1524)
				(type default)
			)
			(layer "F.SilkS")
		)
		(fp_line
			(start -1.27 1.524)
			(end -1.27 0.6604)
			(stroke
				(width 0.4826)
				(type default)
			)
			(layer "F.SilkS")
		)
		(fp_line
			(start -1.4478 1.7018)
			(end 1.4478 1.7018)
			(stroke
				(width 0.1524)
				(type default)
			)
			(layer "F.SilkS")
		)
		(fp_line
			(start -1.4478 -1.7018)
			(end -1.4478 1.7018)
			(stroke
				(width 0.1524)
				(type default)
			)
			(layer "F.SilkS")
		)
		(fp_poly
			(pts
				(xy -1.524 -1.778) (xy 1.524 -1.778) (xy 1.524 1.778) (xy -1.524 1.778)
			)
			(stroke
				(width 0)
				(type default)
			)
			(fill no)
			(layer "F.CrtYd")
		)
		(fp_poly
			(pts
				(xy -1.524 -1.778) (xy 1.524 -1.778) (xy 1.524 1.778) (xy -1.524 1.778)
			)
			(stroke
				(width 0)
				(type default)
			)
			(fill no)
			(layer "F.Fab")
		)
		(pad "1" smd rect
			(at -0.65024 0.9398 180)
			(size 0.4064 1.016)
			(layers "F.Cu" "F.Mask" "F.Paste")
			(net "GND")
		)
		(pad "2" smd rect
			(at 0 0.9398 180)
			(size 0.4064 1.016)
			(layers "F.Cu" "F.Mask" "F.Paste")
			(net "SW_PWR_R_HDD14")
		)
		(pad "3" smd rect
			(at 0.65024 0.9398 180)
			(size 0.4064 1.016)
			(layers "F.Cu" "F.Mask" "F.Paste")
			(net "SW_HDD_P14")
		)
		(pad "4" smd rect
			(at 0.65024 -0.9398 180)
			(size 0.4064 1.016)
			(layers "F.Cu" "F.Mask" "F.Paste")
			(net "GND")
		)
		(pad "5" smd rect
			(at 0 -0.9398 180)
			(size 0.4064 1.016)
			(layers "F.Cu" "F.Mask" "F.Paste")
			(net "SW_HDD_G14")
		)
		(pad "6" smd rect
			(at -0.65024 -0.9398 180)
			(size 0.4064 1.016)
			(layers "F.Cu" "F.Mask" "F.Paste")
			(net "SW_HDD_R14")
		)
	)
	(footprint ""
		(layer "F.Cu")
		(at 32.463486 -244.660674 90)
		(property "Reference" "C497"
			(at 0 0 90)
			(layer "F.SilkS")
			(hide yes)
			(effects
				(font
					(size 1.27 1.27)
				)
			)
		)
		(property "Value" "SCD01U16V1KX-GP"
			(at -2.8321 -1.7399 90)
			(unlocked yes)
			(layer "F.Fab")
			(hide yes)
			(effects
				(font
					(size 1.016 1.016)
					(thickness 0.1524)
				)
			)
		)
		(property "Device Type" "C0201H13"
			(at -2.8321 -3.2639 90)
			(unlocked yes)
			(layer "F.Fab")
			(hide yes)
			(effects
				(font
					(size 1.016 1.016)
					(thickness 0.1524)
				)
			)
		)
		(duplicate_pad_numbers_are_jumpers no)
		(fp_rect
			(start -0.2794 0.6477)
			(end 0.2794 -0.6477)
			(stroke
				(width 0)
				(type default)
			)
			(fill no)
			(layer "F.CrtYd")
		)
		(fp_rect
			(start -0.2794 0.6477)
			(end 0.2794 -0.6477)
			(stroke
				(width 0)
				(type default)
			)
			(fill no)
			(layer "F.Fab")
		)
		(pad "1" smd custom
			(at 0 -0.2794 90)
			(size 0.0762 0.0762)
			(layers "F.Cu" "F.Mask" "F.Paste")
			(net "SAS_HDD_RX_P0")
			(options
				(clearance outline)
				(anchor circle)
			)
			(primitives
				(gr_poly
					(pts
						(arc
							(start 0.1524 -0.127)
							(mid 0.137521 -0.162921)
							(end 0.1016 -0.1778)
						)
						(arc
							(start -0.1016 -0.1778)
							(mid -0.137521 -0.162921)
							(end -0.1524 -0.127)
						)
						(arc
							(start -0.1524 0.127)
							(mid -0.137521 0.162921)
							(end -0.1016 0.1778)
						)
						(arc
							(start 0.1016 0.1778)
							(mid 0.137521 0.162921)
							(end 0.1524 0.127)
						)
					)
					(width 0)
					(fill yes)
				)
			)
		)
		(pad "2" smd custom
			(at 0 0.2794 90)
			(size 0.0762 0.0762)
			(layers "F.Cu" "F.Mask" "F.Paste")
			(net "PHY_SCC_B_TO_DRV_B_0_DP")
			(options
				(clearance outline)
				(anchor circle)
			)
			(primitives
				(gr_poly
					(pts
						(arc
							(start 0.1524 -0.127)
							(mid 0.137521 -0.162921)
							(end 0.1016 -0.1778)
						)
						(arc
							(start -0.1016 -0.1778)
							(mid -0.137521 -0.162921)
							(end -0.1524 -0.127)
						)
						(arc
							(start -0.1524 0.127)
							(mid -0.137521 0.162921)
							(end -0.1016 0.1778)
						)
						(arc
							(start 0.1016 0.1778)
							(mid 0.137521 0.162921)
							(end 0.1524 0.127)
						)
					)
					(width 0)
					(fill yes)
				)
			)
		)
	)
	(footprint ""
		(layer "F.Cu")
		(at 209.804 -226.822 90)
		(property "Reference" "R18"
			(at 0 0 90)
			(layer "F.SilkS")
			(hide yes)
			(effects
				(font
					(size 1.27 1.27)
				)
			)
		)
		(property "Value" "4K7R2F-GP"
			(at 0.064008 -3.993896 90)
			(unlocked yes)
			(layer "F.Fab")
			(hide yes)
			(effects
				(font
					(size 1.016 1.016)
					(thickness 0.1524)
				)
			)
		)
		(property "Device Type" "R402H16"
			(at 0.064008 -5.517896 90)
			(unlocked yes)
			(layer "F.Fab")
			(hide yes)
			(effects
				(font
					(size 1.016 1.016)
					(thickness 0.1524)
				)
			)
		)
		(duplicate_pad_numbers_are_jumpers no)
		(fp_line
			(start 0.508 -0.9398)
			(end -0.508 -0.9398)
			(stroke
				(width 0.1524)
				(type default)
			)
			(layer "F.SilkS")
		)
		(fp_line
			(start -0.508 -0.9398)
			(end -0.508 0.9398)
			(stroke
				(width 0.1524)
				(type default)
			)
			(layer "F.SilkS")
		)
		(fp_rect
			(start -0.508 0.9398)
			(end 0.508 -0.9398)
			(stroke
				(width 0)
				(type default)
			)
			(fill no)
			(layer "F.CrtYd")
		)
		(fp_rect
			(start -0.508 0.9398)
			(end 0.508 -0.9398)
			(stroke
				(width 0)
				(type default)
			)
			(fill no)
			(layer "F.Fab")
		)
		(pad "1" smd custom
			(at 0 -0.4445 90)
			(size 0.1397 0.1397)
			(layers "F.Cu" "F.Mask" "F.Paste")
			(net "P3V3_STBY_B")
			(options
				(clearance outline)
				(anchor circle)
			)
			(primitives
				(gr_poly
					(pts
						(arc
							(start -0.1778 -0.2794)
							(mid -0.249642 -0.249642)
							(end -0.2794 -0.1778)
						)
						(arc
							(start -0.2794 0.1778)
							(mid -0.249642 0.249642)
							(end -0.1778 0.2794)
						)
						(arc
							(start 0.1778 0.2794)
							(mid 0.249642 0.249642)
							(end 0.2794 0.1778)
						)
						(arc
							(start 0.2794 -0.1778)
							(mid 0.249642 -0.249642)
							(end 0.1778 -0.2794)
						)
					)
					(width 0)
					(fill yes)
				)
			)
		)
		(pad "2" smd custom
			(at 0 0.4445 90)
			(size 0.1397 0.1397)
			(layers "F.Cu" "F.Mask" "F.Paste")
			(net "IO_EXP1_HDD_FAULT_A1")
			(options
				(clearance outline)
				(anchor circle)
			)
			(primitives
				(gr_poly
					(pts
						(arc
							(start -0.1778 -0.2794)
							(mid -0.249642 -0.249642)
							(end -0.2794 -0.1778)
						)
						(arc
							(start -0.2794 0.1778)
							(mid -0.249642 0.249642)
							(end -0.1778 0.2794)
						)
						(arc
							(start 0.1778 0.2794)
							(mid 0.249642 0.249642)
							(end 0.2794 0.1778)
						)
						(arc
							(start 0.2794 -0.1778)
							(mid 0.249642 -0.249642)
							(end 0.1778 -0.2794)
						)
					)
					(width 0)
					(fill yes)
				)
			)
		)
	)
	(footprint ""
		(layer "F.Cu")
		(at 231.41432 -219.04198 180)
		(property "Reference" "R68"
			(at 0 0 180)
			(layer "F.SilkS")
			(hide yes)
			(effects
				(font
					(size 1.27 1.27)
				)
			)
		)
		(property "Value" "4K7R2F-GP"
			(at 0.064008 -3.993896 180)
			(unlocked yes)
			(layer "F.Fab")
			(hide yes)
			(effects
				(font
					(size 1.016 1.016)
					(thickness 0.1524)
				)
			)
		)
		(property "Device Type" "R402H16"
			(at 0.064008 -5.517896 180)
			(unlocked yes)
			(layer "F.Fab")
			(hide yes)
			(effects
				(font
					(size 1.016 1.016)
					(thickness 0.1524)
				)
			)
		)
		(duplicate_pad_numbers_are_jumpers no)
		(fp_line
			(start 0.508 -0.9398)
			(end -0.508 -0.9398)
			(stroke
				(width 0.1524)
				(type default)
			)
			(layer "F.SilkS")
		)
		(fp_line
			(start -0.508 -0.9398)
			(end -0.508 0.9398)
			(stroke
				(width 0.1524)
				(type default)
			)
			(layer "F.SilkS")
		)
		(fp_rect
			(start -0.508 0.9398)
			(end 0.508 -0.9398)
			(stroke
				(width 0)
				(type default)
			)
			(fill no)
			(layer "F.CrtYd")
		)
		(fp_rect
			(start -0.508 0.9398)
			(end 0.508 -0.9398)
			(stroke
				(width 0)
				(type default)
			)
			(fill no)
			(layer "F.Fab")
		)
		(pad "1" smd custom
			(at 0 -0.4445 180)
			(size 0.1397 0.1397)
			(layers "F.Cu" "F.Mask" "F.Paste")
			(net "P3V3_STBY_B")
			(options
				(clearance outline)
				(anchor circle)
			)
			(primitives
				(gr_poly
					(pts
						(arc
							(start -0.1778 -0.2794)
							(mid -0.249642 -0.249642)
							(end -0.2794 -0.1778)
						)
						(arc
							(start -0.2794 0.1778)
							(mid -0.249642 0.249642)
							(end -0.1778 0.2794)
						)
						(arc
							(start 0.1778 0.2794)
							(mid 0.249642 0.249642)
							(end 0.2794 0.1778)
						)
						(arc
							(start 0.2794 -0.1778)
							(mid 0.249642 -0.249642)
							(end 0.1778 -0.2794)
						)
					)
					(width 0)
					(fill yes)
				)
			)
		)
		(pad "2" smd custom
			(at 0 0.4445 180)
			(size 0.1397 0.1397)
			(layers "F.Cu" "F.Mask" "F.Paste")
			(net "IO_EXP1_A0")
			(options
				(clearance outline)
				(anchor circle)
			)
			(primitives
				(gr_poly
					(pts
						(arc
							(start -0.1778 -0.2794)
							(mid -0.249642 -0.249642)
							(end -0.2794 -0.1778)
						)
						(arc
							(start -0.2794 0.1778)
							(mid -0.249642 0.249642)
							(end -0.1778 0.2794)
						)
						(arc
							(start 0.1778 0.2794)
							(mid 0.249642 0.249642)
							(end 0.2794 0.1778)
						)
						(arc
							(start 0.2794 -0.1778)
							(mid 0.249642 -0.249642)
							(end 0.1778 -0.2794)
						)
					)
					(width 0)
					(fill yes)
				)
			)
		)
	)
	(footprint ""
		(layer "F.Cu")
		(at 18.227802 -226.57435 -90)
		(property "Reference" "R1112"
			(at 0 0 270)
			(layer "F.SilkS")
			(hide yes)
			(effects
				(font
					(size 1.27 1.27)
				)
			)
		)
		(property "Value" "309KR2F-GP"
			(at 0.064008 -3.993896 270)
			(unlocked yes)
			(layer "F.Fab")
			(hide yes)
			(effects
				(font
					(size 1.016 1.016)
					(thickness 0.1524)
				)
			)
		)
		(property "Device Type" "R402H16"
			(at 0.064008 -5.517896 270)
			(unlocked yes)
			(layer "F.Fab")
			(hide yes)
			(effects
				(font
					(size 1.016 1.016)
					(thickness 0.1524)
				)
			)
		)
		(duplicate_pad_numbers_are_jumpers no)
		(fp_line
			(start -0.508 -0.9398)
			(end -0.508 0.9398)
			(stroke
				(width 0.1524)
				(type default)
			)
			(layer "F.SilkS")
		)
		(fp_line
			(start 0.508 -0.9398)
			(end -0.508 -0.9398)
			(stroke
				(width 0.1524)
				(type default)
			)
			(layer "F.SilkS")
		)
		(fp_rect
			(start -0.508 0.9398)
			(end 0.508 -0.9398)
			(stroke
				(width 0)
				(type default)
			)
			(fill no)
			(layer "F.CrtYd")
		)
		(fp_rect
			(start -0.508 0.9398)
			(end 0.508 -0.9398)
			(stroke
				(width 0)
				(type default)
			)
			(fill no)
			(layer "F.Fab")
		)
		(pad "1" smd custom
			(at 0 -0.4445 270)
			(size 0.1397 0.1397)
			(layers "F.Cu" "F.Mask" "F.Paste")
			(net "P5V_B_1_RF")
			(options
				(clearance outline)
				(anchor circle)
			)
			(primitives
				(gr_poly
					(pts
						(arc
							(start -0.1778 -0.2794)
							(mid -0.249642 -0.249642)
							(end -0.2794 -0.1778)
						)
						(arc
							(start -0.2794 0.1778)
							(mid -0.249642 0.249642)
							(end -0.1778 0.2794)
						)
						(arc
							(start 0.1778 0.2794)
							(mid 0.249642 0.249642)
							(end 0.2794 0.1778)
						)
						(arc
							(start 0.2794 -0.1778)
							(mid 0.249642 -0.249642)
							(end 0.1778 -0.2794)
						)
					)
					(width 0)
					(fill yes)
				)
			)
		)
		(pad "2" smd custom
			(at 0 0.4445 270)
			(size 0.1397 0.1397)
			(layers "F.Cu" "F.Mask" "F.Paste")
			(net "P5V_B_1_VREG")
			(options
				(clearance outline)
				(anchor circle)
			)
			(primitives
				(gr_poly
					(pts
						(arc
							(start -0.1778 -0.2794)
							(mid -0.249642 -0.249642)
							(end -0.2794 -0.1778)
						)
						(arc
							(start -0.2794 0.1778)
							(mid -0.249642 0.249642)
							(end -0.1778 0.2794)
						)
						(arc
							(start 0.1778 0.2794)
							(mid 0.249642 0.249642)
							(end 0.2794 0.1778)
						)
						(arc
							(start 0.2794 -0.1778)
							(mid 0.249642 -0.249642)
							(end 0.1778 -0.2794)
						)
					)
					(width 0)
					(fill yes)
				)
			)
		)
	)
	(footprint ""
		(layer "F.Cu")
		(at 203.5302 -307.8226)
		(property "Reference" "TC6"
			(at 0 0 0)
			(layer "F.SilkS")
			(hide yes)
			(effects
				(font
					(size 1.27 1.27)
				)
			)
		)
		(property "Value" "SE270U16VM-8-GP"
			(at -4.5974 -2.54 0)
			(unlocked yes)
			(layer "F.Fab")
			(hide yes)
			(effects
				(font
					(size 1.016 1.016)
					(thickness 0.1524)
				)
			)
		)
		(property "Device Type" "SE361416H394"
			(at -4.5974 -4.064 0)
			(unlocked yes)
			(layer "F.Fab")
			(hide yes)
			(effects
				(font
					(size 1.016 1.016)
					(thickness 0.1524)
				)
			)
		)
		(duplicate_pad_numbers_are_jumpers no)
		(fp_line
			(start -3.556 -3.4163)
			(end -2.3622 -4.6101)
			(stroke
				(width 0.1524)
				(type default)
			)
			(layer "F.SilkS")
		)
		(fp_line
			(start -3.556 4.6101)
			(end -3.556 -3.4163)
			(stroke
				(width 0.1524)
				(type default)
			)
			(layer "F.SilkS")
		)
		(fp_line
			(start -2.3622 -4.6101)
			(end 2.3622 -4.6101)
			(stroke
				(width 0.1524)
				(type default)
			)
			(layer "F.SilkS")
		)
		(fp_line
			(start 2.3622 -4.6101)
			(end 3.556 -3.4163)
			(stroke
				(width 0.1524)
				(type default)
			)
			(layer "F.SilkS")
		)
		(fp_line
			(start 3.556 -3.4163)
			(end 3.556 4.6101)
			(stroke
				(width 0.1524)
				(type default)
			)
			(layer "F.SilkS")
		)
		(fp_line
			(start 3.556 4.6101)
			(end -3.556 4.6101)
			(stroke
				(width 0.1524)
				(type default)
			)
			(layer "F.SilkS")
		)
		(fp_rect
			(start -3.302 3.6449)
			(end 3.302 -3.6449)
			(stroke
				(width 0)
				(type default)
			)
			(fill no)
			(layer "F.CrtYd")
		)
		(fp_poly
			(pts
				(xy 3.81 4.6863) (xy 3.81 -3.4925) (xy 3.302 -3.4925) (xy 3.302 3.6449) (xy -3.302 3.6449) (xy -3.302 -3.6449)
				(xy 3.302 -3.6449) (xy 3.302 -3.5052) (xy 3.81 -3.5052) (xy 3.81 -4.6863) (xy -3.81 -4.6863) (xy -3.81 4.6863)
			)
			(stroke
				(width 0)
				(type default)
			)
			(fill no)
			(layer "F.CrtYd")
		)
		(fp_rect
			(start -3.81 4.6863)
			(end 3.81 -4.6863)
			(stroke
				(width 0)
				(type default)
			)
			(fill no)
			(layer "F.Fab")
		)
		(pad "1" smd rect
			(at 0 -2.574036)
			(size 1.4224 3.556)
			(layers "F.Cu" "F.Mask" "F.Paste")
			(net "P12V_B")
		)
		(pad "2" smd rect
			(at 0 2.574036)
			(size 1.4224 3.556)
			(layers "F.Cu" "F.Mask" "F.Paste")
			(net "GND")
		)
	)
	(footprint ""
		(layer "F.Cu")
		(at 348.582996 -363.22 90)
		(property "Reference" "C531"
			(at 0 0 90)
			(layer "F.SilkS")
			(hide yes)
			(effects
				(font
					(size 1.27 1.27)
				)
			)
		)
		(property "Value" "SC1U25V3KX-GP"
			(at 0 -2.8194 90)
			(unlocked yes)
			(layer "F.Fab")
			(hide yes)
			(effects
				(font
					(size 1.016 1.016)
					(thickness 0.1524)
				)
			)
		)
		(property "Device Type" "C603H36"
			(at 0 -4.3434 90)
			(unlocked yes)
			(layer "F.Fab")
			(hide yes)
			(effects
				(font
					(size 1.016 1.016)
					(thickness 0.1524)
				)
			)
		)
		(duplicate_pad_numbers_are_jumpers no)
		(fp_line
			(start 0.508 0)
			(end -0.508 0)
			(stroke
				(width 0.2032)
				(type default)
			)
			(layer "F.SilkS")
		)
		(fp_rect
			(start -0.5842 1.3335)
			(end 0.5842 -1.3335)
			(stroke
				(width 0)
				(type default)
			)
			(fill no)
			(layer "F.CrtYd")
		)
		(fp_rect
			(start -0.5842 1.3335)
			(end 0.5842 -1.3335)
			(stroke
				(width 0)
				(type default)
			)
			(fill no)
			(layer "F.Fab")
		)
		(pad "1" smd custom
			(at 0 -0.762 90)
			(size 0.2159 0.2159)
			(layers "F.Cu" "F.Mask" "F.Paste")
			(net "P12V_FAN2")
			(options
				(clearance outline)
				(anchor circle)
			)
			(primitives
				(gr_poly
					(pts
						(arc
							(start -0.3302 -0.4318)
							(mid -0.402042 -0.402042)
							(end -0.4318 -0.3302)
						)
						(arc
							(start -0.4318 0.3302)
							(mid -0.402042 0.402042)
							(end -0.3302 0.4318)
						)
						(arc
							(start 0.3302 0.4318)
							(mid 0.402042 0.402042)
							(end 0.4318 0.3302)
						)
						(arc
							(start 0.4318 -0.3302)
							(mid 0.402042 -0.402042)
							(end 0.3302 -0.4318)
						)
					)
					(width 0)
					(fill yes)
				)
			)
		)
		(pad "2" smd custom
			(at 0 0.762 90)
			(size 0.2159 0.2159)
			(layers "F.Cu" "F.Mask" "F.Paste")
			(net "GND")
			(options
				(clearance outline)
				(anchor circle)
			)
			(primitives
				(gr_poly
					(pts
						(arc
							(start -0.3302 -0.4318)
							(mid -0.402042 -0.402042)
							(end -0.4318 -0.3302)
						)
						(arc
							(start -0.4318 0.3302)
							(mid -0.402042 0.402042)
							(end -0.3302 0.4318)
						)
						(arc
							(start 0.3302 0.4318)
							(mid 0.402042 0.402042)
							(end 0.4318 0.3302)
						)
						(arc
							(start 0.4318 -0.3302)
							(mid 0.402042 -0.402042)
							(end 0.3302 -0.4318)
						)
					)
					(width 0)
					(fill yes)
				)
			)
		)
	)
	(footprint ""
		(layer "F.Cu")
		(at 64.013334 -15.219426 90)
		(property "Reference" "C353"
			(at 0 0 90)
			(layer "F.SilkS")
			(hide yes)
			(effects
				(font
					(size 1.27 1.27)
				)
			)
		)
		(property "Value" "SCD01U16V1KX-GP"
			(at -2.8321 -1.7399 90)
			(unlocked yes)
			(layer "F.Fab")
			(hide yes)
			(effects
				(font
					(size 1.016 1.016)
					(thickness 0.1524)
				)
			)
		)
		(property "Device Type" "C0201H13"
			(at -2.8321 -3.2639 90)
			(unlocked yes)
			(layer "F.Fab")
			(hide yes)
			(effects
				(font
					(size 1.016 1.016)
					(thickness 0.1524)
				)
			)
		)
		(duplicate_pad_numbers_are_jumpers no)
		(fp_rect
			(start -0.2794 0.6477)
			(end 0.2794 -0.6477)
			(stroke
				(width 0)
				(type default)
			)
			(fill no)
			(layer "F.CrtYd")
		)
		(fp_rect
			(start -0.2794 0.6477)
			(end 0.2794 -0.6477)
			(stroke
				(width 0)
				(type default)
			)
			(fill no)
			(layer "F.Fab")
		)
		(pad "1" smd custom
			(at 0 -0.2794 90)
			(size 0.0762 0.0762)
			(layers "F.Cu" "F.Mask" "F.Paste")
			(net "SAS_HDD_RX_N25")
			(options
				(clearance outline)
				(anchor circle)
			)
			(primitives
				(gr_poly
					(pts
						(arc
							(start 0.1524 -0.127)
							(mid 0.137521 -0.162921)
							(end 0.1016 -0.1778)
						)
						(arc
							(start -0.1016 -0.1778)
							(mid -0.137521 -0.162921)
							(end -0.1524 -0.127)
						)
						(arc
							(start -0.1524 0.127)
							(mid -0.137521 0.162921)
							(end -0.1016 0.1778)
						)
						(arc
							(start 0.1016 0.1778)
							(mid 0.137521 0.162921)
							(end 0.1524 0.127)
						)
					)
					(width 0)
					(fill yes)
				)
			)
		)
		(pad "2" smd custom
			(at 0 0.2794 90)
			(size 0.0762 0.0762)
			(layers "F.Cu" "F.Mask" "F.Paste")
			(net "PHY_SCC_B_TO_DRV_B_25_DN")
			(options
				(clearance outline)
				(anchor circle)
			)
			(primitives
				(gr_poly
					(pts
						(arc
							(start 0.1524 -0.127)
							(mid 0.137521 -0.162921)
							(end 0.1016 -0.1778)
						)
						(arc
							(start -0.1016 -0.1778)
							(mid -0.137521 -0.162921)
							(end -0.1524 -0.127)
						)
						(arc
							(start -0.1524 0.127)
							(mid -0.137521 0.162921)
							(end -0.1016 0.1778)
						)
						(arc
							(start 0.1016 0.1778)
							(mid 0.137521 0.162921)
							(end 0.1524 0.127)
						)
					)
					(width 0)
					(fill yes)
				)
			)
		)
	)
	(footprint ""
		(layer "F.Cu")
		(at 394.589 -262.001 -90)
		(property "Reference" "R286"
			(at 0 0 270)
			(layer "F.SilkS")
			(hide yes)
			(effects
				(font
					(size 1.27 1.27)
				)
			)
		)
		(property "Value" "2R6F-GP"
			(at -0.0508 -4.8514 270)
			(unlocked yes)
			(layer "F.Fab")
			(hide yes)
			(effects
				(font
					(size 1.016 1.016)
					(thickness 0.1524)
				)
			)
		)
		(property "Device Type" "R1206H26"
			(at 0 -6.3754 270)
			(unlocked yes)
			(layer "F.Fab")
			(hide yes)
			(effects
				(font
					(size 1.016 1.016)
					(thickness 0.1524)
				)
			)
		)
		(duplicate_pad_numbers_are_jumpers no)
		(fp_line
			(start -1.016 2.2352)
			(end -1.016 -2.2352)
			(stroke
				(width 0.1524)
				(type default)
			)
			(layer "F.SilkS")
		)
		(fp_line
			(start 1.016 2.2352)
			(end -1.016 2.2352)
			(stroke
				(width 0.1524)
				(type default)
			)
			(layer "F.SilkS")
		)
		(fp_line
			(start -1.016 -2.2352)
			(end 1.016 -2.2352)
			(stroke
				(width 0.1524)
				(type default)
			)
			(layer "F.SilkS")
		)
		(fp_line
			(start 1.016 -2.2352)
			(end 1.016 2.2352)
			(stroke
				(width 0.1524)
				(type default)
			)
			(layer "F.SilkS")
		)
		(fp_rect
			(start -1.0922 2.3114)
			(end 1.0922 -2.3114)
			(stroke
				(width 0)
				(type default)
			)
			(fill no)
			(layer "F.CrtYd")
		)
		(fp_poly
			(pts
				(xy -1.0922 -2.3114) (xy 1.0922 -2.3114) (xy 1.0922 2.3114) (xy -1.0922 2.3114)
			)
			(stroke
				(width 0)
				(type default)
			)
			(fill no)
			(layer "F.Fab")
		)
		(pad "1" smd rect
			(at 0 -1.397 270)
			(size 1.651 1.27)
			(layers "F.Cu" "F.Mask" "F.Paste")
			(net "P5V_HDD8")
		)
		(pad "2" smd rect
			(at 0 1.397 270)
			(size 1.651 1.27)
			(layers "F.Cu" "F.Mask" "F.Paste")
			(net "5V_PRE_8")
		)
	)
	(footprint ""
		(layer "F.Cu")
		(at 95.377 -31.6484)
		(property "Reference" "C375"
			(at 0 0 0)
			(layer "F.SilkS")
			(hide yes)
			(effects
				(font
					(size 1.27 1.27)
				)
			)
		)
		(property "Value" "SCD01U50V2KX-1GP"
			(at 1.1811 -2.7051 0)
			(unlocked yes)
			(layer "F.Fab")
			(hide yes)
			(effects
				(font
					(size 1.016 1.016)
					(thickness 0.1524)
				)
			)
		)
		(property "Device Type" "C402H22"
			(at 1.1811 -4.2291 0)
			(unlocked yes)
			(layer "F.Fab")
			(hide yes)
			(effects
				(font
					(size 1.016 1.016)
					(thickness 0.1524)
				)
			)
		)
		(duplicate_pad_numbers_are_jumpers no)
		(fp_rect
			(start -0.4318 0.9525)
			(end 0.4318 -0.9525)
			(stroke
				(width 0)
				(type default)
			)
			(fill no)
			(layer "F.CrtYd")
		)
		(fp_rect
			(start -0.4318 0.9525)
			(end 0.4318 -0.9525)
			(stroke
				(width 0)
				(type default)
			)
			(fill no)
			(layer "F.Fab")
		)
		(pad "1" smd custom
			(at 0 -0.4445)
			(size 0.1524 0.1524)
			(layers "F.Cu" "F.Mask" "F.Paste")
			(net "HDD_PRSNT_26")
			(options
				(clearance outline)
				(anchor circle)
			)
			(primitives
				(gr_poly
					(pts
						(arc
							(start 0.3048 -0.2032)
							(mid 0.275042 -0.275042)
							(end 0.2032 -0.3048)
						)
						(arc
							(start -0.2032 -0.3048)
							(mid -0.275042 -0.275042)
							(end -0.3048 -0.2032)
						)
						(arc
							(start -0.3048 0.2032)
							(mid -0.275042 0.275042)
							(end -0.2032 0.3048)
						)
						(arc
							(start 0.2032 0.3048)
							(mid 0.275042 0.275042)
							(end 0.3048 0.2032)
						)
					)
					(width 0)
					(fill yes)
				)
			)
		)
		(pad "2" smd custom
			(at 0 0.4445)
			(size 0.1524 0.1524)
			(layers "F.Cu" "F.Mask" "F.Paste")
			(net "GND")
			(options
				(clearance outline)
				(anchor circle)
			)
			(primitives
				(gr_poly
					(pts
						(arc
							(start 0.3048 -0.2032)
							(mid 0.275042 -0.275042)
							(end 0.2032 -0.3048)
						)
						(arc
							(start -0.2032 -0.3048)
							(mid -0.275042 -0.275042)
							(end -0.3048 -0.2032)
						)
						(arc
							(start -0.3048 0.2032)
							(mid -0.275042 0.275042)
							(end -0.2032 0.3048)
						)
						(arc
							(start 0.2032 0.3048)
							(mid 0.275042 0.275042)
							(end 0.3048 0.2032)
						)
					)
					(width 0)
					(fill yes)
				)
			)
		)
	)
	(footprint ""
		(layer "F.Cu")
		(at 331.47 -147.066 -90)
		(property "Reference" "R483"
			(at 0 0 270)
			(layer "F.SilkS")
			(hide yes)
			(effects
				(font
					(size 1.27 1.27)
				)
			)
		)
		(property "Value" "2R6F-GP"
			(at -0.0508 -4.8514 270)
			(unlocked yes)
			(layer "F.Fab")
			(hide yes)
			(effects
				(font
					(size 1.016 1.016)
					(thickness 0.1524)
				)
			)
		)
		(property "Device Type" "R1206H26"
			(at 0 -6.3754 270)
			(unlocked yes)
			(layer "F.Fab")
			(hide yes)
			(effects
				(font
					(size 1.016 1.016)
					(thickness 0.1524)
				)
			)
		)
		(duplicate_pad_numbers_are_jumpers no)
		(fp_line
			(start -1.016 2.2352)
			(end -1.016 -2.2352)
			(stroke
				(width 0.1524)
				(type default)
			)
			(layer "F.SilkS")
		)
		(fp_line
			(start 1.016 2.2352)
			(end -1.016 2.2352)
			(stroke
				(width 0.1524)
				(type default)
			)
			(layer "F.SilkS")
		)
		(fp_line
			(start -1.016 -2.2352)
			(end 1.016 -2.2352)
			(stroke
				(width 0.1524)
				(type default)
			)
			(layer "F.SilkS")
		)
		(fp_line
			(start 1.016 -2.2352)
			(end 1.016 2.2352)
			(stroke
				(width 0.1524)
				(type default)
			)
			(layer "F.SilkS")
		)
		(fp_rect
			(start -1.0922 2.3114)
			(end 1.0922 -2.3114)
			(stroke
				(width 0)
				(type default)
			)
			(fill no)
			(layer "F.CrtYd")
		)
		(fp_poly
			(pts
				(xy -1.0922 -2.3114) (xy 1.0922 -2.3114) (xy 1.0922 2.3114) (xy -1.0922 2.3114)
			)
			(stroke
				(width 0)
				(type default)
			)
			(fill no)
			(layer "F.Fab")
		)
		(pad "1" smd rect
			(at 0 -1.397 270)
			(size 1.651 1.27)
			(layers "F.Cu" "F.Mask" "F.Paste")
			(net "P5V_HDD18")
		)
		(pad "2" smd rect
			(at 0 1.397 270)
			(size 1.651 1.27)
			(layers "F.Cu" "F.Mask" "F.Paste")
			(net "5V_PRE_18")
		)
	)
	(footprint ""
		(layer "F.Cu")
		(at 318.2112 -147.8534 180)
		(property "Reference" "R488"
			(at 0 0 180)
			(layer "F.SilkS")
			(hide yes)
			(effects
				(font
					(size 1.27 1.27)
				)
			)
		)
		(property "Value" "220R3F-1-GP"
			(at -0.0254 -2.5146 180)
			(unlocked yes)
			(layer "F.Fab")
			(hide yes)
			(effects
				(font
					(size 1.016 1.016)
					(thickness 0.1524)
				)
			)
		)
		(property "Device Type" "R603H22"
			(at -0.0254 -4.0386 180)
			(unlocked yes)
			(layer "F.Fab")
			(hide yes)
			(effects
				(font
					(size 1.016 1.016)
					(thickness 0.1524)
				)
			)
		)
		(duplicate_pad_numbers_are_jumpers no)
		(fp_line
			(start 0.2032 0)
			(end 0.4826 0)
			(stroke
				(width 0.2032)
				(type default)
			)
			(layer "F.SilkS")
		)
		(fp_line
			(start -0.4826 0)
			(end -0.2032 0)
			(stroke
				(width 0.2032)
				(type default)
			)
			(layer "F.SilkS")
		)
		(fp_rect
			(start -0.5842 1.3335)
			(end 0.5842 -1.3335)
			(stroke
				(width 0)
				(type default)
			)
			(fill no)
			(layer "F.CrtYd")
		)
		(fp_rect
			(start -0.5842 1.3335)
			(end 0.5842 -1.3335)
			(stroke
				(width 0)
				(type default)
			)
			(fill no)
			(layer "F.Fab")
		)
		(pad "1" smd custom
			(at 0 -0.762 180)
			(size 0.2159 0.2159)
			(layers "F.Cu" "F.Mask" "F.Paste")
			(net "HDD_PRSNT_18")
			(options
				(clearance outline)
				(anchor circle)
			)
			(primitives
				(gr_poly
					(pts
						(arc
							(start -0.3302 -0.4318)
							(mid -0.402042 -0.402042)
							(end -0.4318 -0.3302)
						)
						(arc
							(start -0.4318 0.3302)
							(mid -0.402042 0.402042)
							(end -0.3302 0.4318)
						)
						(arc
							(start 0.3302 0.4318)
							(mid 0.402042 0.402042)
							(end 0.4318 0.3302)
						)
						(arc
							(start 0.4318 -0.3302)
							(mid 0.402042 -0.402042)
							(end 0.3302 -0.4318)
						)
					)
					(width 0)
					(fill yes)
				)
			)
		)
		(pad "2" smd custom
			(at 0 0.762 180)
			(size 0.2159 0.2159)
			(layers "F.Cu" "F.Mask" "F.Paste")
			(net "DRIVE_B_18_INS")
			(options
				(clearance outline)
				(anchor circle)
			)
			(primitives
				(gr_poly
					(pts
						(arc
							(start -0.3302 -0.4318)
							(mid -0.402042 -0.402042)
							(end -0.4318 -0.3302)
						)
						(arc
							(start -0.4318 0.3302)
							(mid -0.402042 0.402042)
							(end -0.3302 0.4318)
						)
						(arc
							(start 0.3302 0.4318)
							(mid 0.402042 0.402042)
							(end 0.4318 0.3302)
						)
						(arc
							(start 0.4318 -0.3302)
							(mid 0.402042 -0.402042)
							(end 0.3302 -0.4318)
						)
					)
					(width 0)
					(fill yes)
				)
			)
		)
	)
	(footprint ""
		(layer "F.Cu")
		(at 181.6862 -272.288)
		(property "Reference" "C100"
			(at 0 0 0)
			(layer "F.SilkS")
			(hide yes)
			(effects
				(font
					(size 1.27 1.27)
				)
			)
		)
		(property "Value" "SC4D7U25V5KX-1-GP"
			(at -0.0762 -6.1214 0)
			(unlocked yes)
			(layer "F.Fab")
			(hide yes)
			(effects
				(font
					(size 1.016 1.016)
					(thickness 0.1524)
				)
			)
		)
		(property "Device Type" "C805H58"
			(at -0.0762 -8.1534 0)
			(unlocked yes)
			(layer "F.Fab")
			(hide yes)
			(effects
				(font
					(size 1.016 1.016)
					(thickness 0.1524)
				)
			)
		)
		(duplicate_pad_numbers_are_jumpers no)
		(fp_line
			(start 0.635 0)
			(end -0.635 0)
			(stroke
				(width 0.508)
				(type default)
			)
			(layer "F.SilkS")
		)
		(fp_rect
			(start -0.9652 1.778)
			(end 0.9652 -1.778)
			(stroke
				(width 0)
				(type default)
			)
			(fill no)
			(layer "F.CrtYd")
		)
		(fp_poly
			(pts
				(xy -0.9652 -1.778) (xy 0.9652 -1.778) (xy 0.9652 1.778) (xy -0.9652 1.778)
			)
			(stroke
				(width 0)
				(type default)
			)
			(fill no)
			(layer "F.Fab")
		)
		(pad "1" smd rect
			(at 0 -0.9652)
			(size 1.397 1.143)
			(layers "F.Cu" "F.Mask" "F.Paste")
			(net "P12V_HDD5")
		)
		(pad "2" smd rect
			(at 0 0.9652)
			(size 1.397 1.143)
			(layers "F.Cu" "F.Mask" "F.Paste")
			(net "GND")
		)
	)
	(footprint ""
		(layer "F.Cu")
		(at 77.978 -131.572 90)
		(property "Reference" "R406"
			(at 0 0 90)
			(layer "F.SilkS")
			(hide yes)
			(effects
				(font
					(size 1.27 1.27)
				)
			)
		)
		(property "Value" "4K7R2J-2-GP"
			(at 0.064008 -3.993896 90)
			(unlocked yes)
			(layer "F.Fab")
			(hide yes)
			(effects
				(font
					(size 1.016 1.016)
					(thickness 0.1524)
				)
			)
		)
		(property "Device Type" "R402H16"
			(at 0.064008 -5.517896 90)
			(unlocked yes)
			(layer "F.Fab")
			(hide yes)
			(effects
				(font
					(size 1.016 1.016)
					(thickness 0.1524)
				)
			)
		)
		(duplicate_pad_numbers_are_jumpers no)
		(fp_line
			(start 0.508 -0.9398)
			(end -0.508 -0.9398)
			(stroke
				(width 0.1524)
				(type default)
			)
			(layer "F.SilkS")
		)
		(fp_line
			(start -0.508 -0.9398)
			(end -0.508 0.9398)
			(stroke
				(width 0.1524)
				(type default)
			)
			(layer "F.SilkS")
		)
		(fp_rect
			(start -0.508 0.9398)
			(end 0.508 -0.9398)
			(stroke
				(width 0)
				(type default)
			)
			(fill no)
			(layer "F.CrtYd")
		)
		(fp_rect
			(start -0.508 0.9398)
			(end 0.508 -0.9398)
			(stroke
				(width 0)
				(type default)
			)
			(fill no)
			(layer "F.Fab")
		)
		(pad "1" smd custom
			(at 0 -0.4445 90)
			(size 0.1397 0.1397)
			(layers "F.Cu" "F.Mask" "F.Paste")
			(net "P12V_B")
			(options
				(clearance outline)
				(anchor circle)
			)
			(primitives
				(gr_poly
					(pts
						(arc
							(start -0.1778 -0.2794)
							(mid -0.249642 -0.249642)
							(end -0.2794 -0.1778)
						)
						(arc
							(start -0.2794 0.1778)
							(mid -0.249642 0.249642)
							(end -0.1778 0.2794)
						)
						(arc
							(start 0.1778 0.2794)
							(mid 0.249642 0.249642)
							(end 0.2794 0.1778)
						)
						(arc
							(start 0.2794 -0.1778)
							(mid 0.249642 -0.249642)
							(end 0.1778 -0.2794)
						)
					)
					(width 0)
					(fill yes)
				)
			)
		)
		(pad "2" smd custom
			(at 0 0.4445 90)
			(size 0.1397 0.1397)
			(layers "F.Cu" "F.Mask" "F.Paste")
			(net "SW_HDD_R14")
			(options
				(clearance outline)
				(anchor circle)
			)
			(primitives
				(gr_poly
					(pts
						(arc
							(start -0.1778 -0.2794)
							(mid -0.249642 -0.249642)
							(end -0.2794 -0.1778)
						)
						(arc
							(start -0.2794 0.1778)
							(mid -0.249642 0.249642)
							(end -0.1778 0.2794)
						)
						(arc
							(start 0.1778 0.2794)
							(mid 0.249642 0.249642)
							(end 0.2794 0.1778)
						)
						(arc
							(start 0.2794 -0.1778)
							(mid 0.249642 -0.249642)
							(end 0.1778 -0.2794)
						)
					)
					(width 0)
					(fill yes)
				)
			)
		)
	)
	(footprint ""
		(layer "F.Cu")
		(at 314.623196 -372.237 -90)
		(property "Reference" "R972"
			(at 0 0 270)
			(layer "F.SilkS")
			(hide yes)
			(effects
				(font
					(size 1.27 1.27)
				)
			)
		)
		(property "Value" "1KR5F-1-GP"
			(at 0 -8.9535 270)
			(unlocked yes)
			(layer "F.Fab")
			(hide yes)
			(effects
				(font
					(size 1.27 1.016)
					(thickness 0.1524)
				)
			)
		)
		(property "Device Type" "R805H24"
			(at 0 -10.6299 270)
			(unlocked yes)
			(layer "F.Fab")
			(hide yes)
			(effects
				(font
					(size 1.27 1.016)
					(thickness 0.1524)
				)
			)
		)
		(duplicate_pad_numbers_are_jumpers no)
		(fp_line
			(start -0.889 1.7018)
			(end 0.889 1.7018)
			(stroke
				(width 0.1524)
				(type default)
			)
			(layer "F.SilkS")
		)
		(fp_line
			(start 0.889 1.7018)
			(end 0.889 -0.508)
			(stroke
				(width 0.1524)
				(type default)
			)
			(layer "F.SilkS")
		)
		(fp_line
			(start -0.889 0.0762)
			(end -0.889 1.7018)
			(stroke
				(width 0.1524)
				(type default)
			)
			(layer "F.SilkS")
		)
		(fp_line
			(start -0.889 -1.7018)
			(end -0.889 0.2794)
			(stroke
				(width 0.1524)
				(type default)
			)
			(layer "F.SilkS")
		)
		(fp_line
			(start 0.889 -1.7018)
			(end 0.889 -0.381)
			(stroke
				(width 0.1524)
				(type default)
			)
			(layer "F.SilkS")
		)
		(fp_line
			(start 0.889 -1.7018)
			(end -0.889 -1.7018)
			(stroke
				(width 0.1524)
				(type default)
			)
			(layer "F.SilkS")
		)
		(fp_poly
			(pts
				(xy 0.9652 -1.778) (xy 0.9652 1.778) (xy -0.9652 1.778) (xy -0.9652 -1.778)
			)
			(stroke
				(width 0)
				(type default)
			)
			(fill no)
			(layer "F.CrtYd")
		)
		(fp_rect
			(start -0.9652 1.778)
			(end 0.9652 -1.778)
			(stroke
				(width 0)
				(type default)
			)
			(fill no)
			(layer "F.Fab")
		)
		(pad "1" smd rect
			(at 0 -0.9652 270)
			(size 1.397 1.143)
			(layers "F.Cu" "F.Mask" "F.Paste")
			(net "FAN_YELLOW_2")
		)
		(pad "2" smd rect
			(at 0 0.9652 270)
			(size 1.397 1.143)
			(layers "F.Cu" "F.Mask" "F.Paste")
			(net "FAN_LED_YELLOW_2")
		)
	)
	(footprint ""
		(layer "F.Cu")
		(at 287.83661 -238.694468 -90)
		(property "Reference" "SAS1"
			(at 0 0 270)
			(layer "F.SilkS")
			(hide yes)
			(effects
				(font
					(size 1.27 1.27)
				)
			)
		)
		(property "Value" "AMP-CONN342-10R-2-GP"
			(at 20.955 -16.7386 270)
			(unlocked yes)
			(layer "F.Fab")
			(hide yes)
			(effects
				(font
					(size 1.016 1.016)
					(thickness 0.1524)
				)
			)
		)
		(property "Device Type" "PREFIT-342P-668151H483"
			(at 20.955 -18.2626 270)
			(unlocked yes)
			(layer "F.Fab")
			(hide yes)
			(effects
				(font
					(size 1.016 1.016)
					(thickness 0.1524)
				)
			)
		)
		(duplicate_pad_numbers_are_jumpers no)
		(fp_line
			(start 65.3923 13.0048)
			(end -1.9431 13.0048)
			(stroke
				(width 0.1524)
				(type default)
			)
			(layer "F.SilkS")
		)
		(fp_line
			(start 0.381 -1.905)
			(end 1.397 -1.905)
			(stroke
				(width 0.1524)
				(type default)
			)
			(layer "F.SilkS")
		)
		(fp_line
			(start 0.381 -1.905)
			(end 0.381 -2.6162)
			(stroke
				(width 0.1524)
				(type default)
			)
			(layer "F.SilkS")
		)
		(fp_line
			(start 1.397 -1.905)
			(end 1.397 -2.6162)
			(stroke
				(width 0.1524)
				(type default)
			)
			(layer "F.SilkS")
		)
		(fp_line
			(start -1.9431 -2.6162)
			(end -1.9431 13.0048)
			(stroke
				(width 0.1524)
				(type default)
			)
			(layer "F.SilkS")
		)
		(fp_line
			(start 0.381 -2.6162)
			(end -1.9431 -2.6162)
			(stroke
				(width 0.1524)
				(type default)
			)
			(layer "F.SilkS")
		)
		(fp_line
			(start 1.397 -2.6162)
			(end 65.3923 -2.6162)
			(stroke
				(width 0.1524)
				(type default)
			)
			(layer "F.SilkS")
		)
		(fp_line
			(start 65.3923 -2.6162)
			(end 65.3923 13.0048)
			(stroke
				(width 0.1524)
				(type default)
			)
			(layer "F.SilkS")
		)
		(fp_poly
			(pts
				(xy -1.9431 13.0048) (xy -1.9431 -2.6162) (xy 0.381 -2.6162) (xy 0.381 -1.905) (xy 1.397 -1.905)
				(xy 1.397 -2.6162) (xy 26.035 -2.6162) (xy 26.035 -0.735076) (xy -0.635 -0.735076) (xy -0.635 11.335004)
				(xy 64.77 11.335004) (xy 64.77 -0.735076) (xy 36.957 -0.735076) (xy 36.957 -2.6162) (xy 65.3923 -2.6162)
				(xy 65.3923 13.0048)
			)
			(stroke
				(width 0)
				(type default)
			)
			(fill yes)
			(layer "F.SilkS")
		)
		(fp_poly
			(pts
				(arc
					(start 64.516 10.414)
					(mid 64.262 10.668)
					(end 64.008 10.414)
				)
				(arc
					(start 64.008 10.16)
					(mid 64.262 9.906)
					(end 64.516 10.16)
				)
			)
			(stroke
				(width 0)
				(type default)
			)
			(fill yes)
			(layer "F.SilkS")
		)
		(fp_poly
			(pts
				(arc
					(start 64.516 9.144)
					(mid 64.262 9.398)
					(end 64.008 9.144)
				)
				(arc
					(start 64.008 8.89)
					(mid 64.262 8.636)
					(end 64.516 8.89)
				)
			)
			(stroke
				(width 0)
				(type default)
			)
			(fill yes)
			(layer "F.SilkS")
		)
		(fp_poly
			(pts
				(arc
					(start 64.516 7.874)
					(mid 64.262 8.128)
					(end 64.008 7.874)
				)
				(arc
					(start 64.008 7.62)
					(mid 64.262 7.366)
					(end 64.516 7.62)
				)
			)
			(stroke
				(width 0)
				(type default)
			)
			(fill yes)
			(layer "F.SilkS")
		)
		(fp_poly
			(pts
				(arc
					(start 64.516 6.604)
					(mid 64.262 6.858)
					(end 64.008 6.604)
				)
				(arc
					(start 64.008 6.35)
					(mid 64.262 6.096)
					(end 64.516 6.35)
				)
			)
			(stroke
				(width 0)
				(type default)
			)
			(fill yes)
			(layer "F.SilkS")
		)
		(fp_poly
			(pts
				(arc
					(start 64.516 5.334)
					(mid 64.262 5.588)
					(end 64.008 5.334)
				)
				(arc
					(start 64.008 5.08)
					(mid 64.262 4.826)
					(end 64.516 5.08)
				)
			)
			(stroke
				(width 0)
				(type default)
			)
			(fill yes)
			(layer "F.SilkS")
		)
		(fp_poly
			(pts
				(arc
					(start 64.516 4.064)
					(mid 64.262 4.318)
					(end 64.008 4.064)
				)
				(arc
					(start 64.008 3.81)
					(mid 64.262 3.556)
					(end 64.516 3.81)
				)
			)
			(stroke
				(width 0)
				(type default)
			)
			(fill yes)
			(layer "F.SilkS")
		)
		(fp_poly
			(pts
				(arc
					(start 64.516 2.794)
					(mid 64.262 3.048)
					(end 64.008 2.794)
				)
				(arc
					(start 64.008 2.54)
					(mid 64.262 2.286)
					(end 64.516 2.54)
				)
			)
			(stroke
				(width 0)
				(type default)
			)
			(fill yes)
			(layer "F.SilkS")
		)
		(fp_poly
			(pts
				(arc
					(start 64.516 1.524)
					(mid 64.262 1.778)
					(end 64.008 1.524)
				)
				(arc
					(start 64.008 1.27)
					(mid 64.262 1.016)
					(end 64.516 1.27)
				)
			)
			(stroke
				(width 0)
				(type default)
			)
			(fill yes)
			(layer "F.SilkS")
		)
		(fp_poly
			(pts
				(arc
					(start 64.516 0.254)
					(mid 64.262 0.508)
					(end 64.008 0.254)
				)
				(arc
					(start 64.008 0)
					(mid 64.262 -0.254)
					(end 64.516 0)
				)
			)
			(stroke
				(width 0)
				(type default)
			)
			(fill yes)
			(layer "F.SilkS")
		)
		(fp_rect
			(start -5.3848 16.0782)
			(end 68.3768 -5.4864)
			(stroke
				(width 0)
				(type default)
			)
			(fill no)
			(layer "B.CrtYd")
		)
		(fp_rect
			(start -1.6891 12.7508)
			(end 65.1383 -2.3622)
			(stroke
				(width 0)
				(type default)
			)
			(fill no)
			(layer "F.CrtYd")
		)
		(fp_poly
			(pts
				(xy -6.6929 17.7546) (xy -6.6929 -7.366) (xy 70.1421 -7.366) (xy 70.1421 0) (xy 65.6463 0) (xy 65.6463 -2.8702)
				(xy -2.1971 -2.8702) (xy -2.1971 13.2588) (xy 65.6463 13.2588) (xy 65.6463 0.0127) (xy 70.1421 0.0127)
				(xy 70.1421 17.7546)
			)
			(stroke
				(width 0)
				(type default)
			)
			(fill no)
			(layer "F.CrtYd")
		)
		(fp_poly
			(pts
				(xy -2.1971 13.2588) (xy -2.1971 -2.8702) (xy 65.6463 -2.8702) (xy 65.6463 0) (xy 65.1383 0) (xy 65.1383 -2.3622)
				(xy -1.6891 -2.3622) (xy -1.6891 12.7508) (xy 65.1383 12.7508) (xy 65.1383 0.0127) (xy 65.6463 0.0127)
				(xy 65.6463 13.2588)
			)
			(stroke
				(width 0)
				(type default)
			)
			(fill no)
			(layer "F.CrtYd")
		)
		(fp_rect
			(start -10.3886 21.082)
			(end 73.3806 -10.4902)
			(stroke
				(width 0)
				(type default)
			)
			(fill no)
			(layer "B.Fab")
		)
		(fp_rect
			(start -5.3848 16.0782)
			(end 68.3768 -5.4864)
			(stroke
				(width 0)
				(type default)
			)
			(fill no)
			(layer "B.Fab")
		)
		(fp_rect
			(start -11.6967 22.7584)
			(end 75.1459 -12.3698)
			(stroke
				(width 0)
				(type default)
			)
			(fill no)
			(layer "F.Fab")
		)
		(fp_rect
			(start -6.6929 17.7546)
			(end 70.1421 -7.366)
			(stroke
				(width 0)
				(type default)
			)
			(fill no)
			(layer "F.Fab")
		)
		(fp_rect
			(start -2.1971 13.2588)
			(end 65.6463 -2.8702)
			(stroke
				(width 0)
				(type default)
			)
			(fill no)
			(layer "F.Fab")
		)
		(fp_text user "Press Fit"
			(at 26.416 -1.6002 270)
			(unlocked yes)
			(layer "F.SilkS")
			(effects
				(font
					(size 1.016 1.016)
					(thickness 0.1524)
				)
				(justify left)
			)
		)
		(fp_text user "Can not place BGA,CSP,Wave Solder Component"
			(at 6.985 18.8468 270)
			(unlocked yes)
			(layer "B.Fab")
			(effects
				(font
					(size 1.016 1.016)
					(thickness 0.1524)
				)
				(justify left)
			)
		)
		(fp_text user "Can not place BGA,CSP,Wave Solder Component"
			(at 7.62 20.4978 270)
			(unlocked yes)
			(layer "F.Fab")
			(effects
				(font
					(size 1.016 1.016)
					(thickness 0.1524)
				)
				(justify left)
			)
		)
		(fp_text user "High Limit 2mm"
			(at 24.003 15.5448 270)
			(unlocked yes)
			(layer "F.Fab")
			(effects
				(font
					(size 1.016 1.016)
					(thickness 0.1524)
				)
				(justify left)
			)
		)
		(pad "A1" thru_hole circle
			(at 0 0 270)
			(size 0.762 0.762)
			(drill 0.359918)
			(layers "*.Cu" "*.Mask")
			(remove_unused_layers no)
			(net "PHY_DRV_B_TO_SCC_B_5_DN")
			(clearance 0.1651)
			(thermal_gap 0.1651)
		)
		(pad "A2" thru_hole circle
			(at 1.800098 0.999998 270)
			(size 0.762 0.762)
			(drill 0.359918)
			(layers "*.Cu" "*.Mask")
			(remove_unused_layers no)
			(net "PHY_DRV_B_TO_SCC_B_4_DN")
			(clearance 0.1651)
			(thermal_gap 0.1651)
		)
		(pad "A3" thru_hole circle
			(at 3.599942 0 270)
			(size 0.762 0.762)
			(drill 0.359918)
			(layers "*.Cu" "*.Mask")
			(remove_unused_layers no)
			(net "PHY_DRV_B_TO_SCC_B_3_DN")
			(clearance 0.1651)
			(thermal_gap 0.1651)
		)
		(pad "A4" thru_hole circle
			(at 5.40004 0.999998 270)
			(size 0.762 0.762)
			(drill 0.359918)
			(layers "*.Cu" "*.Mask")
			(remove_unused_layers no)
			(net "PHY_DRV_B_TO_SCC_B_2_DN")
			(clearance 0.1651)
			(thermal_gap 0.1651)
		)
		(pad "A5" thru_hole circle
			(at 7.199884 0 270)
			(size 0.762 0.762)
			(drill 0.359918)
			(layers "*.Cu" "*.Mask")
			(remove_unused_layers no)
			(net "PHY_DRV_B_TO_SCC_B_1_DN")
			(clearance 0.1651)
			(thermal_gap 0.1651)
		)
		(pad "A6" thru_hole circle
			(at 8.999982 0.999998 270)
			(size 0.762 0.762)
			(drill 0.359918)
			(layers "*.Cu" "*.Mask")
			(remove_unused_layers no)
			(net "PHY_DRV_B_TO_SCC_B_0_DN")
			(clearance 0.1651)
			(thermal_gap 0.1651)
		)
		(pad "A7" thru_hole circle
			(at 10.80008 0 270)
			(size 0.762 0.762)
			(drill 0.359918)
			(layers "*.Cu" "*.Mask")
			(remove_unused_layers no)
			(net "PHY_DRV_B_TO_SCC_B_6_DN")
			(clearance 0.1651)
			(thermal_gap 0.1651)
		)
		(pad "A8" thru_hole circle
			(at 12.599924 0.999998 270)
			(size 0.762 0.762)
			(drill 0.359918)
			(layers "*.Cu" "*.Mask")
			(remove_unused_layers no)
			(net "PHY_DRV_B_TO_SCC_B_7_DN")
			(clearance 0.1651)
			(thermal_gap 0.1651)
		)
		(pad "A9" thru_hole circle
			(at 14.400022 0 270)
			(size 0.762 0.762)
			(drill 0.359918)
			(layers "*.Cu" "*.Mask")
			(remove_unused_layers no)
			(net "PHY_DRV_B_TO_SCC_B_8_DN")
			(clearance 0.1651)
			(thermal_gap 0.1651)
		)
		(pad "A10" thru_hole circle
			(at 16.20012 0.999998 270)
			(size 0.762 0.762)
			(drill 0.359918)
			(layers "*.Cu" "*.Mask")
			(remove_unused_layers no)
			(net "PHY_DRV_B_TO_SCC_B_9_DN")
			(clearance 0.1651)
			(thermal_gap 0.1651)
		)
		(pad "A11" thru_hole circle
			(at 17.999964 0 270)
			(size 0.762 0.762)
			(drill 0.359918)
			(layers "*.Cu" "*.Mask")
			(remove_unused_layers no)
			(net "PHY_DRV_B_TO_SCC_B_10_DN")
			(clearance 0.1651)
			(thermal_gap 0.1651)
		)
		(pad "A12" thru_hole circle
			(at 19.800062 0.999998 270)
			(size 0.762 0.762)
			(drill 0.359918)
			(layers "*.Cu" "*.Mask")
			(remove_unused_layers no)
			(net "PHY_DRV_B_TO_SCC_B_11_DN")
			(clearance 0.1651)
			(thermal_gap 0.1651)
		)
		(pad "A13" thru_hole circle
			(at 21.599906 0 270)
			(size 0.762 0.762)
			(drill 0.359918)
			(layers "*.Cu" "*.Mask")
			(remove_unused_layers no)
			(net "PHY_DRV_B_TO_SCC_B_12_DN")
			(clearance 0.1651)
			(thermal_gap 0.1651)
		)
		(pad "A14" thru_hole circle
			(at 23.400004 0.999998 270)
			(size 0.762 0.762)
			(drill 0.359918)
			(layers "*.Cu" "*.Mask")
			(remove_unused_layers no)
			(net "PHY_DRV_B_TO_SCC_B_13_DN")
			(clearance 0.1651)
			(thermal_gap 0.1651)
		)
		(pad "A15" thru_hole circle
			(at 25.200102 0 270)
			(size 0.762 0.762)
			(drill 0.359918)
			(layers "*.Cu" "*.Mask")
			(remove_unused_layers no)
			(net "PHY_DRV_B_TO_SCC_B_14_DN")
			(clearance 0.1651)
			(thermal_gap 0.1651)
		)
		(pad "A16" thru_hole circle
			(at 26.999946 0.999998 270)
			(size 0.762 0.762)
			(drill 0.359918)
			(layers "*.Cu" "*.Mask")
			(remove_unused_layers no)
			(net "PHY_DRV_B_TO_SCC_B_15_DN")
			(clearance 0.1651)
			(thermal_gap 0.1651)
		)
		(pad "A17" thru_hole circle
			(at 28.800044 0 270)
			(size 0.762 0.762)
			(drill 0.359918)
			(layers "*.Cu" "*.Mask")
			(remove_unused_layers no)
			(net "PHY_DRV_B_TO_SCC_B_16_DN")
			(clearance 0.1651)
			(thermal_gap 0.1651)
		)
		(pad "A18" thru_hole circle
			(at 30.599888 0.999998 270)
			(size 0.762 0.762)
			(drill 0.359918)
			(layers "*.Cu" "*.Mask")
			(remove_unused_layers no)
			(net "PHY_DRV_B_TO_SCC_B_17_DN")
			(clearance 0.1651)
			(thermal_gap 0.1651)
		)
		(pad "A19" thru_hole circle
			(at 32.399986 0 270)
			(size 0.762 0.762)
			(drill 0.359918)
			(layers "*.Cu" "*.Mask")
			(remove_unused_layers no)
			(net "PHY_DRV_B_TO_SCC_B_23_DN")
			(clearance 0.1651)
			(thermal_gap 0.1651)
		)
		(pad "A20" thru_hole circle
			(at 34.200084 0.999998 270)
			(size 0.762 0.762)
			(drill 0.359918)
			(layers "*.Cu" "*.Mask")
			(remove_unused_layers no)
			(net "PHY_DRV_B_TO_SCC_B_22_DN")
			(clearance 0.1651)
			(thermal_gap 0.1651)
		)
		(pad "A21" thru_hole circle
			(at 35.999928 0 270)
			(size 0.762 0.762)
			(drill 0.359918)
			(layers "*.Cu" "*.Mask")
			(remove_unused_layers no)
			(net "PHY_DRV_B_TO_SCC_B_21_DN")
			(clearance 0.1651)
			(thermal_gap 0.1651)
		)
		(pad "A22" thru_hole circle
			(at 37.800026 0.999998 270)
			(size 0.762 0.762)
			(drill 0.359918)
			(layers "*.Cu" "*.Mask")
			(remove_unused_layers no)
			(net "PHY_DRV_B_TO_SCC_B_20_DN")
			(clearance 0.1651)
			(thermal_gap 0.1651)
		)
		(pad "A23" thru_hole circle
			(at 39.600124 0 270)
			(size 0.762 0.762)
			(drill 0.359918)
			(layers "*.Cu" "*.Mask")
			(remove_unused_layers no)
			(net "PHY_DRV_B_TO_SCC_B_19_DN")
			(clearance 0.1651)
			(thermal_gap 0.1651)
		)
		(pad "A24" thru_hole circle
			(at 41.399968 0.999998 270)
			(size 0.762 0.762)
			(drill 0.359918)
			(layers "*.Cu" "*.Mask")
			(remove_unused_layers no)
			(net "PHY_DRV_B_TO_SCC_B_18_DN")
			(clearance 0.1651)
			(thermal_gap 0.1651)
		)
		(pad "A25" thru_hole circle
			(at 43.200066 0 270)
			(size 0.762 0.762)
			(drill 0.359918)
			(layers "*.Cu" "*.Mask")
			(remove_unused_layers no)
			(net "PHY_DRV_B_TO_SCC_B_24_DN")
			(clearance 0.1651)
			(thermal_gap 0.1651)
		)
		(pad "A26" thru_hole circle
			(at 44.99991 0.999998 270)
			(size 0.762 0.762)
			(drill 0.359918)
			(layers "*.Cu" "*.Mask")
			(remove_unused_layers no)
			(net "PHY_DRV_B_TO_SCC_B_25_DN")
			(clearance 0.1651)
			(thermal_gap 0.1651)
		)
		(pad "A27" thru_hole circle
			(at 46.800008 0 270)
			(size 0.762 0.762)
			(drill 0.359918)
			(layers "*.Cu" "*.Mask")
			(remove_unused_layers no)
			(net "PHY_DRV_B_TO_SCC_B_26_DN")
			(clearance 0.1651)
			(thermal_gap 0.1651)
		)
		(pad "A28" thru_hole circle
			(at 48.600106 0.999998 270)
			(size 0.762 0.762)
			(drill 0.359918)
			(layers "*.Cu" "*.Mask")
			(remove_unused_layers no)
			(net "PHY_DRV_B_TO_SCC_B_27_DN")
			(clearance 0.1651)
			(thermal_gap 0.1651)
		)
		(pad "A29" thru_hole circle
			(at 50.39995 0 270)
			(size 0.762 0.762)
			(drill 0.359918)
			(layers "*.Cu" "*.Mask")
			(remove_unused_layers no)
			(net "PHY_DRV_B_TO_SCC_B_28_DN")
			(clearance 0.1651)
			(thermal_gap 0.1651)
		)
		(pad "A30" thru_hole circle
			(at 52.200048 0.999998 270)
			(size 0.762 0.762)
			(drill 0.359918)
			(layers "*.Cu" "*.Mask")
			(remove_unused_layers no)
			(net "PHY_DRV_B_TO_SCC_B_29_DN")
			(clearance 0.1651)
			(thermal_gap 0.1651)
		)
		(pad "A31" thru_hole circle
			(at 53.999892 0 270)
			(size 0.762 0.762)
			(drill 0.359918)
			(layers "*.Cu" "*.Mask")
			(remove_unused_layers no)
			(net "PHY_DRV_B_TO_SCC_B_35_DN")
			(clearance 0.1651)
			(thermal_gap 0.1651)
		)
		(pad "A32" thru_hole circle
			(at 55.79999 0.999998 270)
			(size 0.762 0.762)
			(drill 0.359918)
			(layers "*.Cu" "*.Mask")
			(remove_unused_layers no)
			(net "PHY_DRV_B_TO_SCC_B_34_DN")
			(clearance 0.1651)
			(thermal_gap 0.1651)
		)
		(pad "A33" thru_hole circle
			(at 57.600088 0 270)
			(size 0.762 0.762)
			(drill 0.359918)
			(layers "*.Cu" "*.Mask")
			(remove_unused_layers no)
			(net "PHY_DRV_B_TO_SCC_B_33_DN")
			(clearance 0.1651)
			(thermal_gap 0.1651)
		)
		(pad "A34" thru_hole circle
			(at 59.399932 0.999998 270)
			(size 0.762 0.762)
			(drill 0.359918)
			(layers "*.Cu" "*.Mask")
			(remove_unused_layers no)
			(net "PHY_DRV_B_TO_SCC_B_32_DN")
			(clearance 0.1651)
			(thermal_gap 0.1651)
		)
		(pad "A35" thru_hole circle
			(at 61.20003 0 270)
			(size 0.762 0.762)
			(drill 0.359918)
			(layers "*.Cu" "*.Mask")
			(remove_unused_layers no)
			(net "PHY_DRV_B_TO_SCC_B_31_DN")
			(clearance 0.1651)
			(thermal_gap 0.1651)
		)
		(pad "A36" thru_hole circle
			(at 62.999874 0.999998 270)
			(size 0.762 0.762)
			(drill 0.359918)
			(layers "*.Cu" "*.Mask")
			(remove_unused_layers no)
			(net "PHY_DRV_B_TO_SCC_B_30_DN")
			(clearance 0.1651)
			(thermal_gap 0.1651)
		)
		(pad "B1" thru_hole circle
			(at 0 1.400048 270)
			(size 0.762 0.762)
			(drill 0.359918)
			(layers "*.Cu" "*.Mask")
			(remove_unused_layers no)
			(net "PHY_DRV_B_TO_SCC_B_5_DP")
			(clearance 0.1651)
			(thermal_gap 0.1651)
		)
		(pad "B2" thru_hole circle
			(at 1.800098 2.400046 270)
			(size 0.762 0.762)
			(drill 0.359918)
			(layers "*.Cu" "*.Mask")
			(remove_unused_layers no)
			(net "PHY_DRV_B_TO_SCC_B_4_DP")
			(clearance 0.1651)
			(thermal_gap 0.1651)
		)
		(pad "B3" thru_hole circle
			(at 3.599942 1.400048 270)
			(size 0.762 0.762)
			(drill 0.359918)
			(layers "*.Cu" "*.Mask")
			(remove_unused_layers no)
			(net "PHY_DRV_B_TO_SCC_B_3_DP")
			(clearance 0.1651)
			(thermal_gap 0.1651)
		)
		(pad "B4" thru_hole circle
			(at 5.40004 2.400046 270)
			(size 0.762 0.762)
			(drill 0.359918)
			(layers "*.Cu" "*.Mask")
			(remove_unused_layers no)
			(net "PHY_DRV_B_TO_SCC_B_2_DP")
			(clearance 0.1651)
			(thermal_gap 0.1651)
		)
		(pad "B5" thru_hole circle
			(at 7.199884 1.400048 270)
			(size 0.762 0.762)
			(drill 0.359918)
			(layers "*.Cu" "*.Mask")
			(remove_unused_layers no)
			(net "PHY_DRV_B_TO_SCC_B_1_DP")
			(clearance 0.1651)
			(thermal_gap 0.1651)
		)
		(pad "B6" thru_hole circle
			(at 8.999982 2.400046 270)
			(size 0.762 0.762)
			(drill 0.359918)
			(layers "*.Cu" "*.Mask")
			(remove_unused_layers no)
			(net "PHY_DRV_B_TO_SCC_B_0_DP")
			(clearance 0.1651)
			(thermal_gap 0.1651)
		)
		(pad "B7" thru_hole circle
			(at 10.80008 1.400048 270)
			(size 0.762 0.762)
			(drill 0.359918)
			(layers "*.Cu" "*.Mask")
			(remove_unused_layers no)
			(net "PHY_DRV_B_TO_SCC_B_6_DP")
			(clearance 0.1651)
			(thermal_gap 0.1651)
		)
		(pad "B8" thru_hole circle
			(at 12.599924 2.400046 270)
			(size 0.762 0.762)
			(drill 0.359918)
			(layers "*.Cu" "*.Mask")
			(remove_unused_layers no)
			(net "PHY_DRV_B_TO_SCC_B_7_DP")
			(clearance 0.1651)
			(thermal_gap 0.1651)
		)
		(pad "B9" thru_hole circle
			(at 14.400022 1.400048 270)
			(size 0.762 0.762)
			(drill 0.359918)
			(layers "*.Cu" "*.Mask")
			(remove_unused_layers no)
			(net "PHY_DRV_B_TO_SCC_B_8_DP")
			(clearance 0.1651)
			(thermal_gap 0.1651)
		)
		(pad "B10" thru_hole circle
			(at 16.20012 2.400046 270)
			(size 0.762 0.762)
			(drill 0.359918)
			(layers "*.Cu" "*.Mask")
			(remove_unused_layers no)
			(net "PHY_DRV_B_TO_SCC_B_9_DP")
			(clearance 0.1651)
			(thermal_gap 0.1651)
		)
		(pad "B11" thru_hole circle
			(at 17.999964 1.400048 270)
			(size 0.762 0.762)
			(drill 0.359918)
			(layers "*.Cu" "*.Mask")
			(remove_unused_layers no)
			(net "PHY_DRV_B_TO_SCC_B_10_DP")
			(clearance 0.1651)
			(thermal_gap 0.1651)
		)
		(pad "B12" thru_hole circle
			(at 19.800062 2.400046 270)
			(size 0.762 0.762)
			(drill 0.359918)
			(layers "*.Cu" "*.Mask")
			(remove_unused_layers no)
			(net "PHY_DRV_B_TO_SCC_B_11_DP")
			(clearance 0.1651)
			(thermal_gap 0.1651)
		)
		(pad "B13" thru_hole circle
			(at 21.599906 1.400048 270)
			(size 0.762 0.762)
			(drill 0.359918)
			(layers "*.Cu" "*.Mask")
			(remove_unused_layers no)
			(net "PHY_DRV_B_TO_SCC_B_12_DP")
			(clearance 0.1651)
			(thermal_gap 0.1651)
		)
		(pad "B14" thru_hole circle
			(at 23.400004 2.400046 270)
			(size 0.762 0.762)
			(drill 0.359918)
			(layers "*.Cu" "*.Mask")
			(remove_unused_layers no)
			(net "PHY_DRV_B_TO_SCC_B_13_DP")
			(clearance 0.1651)
			(thermal_gap 0.1651)
		)
		(pad "B15" thru_hole circle
			(at 25.200102 1.400048 270)
			(size 0.762 0.762)
			(drill 0.359918)
			(layers "*.Cu" "*.Mask")
			(remove_unused_layers no)
			(net "PHY_DRV_B_TO_SCC_B_14_DP")
			(clearance 0.1651)
			(thermal_gap 0.1651)
		)
		(pad "B16" thru_hole circle
			(at 26.999946 2.400046 270)
			(size 0.762 0.762)
			(drill 0.359918)
			(layers "*.Cu" "*.Mask")
			(remove_unused_layers no)
			(net "PHY_DRV_B_TO_SCC_B_15_DP")
			(clearance 0.1651)
			(thermal_gap 0.1651)
		)
		(pad "B17" thru_hole circle
			(at 28.800044 1.400048 270)
			(size 0.762 0.762)
			(drill 0.359918)
			(layers "*.Cu" "*.Mask")
			(remove_unused_layers no)
			(net "PHY_DRV_B_TO_SCC_B_16_DP")
			(clearance 0.1651)
			(thermal_gap 0.1651)
		)
		(pad "B18" thru_hole circle
			(at 30.599888 2.400046 270)
			(size 0.762 0.762)
			(drill 0.359918)
			(layers "*.Cu" "*.Mask")
			(remove_unused_layers no)
			(net "PHY_DRV_B_TO_SCC_B_17_DP")
			(clearance 0.1651)
			(thermal_gap 0.1651)
		)
		(pad "B19" thru_hole circle
			(at 32.399986 1.400048 270)
			(size 0.762 0.762)
			(drill 0.359918)
			(layers "*.Cu" "*.Mask")
			(remove_unused_layers no)
			(net "PHY_DRV_B_TO_SCC_B_23_DP")
			(clearance 0.1651)
			(thermal_gap 0.1651)
		)
		(pad "B20" thru_hole circle
			(at 34.200084 2.400046 270)
			(size 0.762 0.762)
			(drill 0.359918)
			(layers "*.Cu" "*.Mask")
			(remove_unused_layers no)
			(net "PHY_DRV_B_TO_SCC_B_22_DP")
			(clearance 0.1651)
			(thermal_gap 0.1651)
		)
		(pad "B21" thru_hole circle
			(at 35.999928 1.400048 270)
			(size 0.762 0.762)
			(drill 0.359918)
			(layers "*.Cu" "*.Mask")
			(remove_unused_layers no)
			(net "PHY_DRV_B_TO_SCC_B_21_DP")
			(clearance 0.1651)
			(thermal_gap 0.1651)
		)
		(pad "B22" thru_hole circle
			(at 37.800026 2.400046 270)
			(size 0.762 0.762)
			(drill 0.359918)
			(layers "*.Cu" "*.Mask")
			(remove_unused_layers no)
			(net "PHY_DRV_B_TO_SCC_B_20_DP")
			(clearance 0.1651)
			(thermal_gap 0.1651)
		)
		(pad "B23" thru_hole circle
			(at 39.600124 1.400048 270)
			(size 0.762 0.762)
			(drill 0.359918)
			(layers "*.Cu" "*.Mask")
			(remove_unused_layers no)
			(net "PHY_DRV_B_TO_SCC_B_19_DP")
			(clearance 0.1651)
			(thermal_gap 0.1651)
		)
		(pad "B24" thru_hole circle
			(at 41.399968 2.400046 270)
			(size 0.762 0.762)
			(drill 0.359918)
			(layers "*.Cu" "*.Mask")
			(remove_unused_layers no)
			(net "PHY_DRV_B_TO_SCC_B_18_DP")
			(clearance 0.1651)
			(thermal_gap 0.1651)
		)
		(pad "B25" thru_hole circle
			(at 43.200066 1.400048 270)
			(size 0.762 0.762)
			(drill 0.359918)
			(layers "*.Cu" "*.Mask")
			(remove_unused_layers no)
			(net "PHY_DRV_B_TO_SCC_B_24_DP")
			(clearance 0.1651)
			(thermal_gap 0.1651)
		)
		(pad "B26" thru_hole circle
			(at 44.99991 2.400046 270)
			(size 0.762 0.762)
			(drill 0.359918)
			(layers "*.Cu" "*.Mask")
			(remove_unused_layers no)
			(net "PHY_DRV_B_TO_SCC_B_25_DP")
			(clearance 0.1651)
			(thermal_gap 0.1651)
		)
		(pad "B27" thru_hole circle
			(at 46.800008 1.400048 270)
			(size 0.762 0.762)
			(drill 0.359918)
			(layers "*.Cu" "*.Mask")
			(remove_unused_layers no)
			(net "PHY_DRV_B_TO_SCC_B_26_DP")
			(clearance 0.1651)
			(thermal_gap 0.1651)
		)
		(pad "B28" thru_hole circle
			(at 48.600106 2.400046 270)
			(size 0.762 0.762)
			(drill 0.359918)
			(layers "*.Cu" "*.Mask")
			(remove_unused_layers no)
			(net "PHY_DRV_B_TO_SCC_B_27_DP")
			(clearance 0.1651)
			(thermal_gap 0.1651)
		)
		(pad "B29" thru_hole circle
			(at 50.39995 1.400048 270)
			(size 0.762 0.762)
			(drill 0.359918)
			(layers "*.Cu" "*.Mask")
			(remove_unused_layers no)
			(net "PHY_DRV_B_TO_SCC_B_28_DP")
			(clearance 0.1651)
			(thermal_gap 0.1651)
		)
		(pad "B30" thru_hole circle
			(at 52.200048 2.400046 270)
			(size 0.762 0.762)
			(drill 0.359918)
			(layers "*.Cu" "*.Mask")
			(remove_unused_layers no)
			(net "PHY_DRV_B_TO_SCC_B_29_DP")
			(clearance 0.1651)
			(thermal_gap 0.1651)
		)
		(pad "B31" thru_hole circle
			(at 53.999892 1.400048 270)
			(size 0.762 0.762)
			(drill 0.359918)
			(layers "*.Cu" "*.Mask")
			(remove_unused_layers no)
			(net "PHY_DRV_B_TO_SCC_B_35_DP")
			(clearance 0.1651)
			(thermal_gap 0.1651)
		)
		(pad "B32" thru_hole circle
			(at 55.79999 2.400046 270)
			(size 0.762 0.762)
			(drill 0.359918)
			(layers "*.Cu" "*.Mask")
			(remove_unused_layers no)
			(net "PHY_DRV_B_TO_SCC_B_34_DP")
			(clearance 0.1651)
			(thermal_gap 0.1651)
		)
		(pad "B33" thru_hole circle
			(at 57.600088 1.400048 270)
			(size 0.762 0.762)
			(drill 0.359918)
			(layers "*.Cu" "*.Mask")
			(remove_unused_layers no)
			(net "PHY_DRV_B_TO_SCC_B_33_DP")
			(clearance 0.1651)
			(thermal_gap 0.1651)
		)
		(pad "B34" thru_hole circle
			(at 59.399932 2.400046 270)
			(size 0.762 0.762)
			(drill 0.359918)
			(layers "*.Cu" "*.Mask")
			(remove_unused_layers no)
			(net "PHY_DRV_B_TO_SCC_B_32_DP")
			(clearance 0.1651)
			(thermal_gap 0.1651)
		)
		(pad "B35" thru_hole circle
			(at 61.20003 1.400048 270)
			(size 0.762 0.762)
			(drill 0.359918)
			(layers "*.Cu" "*.Mask")
			(remove_unused_layers no)
			(net "PHY_DRV_B_TO_SCC_B_31_DP")
			(clearance 0.1651)
			(thermal_gap 0.1651)
		)
		(pad "B36" thru_hole circle
			(at 62.999874 2.400046 270)
			(size 0.762 0.762)
			(drill 0.359918)
			(layers "*.Cu" "*.Mask")
			(remove_unused_layers no)
			(net "PHY_DRV_B_TO_SCC_B_30_DP")
			(clearance 0.1651)
			(thermal_gap 0.1651)
		)
		(pad "C1" thru_hole circle
			(at 0 3.599942 270)
			(size 0.762 0.762)
			(drill 0.359918)
			(layers "*.Cu" "*.Mask")
			(remove_unused_layers no)
			(net "SCC_B_STBY_PGOOD")
			(clearance 0.1651)
			(thermal_gap 0.1651)
		)
		(pad "C2" thru_hole circle
			(at 1.800098 4.59994 270)
			(size 0.762 0.762)
			(drill 0.359918)
			(layers "*.Cu" "*.Mask")
			(remove_unused_layers no)
			(net "P3V3_STBY_B")
			(clearance 0.1651)
			(thermal_gap 0.1651)
		)
		(pad "C3" thru_hole circle
			(at 3.599942 3.599942 270)
			(size 0.762 0.762)
			(drill 0.359918)
			(layers "*.Cu" "*.Mask")
			(remove_unused_layers no)
			(net "SCC_B_HEARTBEAT")
			(clearance 0.1651)
			(thermal_gap 0.1651)
		)
		(pad "C4" thru_hole circle
			(at 5.40004 4.59994 270)
			(size 0.762 0.762)
			(drill 0.359918)
			(layers "*.Cu" "*.Mask")
			(remove_unused_layers no)
			(net "SCC_B_SLOT_ID_0")
			(clearance 0.1651)
			(thermal_gap 0.1651)
		)
		(pad "C5" thru_hole circle
			(at 7.199884 3.599942 270)
			(size 0.762 0.762)
			(drill 0.359918)
			(layers "*.Cu" "*.Mask")
			(remove_unused_layers no)
			(net "SCC_B_TYPE_0")
			(clearance 0.1651)
			(thermal_gap 0.1651)
		)
		(pad "C6" thru_hole circle
			(at 8.999982 4.59994 270)
			(size 0.762 0.762)
			(drill 0.359918)
			(layers "*.Cu" "*.Mask")
			(remove_unused_layers no)
			(net "SCC_B_TYPE_2")
			(clearance 0.1651)
			(thermal_gap 0.1651)
		)
		(pad "C7" thru_hole circle
			(at 10.80008 3.599942 270)
			(size 0.762 0.762)
			(drill 0.359918)
			(layers "*.Cu" "*.Mask")
			(remove_unused_layers no)
			(net "UART_SDB_B_TX")
			(clearance 0.1651)
			(thermal_gap 0.1651)
		)
		(pad "C8" thru_hole circle
			(at 12.599924 4.59994 270)
			(size 0.762 0.762)
			(drill 0.359918)
			(layers "*.Cu" "*.Mask")
			(remove_unused_layers no)
			(net "PWM_SCC_B_ZONE_C")
			(clearance 0.1651)
			(thermal_gap 0.1651)
		)
		(pad "C9" thru_hole circle
			(at 14.400022 3.599942 270)
			(size 0.762 0.762)
			(drill 0.359918)
			(layers "*.Cu" "*.Mask")
			(remove_unused_layers no)
			(net "SCC_B_PWR_LED")
			(clearance 0.1651)
			(thermal_gap 0.1651)
		)
		(pad "C10" thru_hole circle
			(at 16.20012 4.59994 270)
			(size 0.762 0.762)
			(drill 0.359918)
			(layers "*.Cu" "*.Mask")
			(remove_unused_layers no)
			(net "SCC_B_FAULT_LED")
			(clearance 0.1651)
			(thermal_gap 0.1651)
		)
		(pad "C11" thru_hole circle
			(at 17.999964 3.599942 270)
			(size 0.762 0.762)
			(drill 0.359918)
			(layers "*.Cu" "*.Mask")
			(remove_unused_layers no)
			(net "DRIVE_INSERT_ALERT_B_N")
			(clearance 0.1651)
			(thermal_gap 0.1651)
		)
		(pad "C12" thru_hole circle
			(at 19.800062 4.59994 270)
			(size 0.762 0.762)
			(drill 0.359918)
			(layers "*.Cu" "*.Mask")
			(remove_unused_layers no)
			(net "I2C_CLIP_B_SCL")
			(clearance 0.1651)
			(thermal_gap 0.1651)
		)
		(pad "C13" thru_hole circle
			(at 21.599906 3.599942 270)
			(size 0.762 0.762)
			(drill 0.359918)
			(layers "*.Cu" "*.Mask")
			(remove_unused_layers no)
			(net "UART_EXP_B_TX")
			(clearance 0.1651)
			(thermal_gap 0.1651)
		)
		(pad "C14" thru_hole circle
			(at 23.400004 4.59994 270)
			(size 0.762 0.762)
			(drill 0.359918)
			(layers "*.Cu" "*.Mask")
			(remove_unused_layers no)
			(net "I2C_DPB_B_SCL_BUF")
			(clearance 0.1651)
			(thermal_gap 0.1651)
		)
		(pad "C15" thru_hole circle
			(at 25.200102 3.599942 270)
			(size 0.762 0.762)
			(drill 0.359918)
			(layers "*.Cu" "*.Mask")
			(remove_unused_layers no)
			(net "I2C_DRIVE_B_PWR_SCL")
			(clearance 0.1651)
			(thermal_gap 0.1651)
		)
		(pad "C16" thru_hole circle
			(at 26.999946 4.59994 270)
			(size 0.762 0.762)
			(drill 0.359918)
			(layers "*.Cu" "*.Mask")
			(remove_unused_layers no)
			(net "I2C_DRIVE_B_INS_SCL")
			(clearance 0.1651)
			(thermal_gap 0.1651)
		)
		(pad "C17" thru_hole circle
			(at 28.800044 3.599942 270)
			(size 0.762 0.762)
			(drill 0.359918)
			(layers "*.Cu" "*.Mask")
			(remove_unused_layers no)
			(net "I2C_DRIVE_B_FLT_LED_SCL")
			(clearance 0.1651)
			(thermal_gap 0.1651)
		)
		(pad "C18" thru_hole circle
			(at 30.599888 4.59994 270)
			(size 0.762 0.762)
			(drill 0.359918)
			(layers "*.Cu" "*.Mask")
			(remove_unused_layers no)
			(net "DRIVE_B_0_ACT")
			(clearance 0.1651)
			(thermal_gap 0.1651)
		)
		(pad "C19" thru_hole circle
			(at 32.399986 3.599942 270)
			(size 0.762 0.762)
			(drill 0.359918)
			(layers "*.Cu" "*.Mask")
			(remove_unused_layers no)
			(net "DRIVE_B_2_ACT")
			(clearance 0.1651)
			(thermal_gap 0.1651)
		)
		(pad "C20" thru_hole circle
			(at 34.200084 4.59994 270)
			(size 0.762 0.762)
			(drill 0.359918)
			(layers "*.Cu" "*.Mask")
			(remove_unused_layers no)
			(net "DRIVE_B_4_ACT")
			(clearance 0.1651)
			(thermal_gap 0.1651)
		)
		(pad "C21" thru_hole circle
			(at 35.999928 3.599942 270)
			(size 0.762 0.762)
			(drill 0.359918)
			(layers "*.Cu" "*.Mask")
			(remove_unused_layers no)
			(net "DRIVE_B_6_ACT")
			(clearance 0.1651)
			(thermal_gap 0.1651)
		)
		(pad "C22" thru_hole circle
			(at 37.800026 4.59994 270)
			(size 0.762 0.762)
			(drill 0.359918)
			(layers "*.Cu" "*.Mask")
			(remove_unused_layers no)
			(net "DRIVE_B_8_ACT")
			(clearance 0.1651)
			(thermal_gap 0.1651)
		)
		(pad "C23" thru_hole circle
			(at 39.600124 3.599942 270)
			(size 0.762 0.762)
			(drill 0.359918)
			(layers "*.Cu" "*.Mask")
			(remove_unused_layers no)
			(net "DRIVE_B_10_ACT")
			(clearance 0.1651)
			(thermal_gap 0.1651)
		)
		(pad "C24" thru_hole circle
			(at 41.399968 4.59994 270)
			(size 0.762 0.762)
			(drill 0.359918)
			(layers "*.Cu" "*.Mask")
			(remove_unused_layers no)
			(net "DRIVE_B_12_ACT")
			(clearance 0.1651)
			(thermal_gap 0.1651)
		)
		(pad "C25" thru_hole circle
			(at 43.200066 3.599942 270)
			(size 0.762 0.762)
			(drill 0.359918)
			(layers "*.Cu" "*.Mask")
			(remove_unused_layers no)
			(net "DRIVE_B_14_ACT")
			(clearance 0.1651)
			(thermal_gap 0.1651)
		)
		(pad "C26" thru_hole circle
			(at 44.99991 4.59994 270)
			(size 0.762 0.762)
			(drill 0.359918)
			(layers "*.Cu" "*.Mask")
			(remove_unused_layers no)
			(net "DRIVE_B_16_ACT")
			(clearance 0.1651)
			(thermal_gap 0.1651)
		)
		(pad "C27" thru_hole circle
			(at 46.800008 3.599942 270)
			(size 0.762 0.762)
			(drill 0.359918)
			(layers "*.Cu" "*.Mask")
			(remove_unused_layers no)
			(net "DRIVE_B_18_ACT")
			(clearance 0.1651)
			(thermal_gap 0.1651)
		)
		(pad "C28" thru_hole circle
			(at 48.600106 4.59994 270)
			(size 0.762 0.762)
			(drill 0.359918)
			(layers "*.Cu" "*.Mask")
			(remove_unused_layers no)
			(net "DRIVE_B_20_ACT")
			(clearance 0.1651)
			(thermal_gap 0.1651)
		)
		(pad "C29" thru_hole circle
			(at 50.39995 3.599942 270)
			(size 0.762 0.762)
			(drill 0.359918)
			(layers "*.Cu" "*.Mask")
			(remove_unused_layers no)
			(net "DRIVE_B_22_ACT")
			(clearance 0.1651)
			(thermal_gap 0.1651)
		)
		(pad "C30" thru_hole circle
			(at 52.200048 4.59994 270)
			(size 0.762 0.762)
			(drill 0.359918)
			(layers "*.Cu" "*.Mask")
			(remove_unused_layers no)
			(net "DRIVE_B_24_ACT")
			(clearance 0.1651)
			(thermal_gap 0.1651)
		)
		(pad "C31" thru_hole circle
			(at 53.999892 3.599942 270)
			(size 0.762 0.762)
			(drill 0.359918)
			(layers "*.Cu" "*.Mask")
			(remove_unused_layers no)
			(net "DRIVE_B_26_ACT")
			(clearance 0.1651)
			(thermal_gap 0.1651)
		)
		(pad "C32" thru_hole circle
			(at 55.79999 4.59994 270)
			(size 0.762 0.762)
			(drill 0.359918)
			(layers "*.Cu" "*.Mask")
			(remove_unused_layers no)
			(net "DRIVE_B_28_ACT")
			(clearance 0.1651)
			(thermal_gap 0.1651)
		)
		(pad "C33" thru_hole circle
			(at 57.600088 3.599942 270)
			(size 0.762 0.762)
			(drill 0.359918)
			(layers "*.Cu" "*.Mask")
			(remove_unused_layers no)
			(net "DRIVE_B_30_ACT")
			(clearance 0.1651)
			(thermal_gap 0.1651)
		)
		(pad "C34" thru_hole circle
			(at 59.399932 4.59994 270)
			(size 0.762 0.762)
			(drill 0.359918)
			(layers "*.Cu" "*.Mask")
			(remove_unused_layers no)
			(net "DRIVE_B_32_ACT")
			(clearance 0.1651)
			(thermal_gap 0.1651)
		)
		(pad "C35" thru_hole circle
			(at 61.20003 3.599942 270)
			(size 0.762 0.762)
			(drill 0.359918)
			(layers "*.Cu" "*.Mask")
			(remove_unused_layers no)
			(net "DRIVE_B_34_ACT")
			(clearance 0.1651)
			(thermal_gap 0.1651)
		)
		(pad "C36" thru_hole circle
			(at 62.999874 4.59994 270)
			(size 0.762 0.762)
			(drill 0.359918)
			(layers "*.Cu" "*.Mask")
			(remove_unused_layers no)
			(net "SCC_B_HS_EN")
			(clearance 0.1651)
			(thermal_gap 0.1651)
		)
		(pad "D1" thru_hole circle
			(at 0 4.99999 270)
			(size 0.762 0.762)
			(drill 0.359918)
			(layers "*.Cu" "*.Mask")
			(remove_unused_layers no)
			(net "BMC_B_HEARTBEAT")
			(clearance 0.1651)
			(thermal_gap 0.1651)
		)
		(pad "D2" thru_hole circle
			(at 1.800098 5.999988 270)
			(size 0.762 0.762)
			(drill 0.359918)
			(layers "*.Cu" "*.Mask")
			(remove_unused_layers no)
			(net "SCC_B_STBY_PWR_EN")
			(clearance 0.1651)
			(thermal_gap 0.1651)
		)
		(pad "D3" thru_hole circle
			(at 3.599942 4.99999 270)
			(size 0.762 0.762)
			(drill 0.359918)
			(layers "*.Cu" "*.Mask")
			(remove_unused_layers no)
			(net "SCC_A_HEARTBEAT")
			(clearance 0.1651)
			(thermal_gap 0.1651)
		)
		(pad "D4" thru_hole circle
			(at 5.40004 5.999988 270)
			(size 0.762 0.762)
			(drill 0.359918)
			(layers "*.Cu" "*.Mask")
			(remove_unused_layers no)
			(net "SCC_B_SLOT_ID_1")
			(clearance 0.1651)
			(thermal_gap 0.1651)
		)
		(pad "D5" thru_hole circle
			(at 7.199884 4.99999 270)
			(size 0.762 0.762)
			(drill 0.359918)
			(layers "*.Cu" "*.Mask")
			(remove_unused_layers no)
			(net "SCC_B_TYPE_1")
			(clearance 0.1651)
			(thermal_gap 0.1651)
		)
		(pad "D6" thru_hole circle
			(at 8.999982 5.999988 270)
			(size 0.762 0.762)
			(drill 0.359918)
			(layers "*.Cu" "*.Mask")
			(remove_unused_layers no)
			(net "SCC_B_TYPE_3")
			(clearance 0.1651)
			(thermal_gap 0.1651)
		)
		(pad "D7" thru_hole circle
			(at 10.80008 4.99999 270)
			(size 0.762 0.762)
			(drill 0.359918)
			(layers "*.Cu" "*.Mask")
			(remove_unused_layers no)
			(net "UART_SDB_B_RX")
			(clearance 0.1651)
			(thermal_gap 0.1651)
		)
		(pad "D8" thru_hole circle
			(at 12.599924 5.999988 270)
			(size 0.762 0.762)
			(drill 0.359918)
			(layers "*.Cu" "*.Mask")
			(remove_unused_layers no)
			(net "PWM_SCC_B_ZONE_D")
			(clearance 0.1651)
			(thermal_gap 0.1651)
		)
		(pad "D9" thru_hole circle
			(at 14.400022 4.99999 270)
			(size 0.762 0.762)
			(drill 0.359918)
			(layers "*.Cu" "*.Mask")
			(remove_unused_layers no)
			(net "SCC_B_FULL_PWR_EN")
			(clearance 0.1651)
			(thermal_gap 0.1651)
		)
		(pad "D10" thru_hole circle
			(at 16.20012 5.999988 270)
			(size 0.762 0.762)
			(drill 0.359918)
			(layers "*.Cu" "*.Mask")
			(remove_unused_layers no)
			(net "SCC_B_RESET_N")
			(clearance 0.1651)
			(thermal_gap 0.1651)
		)
		(pad "D11" thru_hole circle
			(at 17.999964 4.99999 270)
			(size 0.762 0.762)
			(drill 0.359918)
			(layers "*.Cu" "*.Mask")
			(remove_unused_layers no)
			(net "SCC_B_INS_N")
			(clearance 0.1651)
			(thermal_gap 0.1651)
		)
		(pad "D12" thru_hole circle
			(at 19.800062 5.999988 270)
			(size 0.762 0.762)
			(drill 0.359918)
			(layers "*.Cu" "*.Mask")
			(remove_unused_layers no)
			(net "I2C_CLIP_B_SDA")
			(clearance 0.1651)
			(thermal_gap 0.1651)
		)
		(pad "D13" thru_hole circle
			(at 21.599906 4.99999 270)
			(size 0.762 0.762)
			(drill 0.359918)
			(layers "*.Cu" "*.Mask")
			(remove_unused_layers no)
			(net "UART_EXP_B_RX")
			(clearance 0.1651)
			(thermal_gap 0.1651)
		)
		(pad "D14" thru_hole circle
			(at 23.400004 5.999988 270)
			(size 0.762 0.762)
			(drill 0.359918)
			(layers "*.Cu" "*.Mask")
			(remove_unused_layers no)
			(net "I2C_DPB_B_SDA_BUF")
			(clearance 0.1651)
			(thermal_gap 0.1651)
		)
		(pad "D15" thru_hole circle
			(at 25.200102 4.99999 270)
			(size 0.762 0.762)
			(drill 0.359918)
			(layers "*.Cu" "*.Mask")
			(remove_unused_layers no)
			(net "I2C_DRIVE_B_PWR_SDA")
			(clearance 0.1651)
			(thermal_gap 0.1651)
		)
		(pad "D16" thru_hole circle
			(at 26.999946 5.999988 270)
			(size 0.762 0.762)
			(drill 0.359918)
			(layers "*.Cu" "*.Mask")
			(remove_unused_layers no)
			(net "I2C_DRIVE_B_INS_SDA")
			(clearance 0.1651)
			(thermal_gap 0.1651)
		)
		(pad "D17" thru_hole circle
			(at 28.800044 4.99999 270)
			(size 0.762 0.762)
			(drill 0.359918)
			(layers "*.Cu" "*.Mask")
			(remove_unused_layers no)
			(net "I2C_DRIVE_B_FLT_LED_SDA")
			(clearance 0.1651)
			(thermal_gap 0.1651)
		)
		(pad "D18" thru_hole circle
			(at 30.599888 5.999988 270)
			(size 0.762 0.762)
			(drill 0.359918)
			(layers "*.Cu" "*.Mask")
			(remove_unused_layers no)
			(net "DRIVE_B_1_ACT")
			(clearance 0.1651)
			(thermal_gap 0.1651)
		)
		(pad "D19" thru_hole circle
			(at 32.399986 4.99999 270)
			(size 0.762 0.762)
			(drill 0.359918)
			(layers "*.Cu" "*.Mask")
			(remove_unused_layers no)
			(net "DRIVE_B_3_ACT")
			(clearance 0.1651)
			(thermal_gap 0.1651)
		)
		(pad "D20" thru_hole circle
			(at 34.200084 5.999988 270)
			(size 0.762 0.762)
			(drill 0.359918)
			(layers "*.Cu" "*.Mask")
			(remove_unused_layers no)
			(net "DRIVE_B_5_ACT")
			(clearance 0.1651)
			(thermal_gap 0.1651)
		)
		(pad "D21" thru_hole circle
			(at 35.999928 4.99999 270)
			(size 0.762 0.762)
			(drill 0.359918)
			(layers "*.Cu" "*.Mask")
			(remove_unused_layers no)
			(net "DRIVE_B_7_ACT")
			(clearance 0.1651)
			(thermal_gap 0.1651)
		)
		(pad "D22" thru_hole circle
			(at 37.800026 5.999988 270)
			(size 0.762 0.762)
			(drill 0.359918)
			(layers "*.Cu" "*.Mask")
			(remove_unused_layers no)
			(net "DRIVE_B_9_ACT")
			(clearance 0.1651)
			(thermal_gap 0.1651)
		)
		(pad "D23" thru_hole circle
			(at 39.600124 4.99999 270)
			(size 0.762 0.762)
			(drill 0.359918)
			(layers "*.Cu" "*.Mask")
			(remove_unused_layers no)
			(net "DRIVE_B_11_ACT")
			(clearance 0.1651)
			(thermal_gap 0.1651)
		)
		(pad "D24" thru_hole circle
			(at 41.399968 5.999988 270)
			(size 0.762 0.762)
			(drill 0.359918)
			(layers "*.Cu" "*.Mask")
			(remove_unused_layers no)
			(net "DRIVE_B_13_ACT")
			(clearance 0.1651)
			(thermal_gap 0.1651)
		)
		(pad "D25" thru_hole circle
			(at 43.200066 4.99999 270)
			(size 0.762 0.762)
			(drill 0.359918)
			(layers "*.Cu" "*.Mask")
			(remove_unused_layers no)
			(net "DRIVE_B_15_ACT")
			(clearance 0.1651)
			(thermal_gap 0.1651)
		)
		(pad "D26" thru_hole circle
			(at 44.99991 5.999988 270)
			(size 0.762 0.762)
			(drill 0.359918)
			(layers "*.Cu" "*.Mask")
			(remove_unused_layers no)
			(net "DRIVE_B_17_ACT")
			(clearance 0.1651)
			(thermal_gap 0.1651)
		)
		(pad "D27" thru_hole circle
			(at 46.800008 4.99999 270)
			(size 0.762 0.762)
			(drill 0.359918)
			(layers "*.Cu" "*.Mask")
			(remove_unused_layers no)
			(net "DRIVE_B_19_ACT")
			(clearance 0.1651)
			(thermal_gap 0.1651)
		)
		(pad "D28" thru_hole circle
			(at 48.600106 5.999988 270)
			(size 0.762 0.762)
			(drill 0.359918)
			(layers "*.Cu" "*.Mask")
			(remove_unused_layers no)
			(net "DRIVE_B_21_ACT")
			(clearance 0.1651)
			(thermal_gap 0.1651)
		)
		(pad "D29" thru_hole circle
			(at 50.39995 4.99999 270)
			(size 0.762 0.762)
			(drill 0.359918)
			(layers "*.Cu" "*.Mask")
			(remove_unused_layers no)
			(net "DRIVE_B_23_ACT")
			(clearance 0.1651)
			(thermal_gap 0.1651)
		)
		(pad "D30" thru_hole circle
			(at 52.200048 5.999988 270)
			(size 0.762 0.762)
			(drill 0.359918)
			(layers "*.Cu" "*.Mask")
			(remove_unused_layers no)
			(net "DRIVE_B_25_ACT")
			(clearance 0.1651)
			(thermal_gap 0.1651)
		)
		(pad "D31" thru_hole circle
			(at 53.999892 4.99999 270)
			(size 0.762 0.762)
			(drill 0.359918)
			(layers "*.Cu" "*.Mask")
			(remove_unused_layers no)
			(net "DRIVE_B_27_ACT")
			(clearance 0.1651)
			(thermal_gap 0.1651)
		)
		(pad "D32" thru_hole circle
			(at 55.79999 5.999988 270)
			(size 0.762 0.762)
			(drill 0.359918)
			(layers "*.Cu" "*.Mask")
			(remove_unused_layers no)
			(net "DRIVE_B_29_ACT")
			(clearance 0.1651)
			(thermal_gap 0.1651)
		)
		(pad "D33" thru_hole circle
			(at 57.600088 4.99999 270)
			(size 0.762 0.762)
			(drill 0.359918)
			(layers "*.Cu" "*.Mask")
			(remove_unused_layers no)
			(net "DRIVE_B_31_ACT")
			(clearance 0.1651)
			(thermal_gap 0.1651)
		)
		(pad "D34" thru_hole circle
			(at 59.399932 5.999988 270)
			(size 0.762 0.762)
			(drill 0.359918)
			(layers "*.Cu" "*.Mask")
			(remove_unused_layers no)
			(net "DRIVE_B_33_ACT")
			(clearance 0.1651)
			(thermal_gap 0.1651)
		)
		(pad "D35" thru_hole circle
			(at 61.20003 4.99999 270)
			(size 0.762 0.762)
			(drill 0.359918)
			(layers "*.Cu" "*.Mask")
			(remove_unused_layers no)
			(net "DRIVE_B_35_ACT")
			(clearance 0.1651)
			(thermal_gap 0.1651)
		)
		(pad "D36" thru_hole circle
			(at 62.999874 5.999988 270)
			(size 0.762 0.762)
			(drill 0.359918)
			(layers "*.Cu" "*.Mask")
			(remove_unused_layers no)
			(net "SCC_B_FULL_PGOOD")
			(clearance 0.1651)
			(thermal_gap 0.1651)
		)
		(pad "E1" thru_hole circle
			(at 0 7.199884 270)
			(size 0.762 0.762)
			(drill 0.359918)
			(layers "*.Cu" "*.Mask")
			(remove_unused_layers no)
			(net "PHY_SCC_B_TO_DRV_B_5_DP")
			(clearance 0.1651)
			(thermal_gap 0.1651)
		)
		(pad "E2" thru_hole circle
			(at 1.800098 8.199882 270)
			(size 0.762 0.762)
			(drill 0.359918)
			(layers "*.Cu" "*.Mask")
			(remove_unused_layers no)
			(net "PHY_SCC_B_TO_DRV_B_4_DP")
			(clearance 0.1651)
			(thermal_gap 0.1651)
		)
		(pad "E3" thru_hole circle
			(at 3.599942 7.199884 270)
			(size 0.762 0.762)
			(drill 0.359918)
			(layers "*.Cu" "*.Mask")
			(remove_unused_layers no)
			(net "PHY_SCC_B_TO_DRV_B_3_DP")
			(clearance 0.1651)
			(thermal_gap 0.1651)
		)
		(pad "E4" thru_hole circle
			(at 5.40004 8.199882 270)
			(size 0.762 0.762)
			(drill 0.359918)
			(layers "*.Cu" "*.Mask")
			(remove_unused_layers no)
			(net "PHY_SCC_B_TO_DRV_B_2_DP")
			(clearance 0.1651)
			(thermal_gap 0.1651)
		)
		(pad "E5" thru_hole circle
			(at 7.199884 7.199884 270)
			(size 0.762 0.762)
			(drill 0.359918)
			(layers "*.Cu" "*.Mask")
			(remove_unused_layers no)
			(net "PHY_SCC_B_TO_DRV_B_1_DP")
			(clearance 0.1651)
			(thermal_gap 0.1651)
		)
		(pad "E6" thru_hole circle
			(at 8.999982 8.199882 270)
			(size 0.762 0.762)
			(drill 0.359918)
			(layers "*.Cu" "*.Mask")
			(remove_unused_layers no)
			(net "PHY_SCC_B_TO_DRV_B_0_DP")
			(clearance 0.1651)
			(thermal_gap 0.1651)
		)
		(pad "E7" thru_hole circle
			(at 10.80008 7.199884 270)
			(size 0.762 0.762)
			(drill 0.359918)
			(layers "*.Cu" "*.Mask")
			(remove_unused_layers no)
			(net "PHY_SCC_B_TO_DRV_B_6_DP")
			(clearance 0.1651)
			(thermal_gap 0.1651)
		)
		(pad "E8" thru_hole circle
			(at 12.599924 8.199882 270)
			(size 0.762 0.762)
			(drill 0.359918)
			(layers "*.Cu" "*.Mask")
			(remove_unused_layers no)
			(net "PHY_SCC_B_TO_DRV_B_7_DP")
			(clearance 0.1651)
			(thermal_gap 0.1651)
		)
		(pad "E9" thru_hole circle
			(at 14.400022 7.199884 270)
			(size 0.762 0.762)
			(drill 0.359918)
			(layers "*.Cu" "*.Mask")
			(remove_unused_layers no)
			(net "PHY_SCC_B_TO_DRV_B_8_DP")
			(clearance 0.1651)
			(thermal_gap 0.1651)
		)
		(pad "E10" thru_hole circle
			(at 16.20012 8.199882 270)
			(size 0.762 0.762)
			(drill 0.359918)
			(layers "*.Cu" "*.Mask")
			(remove_unused_layers no)
			(net "PHY_SCC_B_TO_DRV_B_9_DP")
			(clearance 0.1651)
			(thermal_gap 0.1651)
		)
		(pad "E11" thru_hole circle
			(at 17.999964 7.199884 270)
			(size 0.762 0.762)
			(drill 0.359918)
			(layers "*.Cu" "*.Mask")
			(remove_unused_layers no)
			(net "PHY_SCC_B_TO_DRV_B_10_DP")
			(clearance 0.1651)
			(thermal_gap 0.1651)
		)
		(pad "E12" thru_hole circle
			(at 19.800062 8.199882 270)
			(size 0.762 0.762)
			(drill 0.359918)
			(layers "*.Cu" "*.Mask")
			(remove_unused_layers no)
			(net "PHY_SCC_B_TO_DRV_B_11_DP")
			(clearance 0.1651)
			(thermal_gap 0.1651)
		)
		(pad "E13" thru_hole circle
			(at 21.599906 7.199884 270)
			(size 0.762 0.762)
			(drill 0.359918)
			(layers "*.Cu" "*.Mask")
			(remove_unused_layers no)
			(net "PHY_SCC_B_TO_DRV_B_12_DP")
			(clearance 0.1651)
			(thermal_gap 0.1651)
		)
		(pad "E14" thru_hole circle
			(at 23.400004 8.199882 270)
			(size 0.762 0.762)
			(drill 0.359918)
			(layers "*.Cu" "*.Mask")
			(remove_unused_layers no)
			(net "PHY_SCC_B_TO_DRV_B_13_DP")
			(clearance 0.1651)
			(thermal_gap 0.1651)
		)
		(pad "E15" thru_hole circle
			(at 25.200102 7.199884 270)
			(size 0.762 0.762)
			(drill 0.359918)
			(layers "*.Cu" "*.Mask")
			(remove_unused_layers no)
			(net "PHY_SCC_B_TO_DRV_B_14_DP")
			(clearance 0.1651)
			(thermal_gap 0.1651)
		)
		(pad "E16" thru_hole circle
			(at 26.999946 8.199882 270)
			(size 0.762 0.762)
			(drill 0.359918)
			(layers "*.Cu" "*.Mask")
			(remove_unused_layers no)
			(net "PHY_SCC_B_TO_DRV_B_15_DP")
			(clearance 0.1651)
			(thermal_gap 0.1651)
		)
		(pad "E17" thru_hole circle
			(at 28.800044 7.199884 270)
			(size 0.762 0.762)
			(drill 0.359918)
			(layers "*.Cu" "*.Mask")
			(remove_unused_layers no)
			(net "PHY_SCC_B_TO_DRV_B_16_DP")
			(clearance 0.1651)
			(thermal_gap 0.1651)
		)
		(pad "E18" thru_hole circle
			(at 30.599888 8.199882 270)
			(size 0.762 0.762)
			(drill 0.359918)
			(layers "*.Cu" "*.Mask")
			(remove_unused_layers no)
			(net "PHY_SCC_B_TO_DRV_B_17_DP")
			(clearance 0.1651)
			(thermal_gap 0.1651)
		)
		(pad "E19" thru_hole circle
			(at 32.399986 7.199884 270)
			(size 0.762 0.762)
			(drill 0.359918)
			(layers "*.Cu" "*.Mask")
			(remove_unused_layers no)
			(net "PHY_SCC_B_TO_DRV_B_23_DP")
			(clearance 0.1651)
			(thermal_gap 0.1651)
		)
		(pad "E20" thru_hole circle
			(at 34.200084 8.199882 270)
			(size 0.762 0.762)
			(drill 0.359918)
			(layers "*.Cu" "*.Mask")
			(remove_unused_layers no)
			(net "PHY_SCC_B_TO_DRV_B_22_DP")
			(clearance 0.1651)
			(thermal_gap 0.1651)
		)
		(pad "E21" thru_hole circle
			(at 35.999928 7.199884 270)
			(size 0.762 0.762)
			(drill 0.359918)
			(layers "*.Cu" "*.Mask")
			(remove_unused_layers no)
			(net "PHY_SCC_B_TO_DRV_B_21_DP")
			(clearance 0.1651)
			(thermal_gap 0.1651)
		)
		(pad "E22" thru_hole circle
			(at 37.800026 8.199882 270)
			(size 0.762 0.762)
			(drill 0.359918)
			(layers "*.Cu" "*.Mask")
			(remove_unused_layers no)
			(net "PHY_SCC_B_TO_DRV_B_20_DP")
			(clearance 0.1651)
			(thermal_gap 0.1651)
		)
		(pad "E23" thru_hole circle
			(at 39.600124 7.199884 270)
			(size 0.762 0.762)
			(drill 0.359918)
			(layers "*.Cu" "*.Mask")
			(remove_unused_layers no)
			(net "PHY_SCC_B_TO_DRV_B_19_DP")
			(clearance 0.1651)
			(thermal_gap 0.1651)
		)
		(pad "E24" thru_hole circle
			(at 41.399968 8.199882 270)
			(size 0.762 0.762)
			(drill 0.359918)
			(layers "*.Cu" "*.Mask")
			(remove_unused_layers no)
			(net "PHY_SCC_B_TO_DRV_B_18_DP")
			(clearance 0.1651)
			(thermal_gap 0.1651)
		)
		(pad "E25" thru_hole circle
			(at 43.200066 7.199884 270)
			(size 0.762 0.762)
			(drill 0.359918)
			(layers "*.Cu" "*.Mask")
			(remove_unused_layers no)
			(net "PHY_SCC_B_TO_DRV_B_24_DP")
			(clearance 0.1651)
			(thermal_gap 0.1651)
		)
		(pad "E26" thru_hole circle
			(at 44.99991 8.199882 270)
			(size 0.762 0.762)
			(drill 0.359918)
			(layers "*.Cu" "*.Mask")
			(remove_unused_layers no)
			(net "PHY_SCC_B_TO_DRV_B_25_DP")
			(clearance 0.1651)
			(thermal_gap 0.1651)
		)
		(pad "E27" thru_hole circle
			(at 46.800008 7.199884 270)
			(size 0.762 0.762)
			(drill 0.359918)
			(layers "*.Cu" "*.Mask")
			(remove_unused_layers no)
			(net "PHY_SCC_B_TO_DRV_B_26_DP")
			(clearance 0.1651)
			(thermal_gap 0.1651)
		)
		(pad "E28" thru_hole circle
			(at 48.600106 8.199882 270)
			(size 0.762 0.762)
			(drill 0.359918)
			(layers "*.Cu" "*.Mask")
			(remove_unused_layers no)
			(net "PHY_SCC_B_TO_DRV_B_27_DP")
			(clearance 0.1651)
			(thermal_gap 0.1651)
		)
		(pad "E29" thru_hole circle
			(at 50.39995 7.199884 270)
			(size 0.762 0.762)
			(drill 0.359918)
			(layers "*.Cu" "*.Mask")
			(remove_unused_layers no)
			(net "PHY_SCC_B_TO_DRV_B_28_DP")
			(clearance 0.1651)
			(thermal_gap 0.1651)
		)
		(pad "E30" thru_hole circle
			(at 52.200048 8.199882 270)
			(size 0.762 0.762)
			(drill 0.359918)
			(layers "*.Cu" "*.Mask")
			(remove_unused_layers no)
			(net "PHY_SCC_B_TO_DRV_B_29_DP")
			(clearance 0.1651)
			(thermal_gap 0.1651)
		)
		(pad "E31" thru_hole circle
			(at 53.999892 7.199884 270)
			(size 0.762 0.762)
			(drill 0.359918)
			(layers "*.Cu" "*.Mask")
			(remove_unused_layers no)
			(net "PHY_SCC_B_TO_DRV_B_35_DP")
			(clearance 0.1651)
			(thermal_gap 0.1651)
		)
		(pad "E32" thru_hole circle
			(at 55.79999 8.199882 270)
			(size 0.762 0.762)
			(drill 0.359918)
			(layers "*.Cu" "*.Mask")
			(remove_unused_layers no)
			(net "PHY_SCC_B_TO_DRV_B_34_DP")
			(clearance 0.1651)
			(thermal_gap 0.1651)
		)
		(pad "E33" thru_hole circle
			(at 57.600088 7.199884 270)
			(size 0.762 0.762)
			(drill 0.359918)
			(layers "*.Cu" "*.Mask")
			(remove_unused_layers no)
			(net "PHY_SCC_B_TO_DRV_B_33_DP")
			(clearance 0.1651)
			(thermal_gap 0.1651)
		)
		(pad "E34" thru_hole circle
			(at 59.399932 8.199882 270)
			(size 0.762 0.762)
			(drill 0.359918)
			(layers "*.Cu" "*.Mask")
			(remove_unused_layers no)
			(net "PHY_SCC_B_TO_DRV_B_32_DP")
			(clearance 0.1651)
			(thermal_gap 0.1651)
		)
		(pad "E35" thru_hole circle
			(at 61.20003 7.199884 270)
			(size 0.762 0.762)
			(drill 0.359918)
			(layers "*.Cu" "*.Mask")
			(remove_unused_layers no)
			(net "PHY_SCC_B_TO_DRV_B_31_DP")
			(clearance 0.1651)
			(thermal_gap 0.1651)
		)
		(pad "E36" thru_hole circle
			(at 62.999874 8.199882 270)
			(size 0.762 0.762)
			(drill 0.359918)
			(layers "*.Cu" "*.Mask")
			(remove_unused_layers no)
			(net "PHY_SCC_B_TO_DRV_B_30_DP")
			(clearance 0.1651)
			(thermal_gap 0.1651)
		)
		(pad "F1" thru_hole circle
			(at 0 8.599932 270)
			(size 0.762 0.762)
			(drill 0.359918)
			(layers "*.Cu" "*.Mask")
			(remove_unused_layers no)
			(net "PHY_SCC_B_TO_DRV_B_5_DN")
			(clearance 0.1651)
			(thermal_gap 0.1651)
		)
		(pad "F2" thru_hole circle
			(at 1.800098 9.59993 270)
			(size 0.762 0.762)
			(drill 0.359918)
			(layers "*.Cu" "*.Mask")
			(remove_unused_layers no)
			(net "PHY_SCC_B_TO_DRV_B_4_DN")
			(clearance 0.1651)
			(thermal_gap 0.1651)
		)
		(pad "F3" thru_hole circle
			(at 3.599942 8.599932 270)
			(size 0.762 0.762)
			(drill 0.359918)
			(layers "*.Cu" "*.Mask")
			(remove_unused_layers no)
			(net "PHY_SCC_B_TO_DRV_B_3_DN")
			(clearance 0.1651)
			(thermal_gap 0.1651)
		)
		(pad "F4" thru_hole circle
			(at 5.40004 9.59993 270)
			(size 0.762 0.762)
			(drill 0.359918)
			(layers "*.Cu" "*.Mask")
			(remove_unused_layers no)
			(net "PHY_SCC_B_TO_DRV_B_2_DN")
			(clearance 0.1651)
			(thermal_gap 0.1651)
		)
		(pad "F5" thru_hole circle
			(at 7.199884 8.599932 270)
			(size 0.762 0.762)
			(drill 0.359918)
			(layers "*.Cu" "*.Mask")
			(remove_unused_layers no)
			(net "PHY_SCC_B_TO_DRV_B_1_DN")
			(clearance 0.1651)
			(thermal_gap 0.1651)
		)
		(pad "F6" thru_hole circle
			(at 8.999982 9.59993 270)
			(size 0.762 0.762)
			(drill 0.359918)
			(layers "*.Cu" "*.Mask")
			(remove_unused_layers no)
			(net "PHY_SCC_B_TO_DRV_B_0_DN")
			(clearance 0.1651)
			(thermal_gap 0.1651)
		)
		(pad "F7" thru_hole circle
			(at 10.80008 8.599932 270)
			(size 0.762 0.762)
			(drill 0.359918)
			(layers "*.Cu" "*.Mask")
			(remove_unused_layers no)
			(net "PHY_SCC_B_TO_DRV_B_6_DN")
			(clearance 0.1651)
			(thermal_gap 0.1651)
		)
		(pad "F8" thru_hole circle
			(at 12.599924 9.59993 270)
			(size 0.762 0.762)
			(drill 0.359918)
			(layers "*.Cu" "*.Mask")
			(remove_unused_layers no)
			(net "PHY_SCC_B_TO_DRV_B_7_DN")
			(clearance 0.1651)
			(thermal_gap 0.1651)
		)
		(pad "F9" thru_hole circle
			(at 14.400022 8.599932 270)
			(size 0.762 0.762)
			(drill 0.359918)
			(layers "*.Cu" "*.Mask")
			(remove_unused_layers no)
			(net "PHY_SCC_B_TO_DRV_B_8_DN")
			(clearance 0.1651)
			(thermal_gap 0.1651)
		)
		(pad "F10" thru_hole circle
			(at 16.20012 9.59993 270)
			(size 0.762 0.762)
			(drill 0.359918)
			(layers "*.Cu" "*.Mask")
			(remove_unused_layers no)
			(net "PHY_SCC_B_TO_DRV_B_9_DN")
			(clearance 0.1651)
			(thermal_gap 0.1651)
		)
		(pad "F11" thru_hole circle
			(at 17.999964 8.599932 270)
			(size 0.762 0.762)
			(drill 0.359918)
			(layers "*.Cu" "*.Mask")
			(remove_unused_layers no)
			(net "PHY_SCC_B_TO_DRV_B_10_DN")
			(clearance 0.1651)
			(thermal_gap 0.1651)
		)
		(pad "F12" thru_hole circle
			(at 19.800062 9.59993 270)
			(size 0.762 0.762)
			(drill 0.359918)
			(layers "*.Cu" "*.Mask")
			(remove_unused_layers no)
			(net "PHY_SCC_B_TO_DRV_B_11_DN")
			(clearance 0.1651)
			(thermal_gap 0.1651)
		)
		(pad "F13" thru_hole circle
			(at 21.599906 8.599932 270)
			(size 0.762 0.762)
			(drill 0.359918)
			(layers "*.Cu" "*.Mask")
			(remove_unused_layers no)
			(net "PHY_SCC_B_TO_DRV_B_12_DN")
			(clearance 0.1651)
			(thermal_gap 0.1651)
		)
		(pad "F14" thru_hole circle
			(at 23.400004 9.59993 270)
			(size 0.762 0.762)
			(drill 0.359918)
			(layers "*.Cu" "*.Mask")
			(remove_unused_layers no)
			(net "PHY_SCC_B_TO_DRV_B_13_DN")
			(clearance 0.1651)
			(thermal_gap 0.1651)
		)
		(pad "F15" thru_hole circle
			(at 25.200102 8.599932 270)
			(size 0.762 0.762)
			(drill 0.359918)
			(layers "*.Cu" "*.Mask")
			(remove_unused_layers no)
			(net "PHY_SCC_B_TO_DRV_B_14_DN")
			(clearance 0.1651)
			(thermal_gap 0.1651)
		)
		(pad "F16" thru_hole circle
			(at 26.999946 9.59993 270)
			(size 0.762 0.762)
			(drill 0.359918)
			(layers "*.Cu" "*.Mask")
			(remove_unused_layers no)
			(net "PHY_SCC_B_TO_DRV_B_15_DN")
			(clearance 0.1651)
			(thermal_gap 0.1651)
		)
		(pad "F17" thru_hole circle
			(at 28.800044 8.599932 270)
			(size 0.762 0.762)
			(drill 0.359918)
			(layers "*.Cu" "*.Mask")
			(remove_unused_layers no)
			(net "PHY_SCC_B_TO_DRV_B_16_DN")
			(clearance 0.1651)
			(thermal_gap 0.1651)
		)
		(pad "F18" thru_hole circle
			(at 30.599888 9.59993 270)
			(size 0.762 0.762)
			(drill 0.359918)
			(layers "*.Cu" "*.Mask")
			(remove_unused_layers no)
			(net "PHY_SCC_B_TO_DRV_B_17_DN")
			(clearance 0.1651)
			(thermal_gap 0.1651)
		)
		(pad "F19" thru_hole circle
			(at 32.399986 8.599932 270)
			(size 0.762 0.762)
			(drill 0.359918)
			(layers "*.Cu" "*.Mask")
			(remove_unused_layers no)
			(net "PHY_SCC_B_TO_DRV_B_23_DN")
			(clearance 0.1651)
			(thermal_gap 0.1651)
		)
		(pad "F20" thru_hole circle
			(at 34.200084 9.59993 270)
			(size 0.762 0.762)
			(drill 0.359918)
			(layers "*.Cu" "*.Mask")
			(remove_unused_layers no)
			(net "PHY_SCC_B_TO_DRV_B_22_DN")
			(clearance 0.1651)
			(thermal_gap 0.1651)
		)
		(pad "F21" thru_hole circle
			(at 35.999928 8.599932 270)
			(size 0.762 0.762)
			(drill 0.359918)
			(layers "*.Cu" "*.Mask")
			(remove_unused_layers no)
			(net "PHY_SCC_B_TO_DRV_B_21_DN")
			(clearance 0.1651)
			(thermal_gap 0.1651)
		)
		(pad "F22" thru_hole circle
			(at 37.800026 9.59993 270)
			(size 0.762 0.762)
			(drill 0.359918)
			(layers "*.Cu" "*.Mask")
			(remove_unused_layers no)
			(net "PHY_SCC_B_TO_DRV_B_20_DN")
			(clearance 0.1651)
			(thermal_gap 0.1651)
		)
		(pad "F23" thru_hole circle
			(at 39.600124 8.599932 270)
			(size 0.762 0.762)
			(drill 0.359918)
			(layers "*.Cu" "*.Mask")
			(remove_unused_layers no)
			(net "PHY_SCC_B_TO_DRV_B_19_DN")
			(clearance 0.1651)
			(thermal_gap 0.1651)
		)
		(pad "F24" thru_hole circle
			(at 41.399968 9.59993 270)
			(size 0.762 0.762)
			(drill 0.359918)
			(layers "*.Cu" "*.Mask")
			(remove_unused_layers no)
			(net "PHY_SCC_B_TO_DRV_B_18_DN")
			(clearance 0.1651)
			(thermal_gap 0.1651)
		)
		(pad "F25" thru_hole circle
			(at 43.200066 8.599932 270)
			(size 0.762 0.762)
			(drill 0.359918)
			(layers "*.Cu" "*.Mask")
			(remove_unused_layers no)
			(net "PHY_SCC_B_TO_DRV_B_24_DN")
			(clearance 0.1651)
			(thermal_gap 0.1651)
		)
		(pad "F26" thru_hole circle
			(at 44.99991 9.59993 270)
			(size 0.762 0.762)
			(drill 0.359918)
			(layers "*.Cu" "*.Mask")
			(remove_unused_layers no)
			(net "PHY_SCC_B_TO_DRV_B_25_DN")
			(clearance 0.1651)
			(thermal_gap 0.1651)
		)
		(pad "F27" thru_hole circle
			(at 46.800008 8.599932 270)
			(size 0.762 0.762)
			(drill 0.359918)
			(layers "*.Cu" "*.Mask")
			(remove_unused_layers no)
			(net "PHY_SCC_B_TO_DRV_B_26_DN")
			(clearance 0.1651)
			(thermal_gap 0.1651)
		)
		(pad "F28" thru_hole circle
			(at 48.600106 9.59993 270)
			(size 0.762 0.762)
			(drill 0.359918)
			(layers "*.Cu" "*.Mask")
			(remove_unused_layers no)
			(net "PHY_SCC_B_TO_DRV_B_27_DN")
			(clearance 0.1651)
			(thermal_gap 0.1651)
		)
		(pad "F29" thru_hole circle
			(at 50.39995 8.599932 270)
			(size 0.762 0.762)
			(drill 0.359918)
			(layers "*.Cu" "*.Mask")
			(remove_unused_layers no)
			(net "PHY_SCC_B_TO_DRV_B_28_DN")
			(clearance 0.1651)
			(thermal_gap 0.1651)
		)
		(pad "F30" thru_hole circle
			(at 52.200048 9.59993 270)
			(size 0.762 0.762)
			(drill 0.359918)
			(layers "*.Cu" "*.Mask")
			(remove_unused_layers no)
			(net "PHY_SCC_B_TO_DRV_B_29_DN")
			(clearance 0.1651)
			(thermal_gap 0.1651)
		)
		(pad "F31" thru_hole circle
			(at 53.999892 8.599932 270)
			(size 0.762 0.762)
			(drill 0.359918)
			(layers "*.Cu" "*.Mask")
			(remove_unused_layers no)
			(net "PHY_SCC_B_TO_DRV_B_35_DN")
			(clearance 0.1651)
			(thermal_gap 0.1651)
		)
		(pad "F32" thru_hole circle
			(at 55.79999 9.59993 270)
			(size 0.762 0.762)
			(drill 0.359918)
			(layers "*.Cu" "*.Mask")
			(remove_unused_layers no)
			(net "PHY_SCC_B_TO_DRV_B_34_DN")
			(clearance 0.1651)
			(thermal_gap 0.1651)
		)
		(pad "F33" thru_hole circle
			(at 57.600088 8.599932 270)
			(size 0.762 0.762)
			(drill 0.359918)
			(layers "*.Cu" "*.Mask")
			(remove_unused_layers no)
			(net "PHY_SCC_B_TO_DRV_B_33_DN")
			(clearance 0.1651)
			(thermal_gap 0.1651)
		)
		(pad "F34" thru_hole circle
			(at 59.399932 9.59993 270)
			(size 0.762 0.762)
			(drill 0.359918)
			(layers "*.Cu" "*.Mask")
			(remove_unused_layers no)
			(net "PHY_SCC_B_TO_DRV_B_32_DN")
			(clearance 0.1651)
			(thermal_gap 0.1651)
		)
		(pad "F35" thru_hole circle
			(at 61.20003 8.599932 270)
			(size 0.762 0.762)
			(drill 0.359918)
			(layers "*.Cu" "*.Mask")
			(remove_unused_layers no)
			(net "PHY_SCC_B_TO_DRV_B_31_DN")
			(clearance 0.1651)
			(thermal_gap 0.1651)
		)
		(pad "F36" thru_hole circle
			(at 62.999874 9.59993 270)
			(size 0.762 0.762)
			(drill 0.359918)
			(layers "*.Cu" "*.Mask")
			(remove_unused_layers no)
			(net "PHY_SCC_B_TO_DRV_B_30_DN")
			(clearance 0.1651)
			(thermal_gap 0.1651)
		)
		(pad "GND1" thru_hole circle
			(at 0 2.500122 270)
			(size 0.762 0.762)
			(drill 0.359918)
			(layers "*.Cu" "*.Mask")
			(remove_unused_layers no)
			(net "GND")
			(clearance 0.1651)
			(thermal_gap 0.1651)
		)
		(pad "GND2" thru_hole circle
			(at 0 6.100064 270)
			(size 0.762 0.762)
			(drill 0.359918)
			(layers "*.Cu" "*.Mask")
			(remove_unused_layers no)
			(net "GND")
			(clearance 0.1651)
			(thermal_gap 0.1651)
		)
		(pad "GND3" thru_hole circle
			(at 0 9.700006 270)
			(size 0.762 0.762)
			(drill 0.359918)
			(layers "*.Cu" "*.Mask")
			(remove_unused_layers no)
			(net "GND")
			(clearance 0.1651)
			(thermal_gap 0.1651)
		)
		(pad "GND4" thru_hole circle
			(at 1.800098 -0.100076 270)
			(size 0.762 0.762)
			(drill 0.359918)
			(layers "*.Cu" "*.Mask")
			(remove_unused_layers no)
			(net "GND")
			(clearance 0.1651)
			(thermal_gap 0.1651)
		)
		(pad "GND5" thru_hole circle
			(at 1.800098 3.50012 270)
			(size 0.762 0.762)
			(drill 0.359918)
			(layers "*.Cu" "*.Mask")
			(remove_unused_layers no)
			(net "GND")
			(clearance 0.1651)
			(thermal_gap 0.1651)
		)
		(pad "GND6" thru_hole circle
			(at 1.800098 7.100062 270)
			(size 0.762 0.762)
			(drill 0.359918)
			(layers "*.Cu" "*.Mask")
			(remove_unused_layers no)
			(net "GND")
			(clearance 0.1651)
			(thermal_gap 0.1651)
		)
		(pad "GND7" thru_hole circle
			(at 1.800098 10.700004 270)
			(size 0.762 0.762)
			(drill 0.359918)
			(layers "*.Cu" "*.Mask")
			(remove_unused_layers no)
			(net "GND")
			(clearance 0.1651)
			(thermal_gap 0.1651)
		)
		(pad "GND8" thru_hole circle
			(at 3.599942 2.500122 270)
			(size 0.762 0.762)
			(drill 0.359918)
			(layers "*.Cu" "*.Mask")
			(remove_unused_layers no)
			(net "GND")
			(clearance 0.1651)
			(thermal_gap 0.1651)
		)
		(pad "GND9" thru_hole circle
			(at 3.599942 6.100064 270)
			(size 0.762 0.762)
			(drill 0.359918)
			(layers "*.Cu" "*.Mask")
			(remove_unused_layers no)
			(net "GND")
			(clearance 0.1651)
			(thermal_gap 0.1651)
		)
		(pad "GND10" thru_hole circle
			(at 3.599942 9.700006 270)
			(size 0.762 0.762)
			(drill 0.359918)
			(layers "*.Cu" "*.Mask")
			(remove_unused_layers no)
			(net "GND")
			(clearance 0.1651)
			(thermal_gap 0.1651)
		)
		(pad "GND11" thru_hole circle
			(at 5.40004 -0.100076 270)
			(size 0.762 0.762)
			(drill 0.359918)
			(layers "*.Cu" "*.Mask")
			(remove_unused_layers no)
			(net "GND")
			(clearance 0.1651)
			(thermal_gap 0.1651)
		)
		(pad "GND12" thru_hole circle
			(at 5.40004 3.50012 270)
			(size 0.762 0.762)
			(drill 0.359918)
			(layers "*.Cu" "*.Mask")
			(remove_unused_layers no)
			(net "GND")
			(clearance 0.1651)
			(thermal_gap 0.1651)
		)
		(pad "GND13" thru_hole circle
			(at 5.40004 7.100062 270)
			(size 0.762 0.762)
			(drill 0.359918)
			(layers "*.Cu" "*.Mask")
			(remove_unused_layers no)
			(net "GND")
			(clearance 0.1651)
			(thermal_gap 0.1651)
		)
		(pad "GND14" thru_hole circle
			(at 5.40004 10.700004 270)
			(size 0.762 0.762)
			(drill 0.359918)
			(layers "*.Cu" "*.Mask")
			(remove_unused_layers no)
			(net "GND")
			(clearance 0.1651)
			(thermal_gap 0.1651)
		)
		(pad "GND15" thru_hole circle
			(at 7.199884 2.500122 270)
			(size 0.762 0.762)
			(drill 0.359918)
			(layers "*.Cu" "*.Mask")
			(remove_unused_layers no)
			(net "GND")
			(clearance 0.1651)
			(thermal_gap 0.1651)
		)
		(pad "GND16" thru_hole circle
			(at 7.199884 6.100064 270)
			(size 0.762 0.762)
			(drill 0.359918)
			(layers "*.Cu" "*.Mask")
			(remove_unused_layers no)
			(net "GND")
			(clearance 0.1651)
			(thermal_gap 0.1651)
		)
		(pad "GND17" thru_hole circle
			(at 7.199884 9.700006 270)
			(size 0.762 0.762)
			(drill 0.359918)
			(layers "*.Cu" "*.Mask")
			(remove_unused_layers no)
			(net "GND")
			(clearance 0.1651)
			(thermal_gap 0.1651)
		)
		(pad "GND18" thru_hole circle
			(at 8.999982 -0.100076 270)
			(size 0.762 0.762)
			(drill 0.359918)
			(layers "*.Cu" "*.Mask")
			(remove_unused_layers no)
			(net "GND")
			(clearance 0.1651)
			(thermal_gap 0.1651)
		)
		(pad "GND19" thru_hole circle
			(at 8.999982 3.50012 270)
			(size 0.762 0.762)
			(drill 0.359918)
			(layers "*.Cu" "*.Mask")
			(remove_unused_layers no)
			(net "GND")
			(clearance 0.1651)
			(thermal_gap 0.1651)
		)
		(pad "GND20" thru_hole circle
			(at 8.999982 7.100062 270)
			(size 0.762 0.762)
			(drill 0.359918)
			(layers "*.Cu" "*.Mask")
			(remove_unused_layers no)
			(net "GND")
			(clearance 0.1651)
			(thermal_gap 0.1651)
		)
		(pad "GND21" thru_hole circle
			(at 8.999982 10.700004 270)
			(size 0.762 0.762)
			(drill 0.359918)
			(layers "*.Cu" "*.Mask")
			(remove_unused_layers no)
			(net "GND")
			(clearance 0.1651)
			(thermal_gap 0.1651)
		)
		(pad "GND22" thru_hole circle
			(at 10.80008 2.500122 270)
			(size 0.762 0.762)
			(drill 0.359918)
			(layers "*.Cu" "*.Mask")
			(remove_unused_layers no)
			(net "GND")
			(clearance 0.1651)
			(thermal_gap 0.1651)
		)
		(pad "GND23" thru_hole circle
			(at 10.80008 6.100064 270)
			(size 0.762 0.762)
			(drill 0.359918)
			(layers "*.Cu" "*.Mask")
			(remove_unused_layers no)
			(net "GND")
			(clearance 0.1651)
			(thermal_gap 0.1651)
		)
		(pad "GND24" thru_hole circle
			(at 10.80008 9.700006 270)
			(size 0.762 0.762)
			(drill 0.359918)
			(layers "*.Cu" "*.Mask")
			(remove_unused_layers no)
			(net "GND")
			(clearance 0.1651)
			(thermal_gap 0.1651)
		)
		(pad "GND25" thru_hole circle
			(at 12.599924 -0.100076 270)
			(size 0.762 0.762)
			(drill 0.359918)
			(layers "*.Cu" "*.Mask")
			(remove_unused_layers no)
			(net "GND")
			(clearance 0.1651)
			(thermal_gap 0.1651)
		)
		(pad "GND26" thru_hole circle
			(at 12.599924 3.50012 270)
			(size 0.762 0.762)
			(drill 0.359918)
			(layers "*.Cu" "*.Mask")
			(remove_unused_layers no)
			(net "GND")
			(clearance 0.1651)
			(thermal_gap 0.1651)
		)
		(pad "GND27" thru_hole circle
			(at 12.599924 7.100062 270)
			(size 0.762 0.762)
			(drill 0.359918)
			(layers "*.Cu" "*.Mask")
			(remove_unused_layers no)
			(net "GND")
			(clearance 0.1651)
			(thermal_gap 0.1651)
		)
		(pad "GND28" thru_hole circle
			(at 12.599924 10.700004 270)
			(size 0.762 0.762)
			(drill 0.359918)
			(layers "*.Cu" "*.Mask")
			(remove_unused_layers no)
			(net "GND")
			(clearance 0.1651)
			(thermal_gap 0.1651)
		)
		(pad "GND29" thru_hole circle
			(at 14.400022 2.500122 270)
			(size 0.762 0.762)
			(drill 0.359918)
			(layers "*.Cu" "*.Mask")
			(remove_unused_layers no)
			(net "GND")
			(clearance 0.1651)
			(thermal_gap 0.1651)
		)
		(pad "GND30" thru_hole circle
			(at 14.400022 6.100064 270)
			(size 0.762 0.762)
			(drill 0.359918)
			(layers "*.Cu" "*.Mask")
			(remove_unused_layers no)
			(net "GND")
			(clearance 0.1651)
			(thermal_gap 0.1651)
		)
		(pad "GND31" thru_hole circle
			(at 14.400022 9.700006 270)
			(size 0.762 0.762)
			(drill 0.359918)
			(layers "*.Cu" "*.Mask")
			(remove_unused_layers no)
			(net "GND")
			(clearance 0.1651)
			(thermal_gap 0.1651)
		)
		(pad "GND32" thru_hole circle
			(at 16.20012 -0.100076 270)
			(size 0.762 0.762)
			(drill 0.359918)
			(layers "*.Cu" "*.Mask")
			(remove_unused_layers no)
			(net "GND")
			(clearance 0.1651)
			(thermal_gap 0.1651)
		)
		(pad "GND33" thru_hole circle
			(at 16.20012 3.50012 270)
			(size 0.762 0.762)
			(drill 0.359918)
			(layers "*.Cu" "*.Mask")
			(remove_unused_layers no)
			(net "GND")
			(clearance 0.1651)
			(thermal_gap 0.1651)
		)
		(pad "GND34" thru_hole circle
			(at 16.20012 7.100062 270)
			(size 0.762 0.762)
			(drill 0.359918)
			(layers "*.Cu" "*.Mask")
			(remove_unused_layers no)
			(net "GND")
			(clearance 0.1651)
			(thermal_gap 0.1651)
		)
		(pad "GND35" thru_hole circle
			(at 16.20012 10.700004 270)
			(size 0.762 0.762)
			(drill 0.359918)
			(layers "*.Cu" "*.Mask")
			(remove_unused_layers no)
			(net "GND")
			(clearance 0.1651)
			(thermal_gap 0.1651)
		)
		(pad "GND36" thru_hole circle
			(at 17.999964 2.500122 270)
			(size 0.762 0.762)
			(drill 0.359918)
			(layers "*.Cu" "*.Mask")
			(remove_unused_layers no)
			(net "GND")
			(clearance 0.1651)
			(thermal_gap 0.1651)
		)
		(pad "GND37" thru_hole circle
			(at 17.999964 6.100064 270)
			(size 0.762 0.762)
			(drill 0.359918)
			(layers "*.Cu" "*.Mask")
			(remove_unused_layers no)
			(net "GND")
			(clearance 0.1651)
			(thermal_gap 0.1651)
		)
		(pad "GND38" thru_hole circle
			(at 17.999964 9.700006 270)
			(size 0.762 0.762)
			(drill 0.359918)
			(layers "*.Cu" "*.Mask")
			(remove_unused_layers no)
			(net "GND")
			(clearance 0.1651)
			(thermal_gap 0.1651)
		)
		(pad "GND39" thru_hole circle
			(at 19.800062 -0.100076 270)
			(size 0.762 0.762)
			(drill 0.359918)
			(layers "*.Cu" "*.Mask")
			(remove_unused_layers no)
			(net "GND")
			(clearance 0.1651)
			(thermal_gap 0.1651)
		)
		(pad "GND40" thru_hole circle
			(at 19.800062 3.50012 270)
			(size 0.762 0.762)
			(drill 0.359918)
			(layers "*.Cu" "*.Mask")
			(remove_unused_layers no)
			(net "GND")
			(clearance 0.1651)
			(thermal_gap 0.1651)
		)
		(pad "GND41" thru_hole circle
			(at 19.800062 7.100062 270)
			(size 0.762 0.762)
			(drill 0.359918)
			(layers "*.Cu" "*.Mask")
			(remove_unused_layers no)
			(net "GND")
			(clearance 0.1651)
			(thermal_gap 0.1651)
		)
		(pad "GND42" thru_hole circle
			(at 19.800062 10.700004 270)
			(size 0.762 0.762)
			(drill 0.359918)
			(layers "*.Cu" "*.Mask")
			(remove_unused_layers no)
			(net "GND")
			(clearance 0.1651)
			(thermal_gap 0.1651)
		)
		(pad "GND43" thru_hole circle
			(at 21.599906 2.500122 270)
			(size 0.762 0.762)
			(drill 0.359918)
			(layers "*.Cu" "*.Mask")
			(remove_unused_layers no)
			(net "GND")
			(clearance 0.1651)
			(thermal_gap 0.1651)
		)
		(pad "GND44" thru_hole circle
			(at 21.599906 6.100064 270)
			(size 0.762 0.762)
			(drill 0.359918)
			(layers "*.Cu" "*.Mask")
			(remove_unused_layers no)
			(net "GND")
			(clearance 0.1651)
			(thermal_gap 0.1651)
		)
		(pad "GND45" thru_hole circle
			(at 21.599906 9.700006 270)
			(size 0.762 0.762)
			(drill 0.359918)
			(layers "*.Cu" "*.Mask")
			(remove_unused_layers no)
			(net "GND")
			(clearance 0.1651)
			(thermal_gap 0.1651)
		)
		(pad "GND46" thru_hole circle
			(at 23.400004 -0.100076 270)
			(size 0.762 0.762)
			(drill 0.359918)
			(layers "*.Cu" "*.Mask")
			(remove_unused_layers no)
			(net "GND")
			(clearance 0.1651)
			(thermal_gap 0.1651)
		)
		(pad "GND47" thru_hole circle
			(at 23.400004 3.50012 270)
			(size 0.762 0.762)
			(drill 0.359918)
			(layers "*.Cu" "*.Mask")
			(remove_unused_layers no)
			(net "GND")
			(clearance 0.1651)
			(thermal_gap 0.1651)
		)
		(pad "GND48" thru_hole circle
			(at 23.400004 7.100062 270)
			(size 0.762 0.762)
			(drill 0.359918)
			(layers "*.Cu" "*.Mask")
			(remove_unused_layers no)
			(net "GND")
			(clearance 0.1651)
			(thermal_gap 0.1651)
		)
		(pad "GND49" thru_hole circle
			(at 23.400004 10.700004 270)
			(size 0.762 0.762)
			(drill 0.359918)
			(layers "*.Cu" "*.Mask")
			(remove_unused_layers no)
			(net "GND")
			(clearance 0.1651)
			(thermal_gap 0.1651)
		)
		(pad "GND50" thru_hole circle
			(at 25.200102 2.500122 270)
			(size 0.762 0.762)
			(drill 0.359918)
			(layers "*.Cu" "*.Mask")
			(remove_unused_layers no)
			(net "GND")
			(clearance 0.1651)
			(thermal_gap 0.1651)
		)
		(pad "GND51" thru_hole circle
			(at 25.200102 6.100064 270)
			(size 0.762 0.762)
			(drill 0.359918)
			(layers "*.Cu" "*.Mask")
			(remove_unused_layers no)
			(net "GND")
			(clearance 0.1651)
			(thermal_gap 0.1651)
		)
		(pad "GND52" thru_hole circle
			(at 25.200102 9.700006 270)
			(size 0.762 0.762)
			(drill 0.359918)
			(layers "*.Cu" "*.Mask")
			(remove_unused_layers no)
			(net "GND")
			(clearance 0.1651)
			(thermal_gap 0.1651)
		)
		(pad "GND53" thru_hole circle
			(at 26.999946 -0.100076 270)
			(size 0.762 0.762)
			(drill 0.359918)
			(layers "*.Cu" "*.Mask")
			(remove_unused_layers no)
			(net "GND")
			(clearance 0.1651)
			(thermal_gap 0.1651)
		)
		(pad "GND54" thru_hole circle
			(at 26.999946 3.50012 270)
			(size 0.762 0.762)
			(drill 0.359918)
			(layers "*.Cu" "*.Mask")
			(remove_unused_layers no)
			(net "GND")
			(clearance 0.1651)
			(thermal_gap 0.1651)
		)
		(pad "GND55" thru_hole circle
			(at 26.999946 7.100062 270)
			(size 0.762 0.762)
			(drill 0.359918)
			(layers "*.Cu" "*.Mask")
			(remove_unused_layers no)
			(net "GND")
			(clearance 0.1651)
			(thermal_gap 0.1651)
		)
		(pad "GND56" thru_hole circle
			(at 26.999946 10.700004 270)
			(size 0.762 0.762)
			(drill 0.359918)
			(layers "*.Cu" "*.Mask")
			(remove_unused_layers no)
			(net "GND")
			(clearance 0.1651)
			(thermal_gap 0.1651)
		)
		(pad "GND57" thru_hole circle
			(at 28.800044 2.500122 270)
			(size 0.762 0.762)
			(drill 0.359918)
			(layers "*.Cu" "*.Mask")
			(remove_unused_layers no)
			(net "GND")
			(clearance 0.1651)
			(thermal_gap 0.1651)
		)
		(pad "GND58" thru_hole circle
			(at 28.800044 6.100064 270)
			(size 0.762 0.762)
			(drill 0.359918)
			(layers "*.Cu" "*.Mask")
			(remove_unused_layers no)
			(net "GND")
			(clearance 0.1651)
			(thermal_gap 0.1651)
		)
		(pad "GND59" thru_hole circle
			(at 28.800044 9.700006 270)
			(size 0.762 0.762)
			(drill 0.359918)
			(layers "*.Cu" "*.Mask")
			(remove_unused_layers no)
			(net "GND")
			(clearance 0.1651)
			(thermal_gap 0.1651)
		)
		(pad "GND60" thru_hole circle
			(at 30.599888 -0.100076 270)
			(size 0.762 0.762)
			(drill 0.359918)
			(layers "*.Cu" "*.Mask")
			(remove_unused_layers no)
			(net "GND")
			(clearance 0.1651)
			(thermal_gap 0.1651)
		)
		(pad "GND61" thru_hole circle
			(at 30.599888 3.50012 270)
			(size 0.762 0.762)
			(drill 0.359918)
			(layers "*.Cu" "*.Mask")
			(remove_unused_layers no)
			(net "GND")
			(clearance 0.1651)
			(thermal_gap 0.1651)
		)
		(pad "GND62" thru_hole circle
			(at 30.599888 7.100062 270)
			(size 0.762 0.762)
			(drill 0.359918)
			(layers "*.Cu" "*.Mask")
			(remove_unused_layers no)
			(net "GND")
			(clearance 0.1651)
			(thermal_gap 0.1651)
		)
		(pad "GND63" thru_hole circle
			(at 30.599888 10.700004 270)
			(size 0.762 0.762)
			(drill 0.359918)
			(layers "*.Cu" "*.Mask")
			(remove_unused_layers no)
			(net "GND")
			(clearance 0.1651)
			(thermal_gap 0.1651)
		)
		(pad "GND64" thru_hole circle
			(at 32.399986 2.500122 270)
			(size 0.762 0.762)
			(drill 0.359918)
			(layers "*.Cu" "*.Mask")
			(remove_unused_layers no)
			(net "GND")
			(clearance 0.1651)
			(thermal_gap 0.1651)
		)
		(pad "GND65" thru_hole circle
			(at 32.399986 6.100064 270)
			(size 0.762 0.762)
			(drill 0.359918)
			(layers "*.Cu" "*.Mask")
			(remove_unused_layers no)
			(net "GND")
			(clearance 0.1651)
			(thermal_gap 0.1651)
		)
		(pad "GND66" thru_hole circle
			(at 32.399986 9.700006 270)
			(size 0.762 0.762)
			(drill 0.359918)
			(layers "*.Cu" "*.Mask")
			(remove_unused_layers no)
			(net "GND")
			(clearance 0.1651)
			(thermal_gap 0.1651)
		)
		(pad "GND67" thru_hole circle
			(at 34.200084 -0.100076 270)
			(size 0.762 0.762)
			(drill 0.359918)
			(layers "*.Cu" "*.Mask")
			(remove_unused_layers no)
			(net "GND")
			(clearance 0.1651)
			(thermal_gap 0.1651)
		)
		(pad "GND68" thru_hole circle
			(at 34.200084 3.50012 270)
			(size 0.762 0.762)
			(drill 0.359918)
			(layers "*.Cu" "*.Mask")
			(remove_unused_layers no)
			(net "GND")
			(clearance 0.1651)
			(thermal_gap 0.1651)
		)
		(pad "GND69" thru_hole circle
			(at 34.200084 7.100062 270)
			(size 0.762 0.762)
			(drill 0.359918)
			(layers "*.Cu" "*.Mask")
			(remove_unused_layers no)
			(net "GND")
			(clearance 0.1651)
			(thermal_gap 0.1651)
		)
		(pad "GND70" thru_hole circle
			(at 34.200084 10.700004 270)
			(size 0.762 0.762)
			(drill 0.359918)
			(layers "*.Cu" "*.Mask")
			(remove_unused_layers no)
			(net "GND")
			(clearance 0.1651)
			(thermal_gap 0.1651)
		)
		(pad "GND71" thru_hole circle
			(at 35.999928 2.500122 270)
			(size 0.762 0.762)
			(drill 0.359918)
			(layers "*.Cu" "*.Mask")
			(remove_unused_layers no)
			(net "GND")
			(clearance 0.1651)
			(thermal_gap 0.1651)
		)
		(pad "GND72" thru_hole circle
			(at 35.999928 6.100064 270)
			(size 0.762 0.762)
			(drill 0.359918)
			(layers "*.Cu" "*.Mask")
			(remove_unused_layers no)
			(net "GND")
			(clearance 0.1651)
			(thermal_gap 0.1651)
		)
		(pad "GND73" thru_hole circle
			(at 35.999928 9.700006 270)
			(size 0.762 0.762)
			(drill 0.359918)
			(layers "*.Cu" "*.Mask")
			(remove_unused_layers no)
			(net "GND")
			(clearance 0.1651)
			(thermal_gap 0.1651)
		)
		(pad "GND74" thru_hole circle
			(at 37.800026 -0.100076 270)
			(size 0.762 0.762)
			(drill 0.359918)
			(layers "*.Cu" "*.Mask")
			(remove_unused_layers no)
			(net "GND")
			(clearance 0.1651)
			(thermal_gap 0.1651)
		)
		(pad "GND75" thru_hole circle
			(at 37.800026 3.50012 270)
			(size 0.762 0.762)
			(drill 0.359918)
			(layers "*.Cu" "*.Mask")
			(remove_unused_layers no)
			(net "GND")
			(clearance 0.1651)
			(thermal_gap 0.1651)
		)
		(pad "GND76" thru_hole circle
			(at 37.800026 7.100062 270)
			(size 0.762 0.762)
			(drill 0.359918)
			(layers "*.Cu" "*.Mask")
			(remove_unused_layers no)
			(net "GND")
			(clearance 0.1651)
			(thermal_gap 0.1651)
		)
		(pad "GND77" thru_hole circle
			(at 37.800026 10.700004 270)
			(size 0.762 0.762)
			(drill 0.359918)
			(layers "*.Cu" "*.Mask")
			(remove_unused_layers no)
			(net "GND")
			(clearance 0.1651)
			(thermal_gap 0.1651)
		)
		(pad "GND78" thru_hole circle
			(at 39.600124 2.500122 270)
			(size 0.762 0.762)
			(drill 0.359918)
			(layers "*.Cu" "*.Mask")
			(remove_unused_layers no)
			(net "GND")
			(clearance 0.1651)
			(thermal_gap 0.1651)
		)
		(pad "GND79" thru_hole circle
			(at 39.600124 6.100064 270)
			(size 0.762 0.762)
			(drill 0.359918)
			(layers "*.Cu" "*.Mask")
			(remove_unused_layers no)
			(net "GND")
			(clearance 0.1651)
			(thermal_gap 0.1651)
		)
		(pad "GND80" thru_hole circle
			(at 39.600124 9.700006 270)
			(size 0.762 0.762)
			(drill 0.359918)
			(layers "*.Cu" "*.Mask")
			(remove_unused_layers no)
			(net "GND")
			(clearance 0.1651)
			(thermal_gap 0.1651)
		)
		(pad "GND81" thru_hole circle
			(at 41.399968 -0.100076 270)
			(size 0.762 0.762)
			(drill 0.359918)
			(layers "*.Cu" "*.Mask")
			(remove_unused_layers no)
			(net "GND")
			(clearance 0.1651)
			(thermal_gap 0.1651)
		)
		(pad "GND82" thru_hole circle
			(at 41.399968 3.50012 270)
			(size 0.762 0.762)
			(drill 0.359918)
			(layers "*.Cu" "*.Mask")
			(remove_unused_layers no)
			(net "GND")
			(clearance 0.1651)
			(thermal_gap 0.1651)
		)
		(pad "GND83" thru_hole circle
			(at 41.399968 7.100062 270)
			(size 0.762 0.762)
			(drill 0.359918)
			(layers "*.Cu" "*.Mask")
			(remove_unused_layers no)
			(net "GND")
			(clearance 0.1651)
			(thermal_gap 0.1651)
		)
		(pad "GND84" thru_hole circle
			(at 41.399968 10.700004 270)
			(size 0.762 0.762)
			(drill 0.359918)
			(layers "*.Cu" "*.Mask")
			(remove_unused_layers no)
			(net "GND")
			(clearance 0.1651)
			(thermal_gap 0.1651)
		)
		(pad "GND85" thru_hole circle
			(at 43.200066 2.500122 270)
			(size 0.762 0.762)
			(drill 0.359918)
			(layers "*.Cu" "*.Mask")
			(remove_unused_layers no)
			(net "GND")
			(clearance 0.1651)
			(thermal_gap 0.1651)
		)
		(pad "GND86" thru_hole circle
			(at 43.200066 6.100064 270)
			(size 0.762 0.762)
			(drill 0.359918)
			(layers "*.Cu" "*.Mask")
			(remove_unused_layers no)
			(net "GND")
			(clearance 0.1651)
			(thermal_gap 0.1651)
		)
		(pad "GND87" thru_hole circle
			(at 43.200066 9.700006 270)
			(size 0.762 0.762)
			(drill 0.359918)
			(layers "*.Cu" "*.Mask")
			(remove_unused_layers no)
			(net "GND")
			(clearance 0.1651)
			(thermal_gap 0.1651)
		)
		(pad "GND88" thru_hole circle
			(at 44.99991 -0.100076 270)
			(size 0.762 0.762)
			(drill 0.359918)
			(layers "*.Cu" "*.Mask")
			(remove_unused_layers no)
			(net "GND")
			(clearance 0.1651)
			(thermal_gap 0.1651)
		)
		(pad "GND89" thru_hole circle
			(at 44.99991 3.50012 270)
			(size 0.762 0.762)
			(drill 0.359918)
			(layers "*.Cu" "*.Mask")
			(remove_unused_layers no)
			(net "GND")
			(clearance 0.1651)
			(thermal_gap 0.1651)
		)
		(pad "GND90" thru_hole circle
			(at 44.99991 7.100062 270)
			(size 0.762 0.762)
			(drill 0.359918)
			(layers "*.Cu" "*.Mask")
			(remove_unused_layers no)
			(net "GND")
			(clearance 0.1651)
			(thermal_gap 0.1651)
		)
		(pad "GND91" thru_hole circle
			(at 44.99991 10.700004 270)
			(size 0.762 0.762)
			(drill 0.359918)
			(layers "*.Cu" "*.Mask")
			(remove_unused_layers no)
			(net "GND")
			(clearance 0.1651)
			(thermal_gap 0.1651)
		)
		(pad "GND92" thru_hole circle
			(at 46.800008 2.500122 270)
			(size 0.762 0.762)
			(drill 0.359918)
			(layers "*.Cu" "*.Mask")
			(remove_unused_layers no)
			(net "GND")
			(clearance 0.1651)
			(thermal_gap 0.1651)
		)
		(pad "GND93" thru_hole circle
			(at 46.800008 6.100064 270)
			(size 0.762 0.762)
			(drill 0.359918)
			(layers "*.Cu" "*.Mask")
			(remove_unused_layers no)
			(net "GND")
			(clearance 0.1651)
			(thermal_gap 0.1651)
		)
		(pad "GND94" thru_hole circle
			(at 46.800008 9.700006 270)
			(size 0.762 0.762)
			(drill 0.359918)
			(layers "*.Cu" "*.Mask")
			(remove_unused_layers no)
			(net "GND")
			(clearance 0.1651)
			(thermal_gap 0.1651)
		)
		(pad "GND95" thru_hole circle
			(at 48.600106 -0.100076 270)
			(size 0.762 0.762)
			(drill 0.359918)
			(layers "*.Cu" "*.Mask")
			(remove_unused_layers no)
			(net "GND")
			(clearance 0.1651)
			(thermal_gap 0.1651)
		)
		(pad "GND96" thru_hole circle
			(at 48.600106 3.50012 270)
			(size 0.762 0.762)
			(drill 0.359918)
			(layers "*.Cu" "*.Mask")
			(remove_unused_layers no)
			(net "GND")
			(clearance 0.1651)
			(thermal_gap 0.1651)
		)
		(pad "GND97" thru_hole circle
			(at 48.600106 7.100062 270)
			(size 0.762 0.762)
			(drill 0.359918)
			(layers "*.Cu" "*.Mask")
			(remove_unused_layers no)
			(net "GND")
			(clearance 0.1651)
			(thermal_gap 0.1651)
		)
		(pad "GND98" thru_hole circle
			(at 48.600106 10.700004 270)
			(size 0.762 0.762)
			(drill 0.359918)
			(layers "*.Cu" "*.Mask")
			(remove_unused_layers no)
			(net "GND")
			(clearance 0.1651)
			(thermal_gap 0.1651)
		)
		(pad "GND99" thru_hole circle
			(at 50.39995 2.500122 270)
			(size 0.762 0.762)
			(drill 0.359918)
			(layers "*.Cu" "*.Mask")
			(remove_unused_layers no)
			(net "GND")
			(clearance 0.1651)
			(thermal_gap 0.1651)
		)
		(pad "GND100" thru_hole circle
			(at 50.39995 6.100064 270)
			(size 0.762 0.762)
			(drill 0.359918)
			(layers "*.Cu" "*.Mask")
			(remove_unused_layers no)
			(net "GND")
			(clearance 0.1651)
			(thermal_gap 0.1651)
		)
		(pad "GND101" thru_hole circle
			(at 50.39995 9.700006 270)
			(size 0.762 0.762)
			(drill 0.359918)
			(layers "*.Cu" "*.Mask")
			(remove_unused_layers no)
			(net "GND")
			(clearance 0.1651)
			(thermal_gap 0.1651)
		)
		(pad "GND102" thru_hole circle
			(at 52.200048 -0.100076 270)
			(size 0.762 0.762)
			(drill 0.359918)
			(layers "*.Cu" "*.Mask")
			(remove_unused_layers no)
			(net "GND")
			(clearance 0.1651)
			(thermal_gap 0.1651)
		)
		(pad "GND103" thru_hole circle
			(at 52.200048 3.50012 270)
			(size 0.762 0.762)
			(drill 0.359918)
			(layers "*.Cu" "*.Mask")
			(remove_unused_layers no)
			(net "GND")
			(clearance 0.1651)
			(thermal_gap 0.1651)
		)
		(pad "GND104" thru_hole circle
			(at 52.200048 7.100062 270)
			(size 0.762 0.762)
			(drill 0.359918)
			(layers "*.Cu" "*.Mask")
			(remove_unused_layers no)
			(net "GND")
			(clearance 0.1651)
			(thermal_gap 0.1651)
		)
		(pad "GND105" thru_hole circle
			(at 52.200048 10.700004 270)
			(size 0.762 0.762)
			(drill 0.359918)
			(layers "*.Cu" "*.Mask")
			(remove_unused_layers no)
			(net "GND")
			(clearance 0.1651)
			(thermal_gap 0.1651)
		)
		(pad "GND106" thru_hole circle
			(at 53.999892 2.500122 270)
			(size 0.762 0.762)
			(drill 0.359918)
			(layers "*.Cu" "*.Mask")
			(remove_unused_layers no)
			(net "GND")
			(clearance 0.1651)
			(thermal_gap 0.1651)
		)
		(pad "GND107" thru_hole circle
			(at 53.999892 6.100064 270)
			(size 0.762 0.762)
			(drill 0.359918)
			(layers "*.Cu" "*.Mask")
			(remove_unused_layers no)
			(net "GND")
			(clearance 0.1651)
			(thermal_gap 0.1651)
		)
		(pad "GND108" thru_hole circle
			(at 53.999892 9.700006 270)
			(size 0.762 0.762)
			(drill 0.359918)
			(layers "*.Cu" "*.Mask")
			(remove_unused_layers no)
			(net "GND")
			(clearance 0.1651)
			(thermal_gap 0.1651)
		)
		(pad "GND109" thru_hole circle
			(at 55.79999 -0.100076 270)
			(size 0.762 0.762)
			(drill 0.359918)
			(layers "*.Cu" "*.Mask")
			(remove_unused_layers no)
			(net "GND")
			(clearance 0.1651)
			(thermal_gap 0.1651)
		)
		(pad "GND110" thru_hole circle
			(at 55.79999 3.50012 270)
			(size 0.762 0.762)
			(drill 0.359918)
			(layers "*.Cu" "*.Mask")
			(remove_unused_layers no)
			(net "GND")
			(clearance 0.1651)
			(thermal_gap 0.1651)
		)
		(pad "GND111" thru_hole circle
			(at 55.79999 7.100062 270)
			(size 0.762 0.762)
			(drill 0.359918)
			(layers "*.Cu" "*.Mask")
			(remove_unused_layers no)
			(net "GND")
			(clearance 0.1651)
			(thermal_gap 0.1651)
		)
		(pad "GND112" thru_hole circle
			(at 55.79999 10.700004 270)
			(size 0.762 0.762)
			(drill 0.359918)
			(layers "*.Cu" "*.Mask")
			(remove_unused_layers no)
			(net "GND")
			(clearance 0.1651)
			(thermal_gap 0.1651)
		)
		(pad "GND113" thru_hole circle
			(at 57.600088 2.500122 270)
			(size 0.762 0.762)
			(drill 0.359918)
			(layers "*.Cu" "*.Mask")
			(remove_unused_layers no)
			(net "GND")
			(clearance 0.1651)
			(thermal_gap 0.1651)
		)
		(pad "GND114" thru_hole circle
			(at 57.600088 6.100064 270)
			(size 0.762 0.762)
			(drill 0.359918)
			(layers "*.Cu" "*.Mask")
			(remove_unused_layers no)
			(net "GND")
			(clearance 0.1651)
			(thermal_gap 0.1651)
		)
		(pad "GND115" thru_hole circle
			(at 57.600088 9.700006 270)
			(size 0.762 0.762)
			(drill 0.359918)
			(layers "*.Cu" "*.Mask")
			(remove_unused_layers no)
			(net "GND")
			(clearance 0.1651)
			(thermal_gap 0.1651)
		)
		(pad "GND116" thru_hole circle
			(at 59.399932 -0.100076 270)
			(size 0.762 0.762)
			(drill 0.359918)
			(layers "*.Cu" "*.Mask")
			(remove_unused_layers no)
			(net "GND")
			(clearance 0.1651)
			(thermal_gap 0.1651)
		)
		(pad "GND117" thru_hole circle
			(at 59.399932 3.50012 270)
			(size 0.762 0.762)
			(drill 0.359918)
			(layers "*.Cu" "*.Mask")
			(remove_unused_layers no)
			(net "GND")
			(clearance 0.1651)
			(thermal_gap 0.1651)
		)
		(pad "GND118" thru_hole circle
			(at 59.399932 7.100062 270)
			(size 0.762 0.762)
			(drill 0.359918)
			(layers "*.Cu" "*.Mask")
			(remove_unused_layers no)
			(net "GND")
			(clearance 0.1651)
			(thermal_gap 0.1651)
		)
		(pad "GND119" thru_hole circle
			(at 59.399932 10.700004 270)
			(size 0.762 0.762)
			(drill 0.359918)
			(layers "*.Cu" "*.Mask")
			(remove_unused_layers no)
			(net "GND")
			(clearance 0.1651)
			(thermal_gap 0.1651)
		)
		(pad "GND120" thru_hole circle
			(at 61.20003 2.500122 270)
			(size 0.762 0.762)
			(drill 0.359918)
			(layers "*.Cu" "*.Mask")
			(remove_unused_layers no)
			(net "GND")
			(clearance 0.1651)
			(thermal_gap 0.1651)
		)
		(pad "GND121" thru_hole circle
			(at 61.20003 6.100064 270)
			(size 0.762 0.762)
			(drill 0.359918)
			(layers "*.Cu" "*.Mask")
			(remove_unused_layers no)
			(net "GND")
			(clearance 0.1651)
			(thermal_gap 0.1651)
		)
		(pad "GND122" thru_hole circle
			(at 61.20003 9.700006 270)
			(size 0.762 0.762)
			(drill 0.359918)
			(layers "*.Cu" "*.Mask")
			(remove_unused_layers no)
			(net "GND")
			(clearance 0.1651)
			(thermal_gap 0.1651)
		)
		(pad "GND123" thru_hole circle
			(at 62.999874 -0.100076 270)
			(size 0.762 0.762)
			(drill 0.359918)
			(layers "*.Cu" "*.Mask")
			(remove_unused_layers no)
			(net "GND")
			(clearance 0.1651)
			(thermal_gap 0.1651)
		)
		(pad "GND124" thru_hole circle
			(at 62.999874 3.50012 270)
			(size 0.762 0.762)
			(drill 0.359918)
			(layers "*.Cu" "*.Mask")
			(remove_unused_layers no)
			(net "GND")
			(clearance 0.1651)
			(thermal_gap 0.1651)
		)
		(pad "GND125" thru_hole circle
			(at 62.999874 7.100062 270)
			(size 0.762 0.762)
			(drill 0.359918)
			(layers "*.Cu" "*.Mask")
			(remove_unused_layers no)
			(net "GND")
			(clearance 0.1651)
			(thermal_gap 0.1651)
		)
		(pad "GND126" thru_hole circle
			(at 62.999874 10.700004 270)
			(size 0.762 0.762)
			(drill 0.359918)
			(layers "*.Cu" "*.Mask")
			(remove_unused_layers no)
			(net "GND")
			(clearance 0.1651)
			(thermal_gap 0.1651)
		)
	)
	(footprint ""
		(layer "F.Cu")
		(at 37.9222 -9.4742 -90)
		(property "Reference" "TP2"
			(at 0 0 270)
			(layer "F.SilkS")
			(hide yes)
			(effects
				(font
					(size 1.27 1.27)
				)
			)
		)
		(property "Value" "*"
			(at -0.0508 -1.6764 270)
			(unlocked yes)
			(layer "F.Fab")
			(hide yes)
			(effects
				(font
					(size 1.016 1.016)
					(thickness 0.1524)
				)
			)
		)
		(property "Device Type" "TPAD32"
			(at -0.0508 -3.2004 270)
			(unlocked yes)
			(layer "F.Fab")
			(hide yes)
			(effects
				(font
					(size 1.016 1.016)
					(thickness 0.1524)
				)
			)
		)
		(duplicate_pad_numbers_are_jumpers no)
		(fp_poly
			(pts
				(arc
					(start 0 -0.4064)
					(mid 0 0.4064)
					(end 0 -0.4064)
				)
			)
			(stroke
				(width 0)
				(type default)
			)
			(fill no)
			(layer "F.CrtYd")
		)
		(fp_poly
			(pts
				(arc
					(start 0 -0.7112)
					(mid 0 0.7112)
					(end 0 -0.7112)
				)
			)
			(stroke
				(width 0)
				(type default)
			)
			(fill no)
			(layer "F.Fab")
		)
		(pad "1" smd circle
			(at 0 0 270)
			(size 0.8128 0.8128)
			(layers "F.Cu" "F.Mask" "F.Paste")
			(net "TEMP1_ALERT")
		)
	)
	(footprint ""
		(layer "F.Cu")
		(at 477.536002 -13.6271 180)
		(property "Reference" "VIA71"
			(at 0 0 180)
			(layer "F.SilkS")
			(hide yes)
			(effects
				(font
					(size 1.27 1.27)
				)
			)
		)
		(property "Value" "100OHM-8L-2D36MM-L18-GP"
			(at 3.8989 0.5715 180)
			(unlocked yes)
			(layer "F.Fab")
			(hide yes)
			(effects
				(font
					(size 1.016 1.016)
					(thickness 0.1524)
				)
			)
		)
		(property "Device Type" "VIA-PCIE-4P-414097"
			(at 3.8989 -0.9525 180)
			(unlocked yes)
			(layer "F.Fab")
			(hide yes)
			(effects
				(font
					(size 1.016 1.016)
					(thickness 0.1524)
				)
			)
		)
		(duplicate_pad_numbers_are_jumpers no)
		(fp_rect
			(start -2.0701 0.4826)
			(end 2.0701 -0.4826)
			(stroke
				(width 0)
				(type default)
			)
			(fill no)
			(layer "F.CrtYd")
		)
		(fp_rect
			(start -2.0701 0.4826)
			(end 2.0701 -0.4826)
			(stroke
				(width 0)
				(type default)
			)
			(fill no)
			(layer "F.Fab")
		)
		(pad "1" thru_hole circle
			(at -1.5875 0 180)
			(size 0.508 0.508)
			(drill 0.254)
			(layers "*.Cu" "*.Mask")
			(remove_unused_layers no)
			(net "GND")
			(clearance 0.2286)
			(thermal_gap 0.2286)
		)
		(pad "2" thru_hole circle
			(at -0.5715 0 180)
			(size 0.508 0.508)
			(drill 0.254)
			(layers "*.Cu" "*.Mask")
			(remove_unused_layers no)
			(net "PHY_SCC_B_TO_DRV_B_35_DP")
			(clearance 0.2286)
			(thermal_gap 0.2286)
		)
		(pad "3" thru_hole circle
			(at 0.5715 0 180)
			(size 0.508 0.508)
			(drill 0.254)
			(layers "*.Cu" "*.Mask")
			(remove_unused_layers no)
			(net "PHY_SCC_B_TO_DRV_B_35_DN")
			(clearance 0.2286)
			(thermal_gap 0.2286)
		)
		(pad "4" thru_hole circle
			(at 1.5875 0 180)
			(size 0.508 0.508)
			(drill 0.254)
			(layers "*.Cu" "*.Mask")
			(remove_unused_layers no)
			(net "GND")
			(clearance 0.2286)
			(thermal_gap 0.2286)
		)
	)
	(footprint ""
		(layer "F.Cu")
		(at 74.369168 -97.404428 -90)
		(property "Reference" "R374"
			(at 0 0 270)
			(layer "F.SilkS")
			(hide yes)
			(effects
				(font
					(size 1.27 1.27)
				)
			)
		)
		(property "Value" "4K7R2F-GP"
			(at 0.064008 -3.993896 270)
			(unlocked yes)
			(layer "F.Fab")
			(hide yes)
			(effects
				(font
					(size 1.016 1.016)
					(thickness 0.1524)
				)
			)
		)
		(property "Device Type" "R402H16"
			(at 0.064008 -5.517896 270)
			(unlocked yes)
			(layer "F.Fab")
			(hide yes)
			(effects
				(font
					(size 1.016 1.016)
					(thickness 0.1524)
				)
			)
		)
		(duplicate_pad_numbers_are_jumpers no)
		(fp_line
			(start -0.508 -0.9398)
			(end -0.508 0.9398)
			(stroke
				(width 0.1524)
				(type default)
			)
			(layer "F.SilkS")
		)
		(fp_line
			(start 0.508 -0.9398)
			(end -0.508 -0.9398)
			(stroke
				(width 0.1524)
				(type default)
			)
			(layer "F.SilkS")
		)
		(fp_rect
			(start -0.508 0.9398)
			(end 0.508 -0.9398)
			(stroke
				(width 0)
				(type default)
			)
			(fill no)
			(layer "F.CrtYd")
		)
		(fp_rect
			(start -0.508 0.9398)
			(end 0.508 -0.9398)
			(stroke
				(width 0)
				(type default)
			)
			(fill no)
			(layer "F.Fab")
		)
		(pad "1" smd custom
			(at 0 -0.4445 270)
			(size 0.1397 0.1397)
			(layers "F.Cu" "F.Mask" "F.Paste")
			(net "DRIVE_B_14_ACT")
			(options
				(clearance outline)
				(anchor circle)
			)
			(primitives
				(gr_poly
					(pts
						(arc
							(start -0.1778 -0.2794)
							(mid -0.249642 -0.249642)
							(end -0.2794 -0.1778)
						)
						(arc
							(start -0.2794 0.1778)
							(mid -0.249642 0.249642)
							(end -0.1778 0.2794)
						)
						(arc
							(start 0.1778 0.2794)
							(mid 0.249642 0.249642)
							(end 0.2794 0.1778)
						)
						(arc
							(start 0.2794 -0.1778)
							(mid 0.249642 -0.249642)
							(end 0.1778 -0.2794)
						)
					)
					(width 0)
					(fill yes)
				)
			)
		)
		(pad "2" smd custom
			(at 0 0.4445 270)
			(size 0.1397 0.1397)
			(layers "F.Cu" "F.Mask" "F.Paste")
			(net "GND")
			(options
				(clearance outline)
				(anchor circle)
			)
			(primitives
				(gr_poly
					(pts
						(arc
							(start -0.1778 -0.2794)
							(mid -0.249642 -0.249642)
							(end -0.2794 -0.1778)
						)
						(arc
							(start -0.2794 0.1778)
							(mid -0.249642 0.249642)
							(end -0.1778 0.2794)
						)
						(arc
							(start 0.1778 0.2794)
							(mid 0.249642 0.249642)
							(end 0.2794 0.1778)
						)
						(arc
							(start 0.2794 -0.1778)
							(mid 0.249642 -0.249642)
							(end 0.1778 -0.2794)
						)
					)
					(width 0)
					(fill yes)
				)
			)
		)
	)
	(footprint ""
		(layer "F.Cu")
		(at 334.772 -10.16 180)
		(property "Reference" "R771"
			(at 0 0 180)
			(layer "F.SilkS")
			(hide yes)
			(effects
				(font
					(size 1.27 1.27)
				)
			)
		)
		(property "Value" "0R2J-2-GP"
			(at 0.064008 -3.993896 180)
			(unlocked yes)
			(layer "F.Fab")
			(hide yes)
			(effects
				(font
					(size 1.016 1.016)
					(thickness 0.1524)
				)
			)
		)
		(property "Device Type" "R402H16"
			(at 0.064008 -5.517896 180)
			(unlocked yes)
			(layer "F.Fab")
			(hide yes)
			(effects
				(font
					(size 1.016 1.016)
					(thickness 0.1524)
				)
			)
		)
		(duplicate_pad_numbers_are_jumpers no)
		(fp_line
			(start 0.508 -0.9398)
			(end -0.508 -0.9398)
			(stroke
				(width 0.1524)
				(type default)
			)
			(layer "F.SilkS")
		)
		(fp_line
			(start -0.508 -0.9398)
			(end -0.508 0.9398)
			(stroke
				(width 0.1524)
				(type default)
			)
			(layer "F.SilkS")
		)
		(fp_rect
			(start -0.508 0.9398)
			(end 0.508 -0.9398)
			(stroke
				(width 0)
				(type default)
			)
			(fill no)
			(layer "F.CrtYd")
		)
		(fp_rect
			(start -0.508 0.9398)
			(end 0.508 -0.9398)
			(stroke
				(width 0)
				(type default)
			)
			(fill no)
			(layer "F.Fab")
		)
		(pad "1" smd custom
			(at 0 -0.4445 180)
			(size 0.1397 0.1397)
			(layers "F.Cu" "F.Mask" "F.Paste")
			(net "DRIVE_B_30_PWR")
			(options
				(clearance outline)
				(anchor circle)
			)
			(primitives
				(gr_poly
					(pts
						(arc
							(start -0.1778 -0.2794)
							(mid -0.249642 -0.249642)
							(end -0.2794 -0.1778)
						)
						(arc
							(start -0.2794 0.1778)
							(mid -0.249642 0.249642)
							(end -0.1778 0.2794)
						)
						(arc
							(start 0.1778 0.2794)
							(mid 0.249642 0.249642)
							(end 0.2794 0.1778)
						)
						(arc
							(start 0.2794 -0.1778)
							(mid 0.249642 -0.249642)
							(end 0.1778 -0.2794)
						)
					)
					(width 0)
					(fill yes)
				)
			)
		)
		(pad "2" smd custom
			(at 0 0.4445 180)
			(size 0.1397 0.1397)
			(layers "F.Cu" "F.Mask" "F.Paste")
			(net "SW_PWR_R_HDD30")
			(options
				(clearance outline)
				(anchor circle)
			)
			(primitives
				(gr_poly
					(pts
						(arc
							(start -0.1778 -0.2794)
							(mid -0.249642 -0.249642)
							(end -0.2794 -0.1778)
						)
						(arc
							(start -0.2794 0.1778)
							(mid -0.249642 0.249642)
							(end -0.1778 0.2794)
						)
						(arc
							(start 0.1778 0.2794)
							(mid 0.249642 0.249642)
							(end 0.2794 0.1778)
						)
						(arc
							(start 0.2794 -0.1778)
							(mid 0.249642 -0.249642)
							(end 0.1778 -0.2794)
						)
					)
					(width 0)
					(fill yes)
				)
			)
		)
	)
	(footprint ""
		(layer "F.Cu")
		(at 305.685698 -361.427014 180)
		(property "Reference" "R504"
			(at 0 0 180)
			(layer "F.SilkS")
			(hide yes)
			(effects
				(font
					(size 1.27 1.27)
				)
			)
		)
		(property "Value" "10KR2F-2-GP"
			(at 0.064008 -3.993896 180)
			(unlocked yes)
			(layer "F.Fab")
			(hide yes)
			(effects
				(font
					(size 1.016 1.016)
					(thickness 0.1524)
				)
			)
		)
		(property "Device Type" "R402H16"
			(at 0.064008 -5.517896 180)
			(unlocked yes)
			(layer "F.Fab")
			(hide yes)
			(effects
				(font
					(size 1.016 1.016)
					(thickness 0.1524)
				)
			)
		)
		(duplicate_pad_numbers_are_jumpers no)
		(fp_line
			(start 0.508 -0.9398)
			(end -0.508 -0.9398)
			(stroke
				(width 0.1524)
				(type default)
			)
			(layer "F.SilkS")
		)
		(fp_line
			(start -0.508 -0.9398)
			(end -0.508 0.9398)
			(stroke
				(width 0.1524)
				(type default)
			)
			(layer "F.SilkS")
		)
		(fp_rect
			(start -0.508 0.9398)
			(end 0.508 -0.9398)
			(stroke
				(width 0)
				(type default)
			)
			(fill no)
			(layer "F.CrtYd")
		)
		(fp_rect
			(start -0.508 0.9398)
			(end 0.508 -0.9398)
			(stroke
				(width 0)
				(type default)
			)
			(fill no)
			(layer "F.Fab")
		)
		(pad "1" smd custom
			(at 0 -0.4445 180)
			(size 0.1397 0.1397)
			(layers "F.Cu" "F.Mask" "F.Paste")
			(net "P3V3_STBY_B")
			(options
				(clearance outline)
				(anchor circle)
			)
			(primitives
				(gr_poly
					(pts
						(arc
							(start -0.1778 -0.2794)
							(mid -0.249642 -0.249642)
							(end -0.2794 -0.1778)
						)
						(arc
							(start -0.2794 0.1778)
							(mid -0.249642 0.249642)
							(end -0.1778 0.2794)
						)
						(arc
							(start 0.1778 0.2794)
							(mid 0.249642 0.249642)
							(end 0.2794 0.1778)
						)
						(arc
							(start 0.2794 -0.1778)
							(mid 0.249642 -0.249642)
							(end 0.1778 -0.2794)
						)
					)
					(width 0)
					(fill yes)
				)
			)
		)
		(pad "2" smd custom
			(at 0 0.4445 180)
			(size 0.1397 0.1397)
			(layers "F.Cu" "F.Mask" "F.Paste")
			(net "FANTACH_B_OE")
			(options
				(clearance outline)
				(anchor circle)
			)
			(primitives
				(gr_poly
					(pts
						(arc
							(start -0.1778 -0.2794)
							(mid -0.249642 -0.249642)
							(end -0.2794 -0.1778)
						)
						(arc
							(start -0.2794 0.1778)
							(mid -0.249642 0.249642)
							(end -0.1778 0.2794)
						)
						(arc
							(start 0.1778 0.2794)
							(mid 0.249642 0.249642)
							(end 0.2794 0.1778)
						)
						(arc
							(start 0.2794 -0.1778)
							(mid 0.249642 -0.249642)
							(end 0.1778 -0.2794)
						)
					)
					(width 0)
					(fill yes)
				)
			)
		)
	)
	(footprint ""
		(layer "F.Cu")
		(at 40.3352 -8.1534 -90)
		(property "Reference" "R131"
			(at 0 0 270)
			(layer "F.SilkS")
			(hide yes)
			(effects
				(font
					(size 1.27 1.27)
				)
			)
		)
		(property "Value" "4K7R2F-GP"
			(at 0.064008 -3.993896 270)
			(unlocked yes)
			(layer "F.Fab")
			(hide yes)
			(effects
				(font
					(size 1.016 1.016)
					(thickness 0.1524)
				)
			)
		)
		(property "Device Type" "R402H16"
			(at 0.064008 -5.517896 270)
			(unlocked yes)
			(layer "F.Fab")
			(hide yes)
			(effects
				(font
					(size 1.016 1.016)
					(thickness 0.1524)
				)
			)
		)
		(duplicate_pad_numbers_are_jumpers no)
		(fp_line
			(start -0.508 -0.9398)
			(end -0.508 0.9398)
			(stroke
				(width 0.1524)
				(type default)
			)
			(layer "F.SilkS")
		)
		(fp_line
			(start 0.508 -0.9398)
			(end -0.508 -0.9398)
			(stroke
				(width 0.1524)
				(type default)
			)
			(layer "F.SilkS")
		)
		(fp_rect
			(start -0.508 0.9398)
			(end 0.508 -0.9398)
			(stroke
				(width 0)
				(type default)
			)
			(fill no)
			(layer "F.CrtYd")
		)
		(fp_rect
			(start -0.508 0.9398)
			(end 0.508 -0.9398)
			(stroke
				(width 0)
				(type default)
			)
			(fill no)
			(layer "F.Fab")
		)
		(pad "1" smd custom
			(at 0 -0.4445 270)
			(size 0.1397 0.1397)
			(layers "F.Cu" "F.Mask" "F.Paste")
			(net "TEMP1_A0")
			(options
				(clearance outline)
				(anchor circle)
			)
			(primitives
				(gr_poly
					(pts
						(arc
							(start -0.1778 -0.2794)
							(mid -0.249642 -0.249642)
							(end -0.2794 -0.1778)
						)
						(arc
							(start -0.2794 0.1778)
							(mid -0.249642 0.249642)
							(end -0.1778 0.2794)
						)
						(arc
							(start 0.1778 0.2794)
							(mid 0.249642 0.249642)
							(end 0.2794 0.1778)
						)
						(arc
							(start 0.2794 -0.1778)
							(mid 0.249642 -0.249642)
							(end 0.1778 -0.2794)
						)
					)
					(width 0)
					(fill yes)
				)
			)
		)
		(pad "2" smd custom
			(at 0 0.4445 270)
			(size 0.1397 0.1397)
			(layers "F.Cu" "F.Mask" "F.Paste")
			(net "GND")
			(options
				(clearance outline)
				(anchor circle)
			)
			(primitives
				(gr_poly
					(pts
						(arc
							(start -0.1778 -0.2794)
							(mid -0.249642 -0.249642)
							(end -0.2794 -0.1778)
						)
						(arc
							(start -0.2794 0.1778)
							(mid -0.249642 0.249642)
							(end -0.1778 0.2794)
						)
						(arc
							(start 0.1778 0.2794)
							(mid 0.249642 0.249642)
							(end 0.2794 0.1778)
						)
						(arc
							(start 0.2794 -0.1778)
							(mid 0.249642 -0.249642)
							(end 0.1778 -0.2794)
						)
					)
					(width 0)
					(fill yes)
				)
			)
		)
	)
	(footprint ""
		(layer "F.Cu")
		(at 11.351768 -212.390228 -90)
		(property "Reference" "R155"
			(at 0 0 270)
			(layer "F.SilkS")
			(hide yes)
			(effects
				(font
					(size 1.27 1.27)
				)
			)
		)
		(property "Value" "4K7R2F-GP"
			(at 0.064008 -3.993896 270)
			(unlocked yes)
			(layer "F.Fab")
			(hide yes)
			(effects
				(font
					(size 1.016 1.016)
					(thickness 0.1524)
				)
			)
		)
		(property "Device Type" "R402H16"
			(at 0.064008 -5.517896 270)
			(unlocked yes)
			(layer "F.Fab")
			(hide yes)
			(effects
				(font
					(size 1.016 1.016)
					(thickness 0.1524)
				)
			)
		)
		(duplicate_pad_numbers_are_jumpers no)
		(fp_line
			(start -0.508 -0.9398)
			(end -0.508 0.9398)
			(stroke
				(width 0.1524)
				(type default)
			)
			(layer "F.SilkS")
		)
		(fp_line
			(start 0.508 -0.9398)
			(end -0.508 -0.9398)
			(stroke
				(width 0.1524)
				(type default)
			)
			(layer "F.SilkS")
		)
		(fp_rect
			(start -0.508 0.9398)
			(end 0.508 -0.9398)
			(stroke
				(width 0)
				(type default)
			)
			(fill no)
			(layer "F.CrtYd")
		)
		(fp_rect
			(start -0.508 0.9398)
			(end 0.508 -0.9398)
			(stroke
				(width 0)
				(type default)
			)
			(fill no)
			(layer "F.Fab")
		)
		(pad "1" smd custom
			(at 0 -0.4445 270)
			(size 0.1397 0.1397)
			(layers "F.Cu" "F.Mask" "F.Paste")
			(net "DRIVE_B_0_ACT")
			(options
				(clearance outline)
				(anchor circle)
			)
			(primitives
				(gr_poly
					(pts
						(arc
							(start -0.1778 -0.2794)
							(mid -0.249642 -0.249642)
							(end -0.2794 -0.1778)
						)
						(arc
							(start -0.2794 0.1778)
							(mid -0.249642 0.249642)
							(end -0.1778 0.2794)
						)
						(arc
							(start 0.1778 0.2794)
							(mid 0.249642 0.249642)
							(end 0.2794 0.1778)
						)
						(arc
							(start 0.2794 -0.1778)
							(mid 0.249642 -0.249642)
							(end 0.1778 -0.2794)
						)
					)
					(width 0)
					(fill yes)
				)
			)
		)
		(pad "2" smd custom
			(at 0 0.4445 270)
			(size 0.1397 0.1397)
			(layers "F.Cu" "F.Mask" "F.Paste")
			(net "GND")
			(options
				(clearance outline)
				(anchor circle)
			)
			(primitives
				(gr_poly
					(pts
						(arc
							(start -0.1778 -0.2794)
							(mid -0.249642 -0.249642)
							(end -0.2794 -0.1778)
						)
						(arc
							(start -0.2794 0.1778)
							(mid -0.249642 0.249642)
							(end -0.1778 0.2794)
						)
						(arc
							(start 0.1778 0.2794)
							(mid 0.249642 0.249642)
							(end 0.2794 0.1778)
						)
						(arc
							(start 0.2794 -0.1778)
							(mid 0.249642 -0.249642)
							(end 0.1778 -0.2794)
						)
					)
					(width 0)
					(fill yes)
				)
			)
		)
	)
	(footprint ""
		(layer "F.Cu")
		(at 239.870742 -141.3764 90)
		(property "Reference" "R440"
			(at 0 0 90)
			(layer "F.SilkS")
			(hide yes)
			(effects
				(font
					(size 1.27 1.27)
				)
			)
		)
		(property "Value" "10KR2F-2-GP"
			(at 0.064008 -3.993896 90)
			(unlocked yes)
			(layer "F.Fab")
			(hide yes)
			(effects
				(font
					(size 1.016 1.016)
					(thickness 0.1524)
				)
			)
		)
		(property "Device Type" "R402H16"
			(at 0.064008 -5.517896 90)
			(unlocked yes)
			(layer "F.Fab")
			(hide yes)
			(effects
				(font
					(size 1.016 1.016)
					(thickness 0.1524)
				)
			)
		)
		(duplicate_pad_numbers_are_jumpers no)
		(fp_line
			(start 0.508 -0.9398)
			(end -0.508 -0.9398)
			(stroke
				(width 0.1524)
				(type default)
			)
			(layer "F.SilkS")
		)
		(fp_line
			(start -0.508 -0.9398)
			(end -0.508 0.9398)
			(stroke
				(width 0.1524)
				(type default)
			)
			(layer "F.SilkS")
		)
		(fp_rect
			(start -0.508 0.9398)
			(end 0.508 -0.9398)
			(stroke
				(width 0)
				(type default)
			)
			(fill no)
			(layer "F.CrtYd")
		)
		(fp_rect
			(start -0.508 0.9398)
			(end 0.508 -0.9398)
			(stroke
				(width 0)
				(type default)
			)
			(fill no)
			(layer "F.Fab")
		)
		(pad "1" smd custom
			(at 0 -0.4445 90)
			(size 0.1397 0.1397)
			(layers "F.Cu" "F.Mask" "F.Paste")
			(net "P3V3_STBY_B")
			(options
				(clearance outline)
				(anchor circle)
			)
			(primitives
				(gr_poly
					(pts
						(arc
							(start -0.1778 -0.2794)
							(mid -0.249642 -0.249642)
							(end -0.2794 -0.1778)
						)
						(arc
							(start -0.2794 0.1778)
							(mid -0.249642 0.249642)
							(end -0.1778 0.2794)
						)
						(arc
							(start 0.1778 0.2794)
							(mid 0.249642 0.249642)
							(end 0.2794 0.1778)
						)
						(arc
							(start 0.2794 -0.1778)
							(mid 0.249642 -0.249642)
							(end 0.1778 -0.2794)
						)
					)
					(width 0)
					(fill yes)
				)
			)
		)
		(pad "2" smd custom
			(at 0 0.4445 90)
			(size 0.1397 0.1397)
			(layers "F.Cu" "F.Mask" "F.Paste")
			(net "I2C_SCC_BUFF_EN")
			(options
				(clearance outline)
				(anchor circle)
			)
			(primitives
				(gr_poly
					(pts
						(arc
							(start -0.1778 -0.2794)
							(mid -0.249642 -0.249642)
							(end -0.2794 -0.1778)
						)
						(arc
							(start -0.2794 0.1778)
							(mid -0.249642 0.249642)
							(end -0.1778 0.2794)
						)
						(arc
							(start 0.1778 0.2794)
							(mid 0.249642 0.249642)
							(end 0.2794 0.1778)
						)
						(arc
							(start 0.2794 -0.1778)
							(mid 0.249642 -0.249642)
							(end 0.1778 -0.2794)
						)
					)
					(width 0)
					(fill yes)
				)
			)
		)
	)
	(footprint ""
		(layer "F.Cu")
		(at 174.498 -139.065 -90)
		(property "Reference" "C259"
			(at 0 0 270)
			(layer "F.SilkS")
			(hide yes)
			(effects
				(font
					(size 1.27 1.27)
				)
			)
		)
		(property "Value" "SCD033U25V2KX-GP"
			(at 1.1811 -2.7051 270)
			(unlocked yes)
			(layer "F.Fab")
			(hide yes)
			(effects
				(font
					(size 1.016 1.016)
					(thickness 0.1524)
				)
			)
		)
		(property "Device Type" "C402H22"
			(at 1.1811 -4.2291 270)
			(unlocked yes)
			(layer "F.Fab")
			(hide yes)
			(effects
				(font
					(size 1.016 1.016)
					(thickness 0.1524)
				)
			)
		)
		(duplicate_pad_numbers_are_jumpers no)
		(fp_rect
			(start -0.4318 0.9525)
			(end 0.4318 -0.9525)
			(stroke
				(width 0)
				(type default)
			)
			(fill no)
			(layer "F.CrtYd")
		)
		(fp_rect
			(start -0.4318 0.9525)
			(end 0.4318 -0.9525)
			(stroke
				(width 0)
				(type default)
			)
			(fill no)
			(layer "F.Fab")
		)
		(pad "1" smd custom
			(at 0 -0.4445 270)
			(size 0.1524 0.1524)
			(layers "F.Cu" "F.Mask" "F.Paste")
			(net "SW_HDD_P17")
			(options
				(clearance outline)
				(anchor circle)
			)
			(primitives
				(gr_poly
					(pts
						(arc
							(start 0.3048 -0.2032)
							(mid 0.275042 -0.275042)
							(end 0.2032 -0.3048)
						)
						(arc
							(start -0.2032 -0.3048)
							(mid -0.275042 -0.275042)
							(end -0.3048 -0.2032)
						)
						(arc
							(start -0.3048 0.2032)
							(mid -0.275042 0.275042)
							(end -0.2032 0.3048)
						)
						(arc
							(start 0.2032 0.3048)
							(mid 0.275042 0.275042)
							(end 0.3048 0.2032)
						)
					)
					(width 0)
					(fill yes)
				)
			)
		)
		(pad "2" smd custom
			(at 0 0.4445 270)
			(size 0.1524 0.1524)
			(layers "F.Cu" "F.Mask" "F.Paste")
			(net "GND")
			(options
				(clearance outline)
				(anchor circle)
			)
			(primitives
				(gr_poly
					(pts
						(arc
							(start 0.3048 -0.2032)
							(mid 0.275042 -0.275042)
							(end 0.2032 -0.3048)
						)
						(arc
							(start -0.2032 -0.3048)
							(mid -0.275042 -0.275042)
							(end -0.3048 -0.2032)
						)
						(arc
							(start -0.3048 0.2032)
							(mid -0.275042 0.275042)
							(end -0.2032 0.3048)
						)
						(arc
							(start 0.2032 0.3048)
							(mid 0.275042 0.275042)
							(end 0.3048 0.2032)
						)
					)
					(width 0)
					(fill yes)
				)
			)
		)
	)
	(footprint ""
		(layer "F.Cu")
		(at 257.458972 -372.32971 180)
		(property "Reference" "R1040"
			(at 0 0 180)
			(layer "F.SilkS")
			(hide yes)
			(effects
				(font
					(size 1.27 1.27)
				)
			)
		)
		(property "Value" "3K83R2F-GP"
			(at 0.064008 -3.993896 180)
			(unlocked yes)
			(layer "F.Fab")
			(hide yes)
			(effects
				(font
					(size 1.016 1.016)
					(thickness 0.1524)
				)
			)
		)
		(property "Device Type" "R402H16"
			(at 0.064008 -5.517896 180)
			(unlocked yes)
			(layer "F.Fab")
			(hide yes)
			(effects
				(font
					(size 1.016 1.016)
					(thickness 0.1524)
				)
			)
		)
		(duplicate_pad_numbers_are_jumpers no)
		(fp_line
			(start 0.508 -0.9398)
			(end -0.508 -0.9398)
			(stroke
				(width 0.1524)
				(type default)
			)
			(layer "F.SilkS")
		)
		(fp_line
			(start -0.508 -0.9398)
			(end -0.508 0.9398)
			(stroke
				(width 0.1524)
				(type default)
			)
			(layer "F.SilkS")
		)
		(fp_rect
			(start -0.508 0.9398)
			(end 0.508 -0.9398)
			(stroke
				(width 0)
				(type default)
			)
			(fill no)
			(layer "F.CrtYd")
		)
		(fp_rect
			(start -0.508 0.9398)
			(end 0.508 -0.9398)
			(stroke
				(width 0)
				(type default)
			)
			(fill no)
			(layer "F.Fab")
		)
		(pad "1" smd custom
			(at 0 -0.4445 180)
			(size 0.1397 0.1397)
			(layers "F.Cu" "F.Mask" "F.Paste")
			(net "P12V_B_PGOOD")
			(options
				(clearance outline)
				(anchor circle)
			)
			(primitives
				(gr_poly
					(pts
						(arc
							(start -0.1778 -0.2794)
							(mid -0.249642 -0.249642)
							(end -0.2794 -0.1778)
						)
						(arc
							(start -0.2794 0.1778)
							(mid -0.249642 0.249642)
							(end -0.1778 0.2794)
						)
						(arc
							(start 0.1778 0.2794)
							(mid 0.249642 0.249642)
							(end 0.2794 0.1778)
						)
						(arc
							(start 0.2794 -0.1778)
							(mid 0.249642 -0.249642)
							(end 0.1778 -0.2794)
						)
					)
					(width 0)
					(fill yes)
				)
			)
		)
		(pad "2" smd custom
			(at 0 0.4445 180)
			(size 0.1397 0.1397)
			(layers "F.Cu" "F.Mask" "F.Paste")
			(net "GND")
			(options
				(clearance outline)
				(anchor circle)
			)
			(primitives
				(gr_poly
					(pts
						(arc
							(start -0.1778 -0.2794)
							(mid -0.249642 -0.249642)
							(end -0.2794 -0.1778)
						)
						(arc
							(start -0.2794 0.1778)
							(mid -0.249642 0.249642)
							(end -0.1778 0.2794)
						)
						(arc
							(start 0.1778 0.2794)
							(mid 0.249642 0.249642)
							(end 0.2794 0.1778)
						)
						(arc
							(start 0.2794 -0.1778)
							(mid 0.249642 -0.249642)
							(end 0.1778 -0.2794)
						)
					)
					(width 0)
					(fill yes)
				)
			)
		)
	)
	(footprint ""
		(layer "F.Cu")
		(at 178.435 -256.286 180)
		(property "Reference" "Q18"
			(at 0 0 180)
			(layer "F.SilkS")
			(hide yes)
			(effects
				(font
					(size 1.27 1.27)
				)
			)
		)
		(property "Value" "AO4406AL-GP"
			(at -3.707384 -1.5367 180)
			(unlocked yes)
			(layer "F.Fab")
			(hide yes)
			(effects
				(font
					(size 1.016 1.016)
					(thickness 0.1524)
				)
			)
		)
		(property "Device Type" "SOIC8H69"
			(at -3.707384 -3.0607 180)
			(unlocked yes)
			(layer "F.Fab")
			(hide yes)
			(effects
				(font
					(size 1.016 1.016)
					(thickness 0.1524)
				)
			)
		)
		(duplicate_pad_numbers_are_jumpers no)
		(fp_line
			(start 2.1336 1.4224)
			(end 2.1336 -1.4224)
			(stroke
				(width 0.1524)
				(type default)
			)
			(layer "F.SilkS")
		)
		(fp_line
			(start 2.1336 -1.4224)
			(end -2.7432 -1.4224)
			(stroke
				(width 0.1524)
				(type default)
			)
			(layer "F.SilkS")
		)
		(fp_line
			(start -2.1844 -0.0508)
			(end -2.7178 0.508)
			(stroke
				(width 0.1524)
				(type default)
			)
			(layer "F.SilkS")
		)
		(fp_line
			(start -2.6289 3.4417)
			(end -2.6289 1.4732)
			(stroke
				(width 0.381)
				(type default)
			)
			(layer "F.SilkS")
		)
		(fp_line
			(start -2.7178 -0.508)
			(end -2.1844 -0.0508)
			(stroke
				(width 0.1524)
				(type default)
			)
			(layer "F.SilkS")
		)
		(fp_line
			(start -2.7432 1.4224)
			(end 2.1336 1.4224)
			(stroke
				(width 0.1524)
				(type default)
			)
			(layer "F.SilkS")
		)
		(fp_line
			(start -2.7432 1.4224)
			(end -2.6416 1.4224)
			(stroke
				(width 0.1524)
				(type default)
			)
			(layer "F.SilkS")
		)
		(fp_line
			(start -2.7432 -1.4224)
			(end -2.7432 1.4224)
			(stroke
				(width 0.1524)
				(type default)
			)
			(layer "F.SilkS")
		)
		(fp_poly
			(pts
				(xy -2.2098 -1.4224) (xy -2.2098 1.4224) (xy 2.2098 1.4224) (xy 2.2098 -1.4224)
			)
			(stroke
				(width 0)
				(type default)
			)
			(fill yes)
			(layer "F.SilkS")
		)
		(fp_rect
			(start -2.450084 2.999994)
			(end 2.450084 -2.999994)
			(stroke
				(width 0)
				(type default)
			)
			(fill no)
			(layer "F.CrtYd")
		)
		(fp_poly
			(pts
				(xy -2.8194 3.6322) (xy -2.8194 -3.6322) (xy 2.8194 -3.6322) (xy 2.8194 1.18364) (xy 2.450084 1.18364)
				(xy 2.450084 -2.999994) (xy -2.450084 -2.999994) (xy -2.450084 2.999994) (xy 2.450084 2.999994)
				(xy 2.450084 1.18618) (xy 2.8194 1.18618) (xy 2.8194 3.6322)
			)
			(stroke
				(width 0)
				(type default)
			)
			(fill no)
			(layer "F.CrtYd")
		)
		(fp_rect
			(start -2.8194 3.6322)
			(end 2.8194 -3.6322)
			(stroke
				(width 0)
				(type default)
			)
			(fill no)
			(layer "F.Fab")
		)
		(pad "1" smd rect
			(at -1.905 2.54 180)
			(size 0.635 1.651)
			(layers "F.Cu" "F.Mask" "F.Paste")
			(net "P5V_HDD5")
		)
		(pad "2" smd rect
			(at -0.635 2.54 180)
			(size 0.635 1.651)
			(layers "F.Cu" "F.Mask" "F.Paste")
			(net "P5V_HDD5")
		)
		(pad "3" smd rect
			(at 0.635 2.54 180)
			(size 0.635 1.651)
			(layers "F.Cu" "F.Mask" "F.Paste")
			(net "P5V_HDD5")
		)
		(pad "4" smd rect
			(at 1.905 2.54 180)
			(size 0.635 1.651)
			(layers "F.Cu" "F.Mask" "F.Paste")
			(net "SW_HDD_P5")
		)
		(pad "5" smd rect
			(at 1.905 -2.54 180)
			(size 0.635 1.651)
			(layers "F.Cu" "F.Mask" "F.Paste")
			(net "P5V_B_1")
		)
		(pad "6" smd rect
			(at 0.635 -2.54 180)
			(size 0.635 1.651)
			(layers "F.Cu" "F.Mask" "F.Paste")
			(net "P5V_B_1")
		)
		(pad "7" smd rect
			(at -0.635 -2.54 180)
			(size 0.635 1.651)
			(layers "F.Cu" "F.Mask" "F.Paste")
			(net "P5V_B_1")
		)
		(pad "8" smd rect
			(at -1.905 -2.54 180)
			(size 0.635 1.651)
			(layers "F.Cu" "F.Mask" "F.Paste")
			(net "P5V_B_1")
		)
	)
	(footprint ""
		(layer "F.Cu")
		(at 52.578 -16.637 -90)
		(property "Reference" "Q125"
			(at 0 0 270)
			(layer "F.SilkS")
			(hide yes)
			(effects
				(font
					(size 1.27 1.27)
				)
			)
		)
		(property "Value" "2N7002KDW-GP"
			(at -2.3622 -8.2042 270)
			(unlocked yes)
			(layer "F.Fab")
			(hide yes)
			(effects
				(font
					(size 1.016 1.016)
					(thickness 0.1524)
				)
			)
		)
		(property "Device Type" "SOT-363H44"
			(at -2.3622 -10.1092 270)
			(unlocked yes)
			(layer "F.Fab")
			(hide yes)
			(effects
				(font
					(size 1.016 1.016)
					(thickness 0.1524)
				)
			)
		)
		(duplicate_pad_numbers_are_jumpers no)
		(fp_line
			(start -1.4478 1.7018)
			(end 1.4478 1.7018)
			(stroke
				(width 0.1524)
				(type default)
			)
			(layer "F.SilkS")
		)
		(fp_line
			(start 1.4478 1.7018)
			(end 1.4478 -1.7018)
			(stroke
				(width 0.1524)
				(type default)
			)
			(layer "F.SilkS")
		)
		(fp_line
			(start -1.27 1.524)
			(end -1.27 0.6604)
			(stroke
				(width 0.4826)
				(type default)
			)
			(layer "F.SilkS")
		)
		(fp_line
			(start -1.4478 -1.7018)
			(end -1.4478 1.7018)
			(stroke
				(width 0.1524)
				(type default)
			)
			(layer "F.SilkS")
		)
		(fp_line
			(start 1.4478 -1.7018)
			(end -1.4478 -1.7018)
			(stroke
				(width 0.1524)
				(type default)
			)
			(layer "F.SilkS")
		)
		(fp_poly
			(pts
				(xy -1.524 -1.778) (xy 1.524 -1.778) (xy 1.524 1.778) (xy -1.524 1.778)
			)
			(stroke
				(width 0)
				(type default)
			)
			(fill no)
			(layer "F.CrtYd")
		)
		(fp_poly
			(pts
				(xy -1.524 -1.778) (xy 1.524 -1.778) (xy 1.524 1.778) (xy -1.524 1.778)
			)
			(stroke
				(width 0)
				(type default)
			)
			(fill no)
			(layer "F.Fab")
		)
		(pad "1" smd rect
			(at -0.65024 0.9398 270)
			(size 0.4064 1.016)
			(layers "F.Cu" "F.Mask" "F.Paste")
			(net "GND")
		)
		(pad "2" smd rect
			(at 0 0.9398 270)
			(size 0.4064 1.016)
			(layers "F.Cu" "F.Mask" "F.Paste")
			(net "SW_PWR_R_HDD25")
		)
		(pad "3" smd rect
			(at 0.65024 0.9398 270)
			(size 0.4064 1.016)
			(layers "F.Cu" "F.Mask" "F.Paste")
			(net "SW_HDD_P25")
		)
		(pad "4" smd rect
			(at 0.65024 -0.9398 270)
			(size 0.4064 1.016)
			(layers "F.Cu" "F.Mask" "F.Paste")
			(net "GND")
		)
		(pad "5" smd rect
			(at 0 -0.9398 270)
			(size 0.4064 1.016)
			(layers "F.Cu" "F.Mask" "F.Paste")
			(net "SW_HDD_G25")
		)
		(pad "6" smd rect
			(at -0.65024 -0.9398 270)
			(size 0.4064 1.016)
			(layers "F.Cu" "F.Mask" "F.Paste")
			(net "SW_HDD_R25")
		)
	)
	(footprint ""
		(layer "F.Cu")
		(at 55.4228 -99.314)
		(property "Reference" "R397"
			(at 0 0 0)
			(layer "F.SilkS")
			(hide yes)
			(effects
				(font
					(size 1.27 1.27)
				)
			)
		)
		(property "Value" "91R3F-1-GP"
			(at -0.0254 -2.5146 0)
			(unlocked yes)
			(layer "F.Fab")
			(hide yes)
			(effects
				(font
					(size 1.016 1.016)
					(thickness 0.1524)
				)
			)
		)
		(property "Device Type" "R603H22"
			(at -0.0254 -4.0386 0)
			(unlocked yes)
			(layer "F.Fab")
			(hide yes)
			(effects
				(font
					(size 1.016 1.016)
					(thickness 0.1524)
				)
			)
		)
		(duplicate_pad_numbers_are_jumpers no)
		(fp_line
			(start -0.4826 0)
			(end -0.2032 0)
			(stroke
				(width 0.2032)
				(type default)
			)
			(layer "F.SilkS")
		)
		(fp_line
			(start 0.2032 0)
			(end 0.4826 0)
			(stroke
				(width 0.2032)
				(type default)
			)
			(layer "F.SilkS")
		)
		(fp_rect
			(start -0.5842 1.3335)
			(end 0.5842 -1.3335)
			(stroke
				(width 0)
				(type default)
			)
			(fill no)
			(layer "F.CrtYd")
		)
		(fp_rect
			(start -0.5842 1.3335)
			(end 0.5842 -1.3335)
			(stroke
				(width 0)
				(type default)
			)
			(fill no)
			(layer "F.Fab")
		)
		(pad "1" smd custom
			(at 0 -0.762)
			(size 0.2159 0.2159)
			(layers "F.Cu" "F.Mask" "F.Paste")
			(net "P5V_B_1")
			(options
				(clearance outline)
				(anchor circle)
			)
			(primitives
				(gr_poly
					(pts
						(arc
							(start -0.3302 -0.4318)
							(mid -0.402042 -0.402042)
							(end -0.4318 -0.3302)
						)
						(arc
							(start -0.4318 0.3302)
							(mid -0.402042 0.402042)
							(end -0.3302 0.4318)
						)
						(arc
							(start 0.3302 0.4318)
							(mid 0.402042 0.402042)
							(end 0.4318 0.3302)
						)
						(arc
							(start 0.4318 -0.3302)
							(mid 0.402042 -0.402042)
							(end 0.3302 -0.4318)
						)
					)
					(width 0)
					(fill yes)
				)
			)
		)
		(pad "2" smd custom
			(at 0 0.762)
			(size 0.2159 0.2159)
			(layers "F.Cu" "F.Mask" "F.Paste")
			(net "DRV_ACT_13")
			(options
				(clearance outline)
				(anchor circle)
			)
			(primitives
				(gr_poly
					(pts
						(arc
							(start -0.3302 -0.4318)
							(mid -0.402042 -0.402042)
							(end -0.4318 -0.3302)
						)
						(arc
							(start -0.4318 0.3302)
							(mid -0.402042 0.402042)
							(end -0.3302 0.4318)
						)
						(arc
							(start 0.3302 0.4318)
							(mid 0.402042 0.402042)
							(end 0.4318 0.3302)
						)
						(arc
							(start 0.4318 -0.3302)
							(mid 0.402042 -0.402042)
							(end 0.3302 -0.4318)
						)
					)
					(width 0)
					(fill yes)
				)
			)
		)
	)
	(footprint ""
		(layer "F.Cu")
		(at 430.403 -16.764 180)
		(property "Reference" "R846"
			(at 0 0 180)
			(layer "F.SilkS")
			(hide yes)
			(effects
				(font
					(size 1.27 1.27)
				)
			)
		)
		(property "Value" "0R2J-2-GP"
			(at 0.064008 -3.993896 180)
			(unlocked yes)
			(layer "F.Fab")
			(hide yes)
			(effects
				(font
					(size 1.016 1.016)
					(thickness 0.1524)
				)
			)
		)
		(property "Device Type" "R402H16"
			(at 0.064008 -5.517896 180)
			(unlocked yes)
			(layer "F.Fab")
			(hide yes)
			(effects
				(font
					(size 1.016 1.016)
					(thickness 0.1524)
				)
			)
		)
		(duplicate_pad_numbers_are_jumpers no)
		(fp_line
			(start 0.508 -0.9398)
			(end -0.508 -0.9398)
			(stroke
				(width 0.1524)
				(type default)
			)
			(layer "F.SilkS")
		)
		(fp_line
			(start -0.508 -0.9398)
			(end -0.508 0.9398)
			(stroke
				(width 0.1524)
				(type default)
			)
			(layer "F.SilkS")
		)
		(fp_rect
			(start -0.508 0.9398)
			(end 0.508 -0.9398)
			(stroke
				(width 0)
				(type default)
			)
			(fill no)
			(layer "F.CrtYd")
		)
		(fp_rect
			(start -0.508 0.9398)
			(end 0.508 -0.9398)
			(stroke
				(width 0)
				(type default)
			)
			(fill no)
			(layer "F.Fab")
		)
		(pad "1" smd custom
			(at 0 -0.4445 180)
			(size 0.1397 0.1397)
			(layers "F.Cu" "F.Mask" "F.Paste")
			(net "SW_HDD_G33")
			(options
				(clearance outline)
				(anchor circle)
			)
			(primitives
				(gr_poly
					(pts
						(arc
							(start -0.1778 -0.2794)
							(mid -0.249642 -0.249642)
							(end -0.2794 -0.1778)
						)
						(arc
							(start -0.2794 0.1778)
							(mid -0.249642 0.249642)
							(end -0.1778 0.2794)
						)
						(arc
							(start 0.1778 0.2794)
							(mid 0.249642 0.249642)
							(end 0.2794 0.1778)
						)
						(arc
							(start 0.2794 -0.1778)
							(mid 0.249642 -0.249642)
							(end 0.1778 -0.2794)
						)
					)
					(width 0)
					(fill yes)
				)
			)
		)
		(pad "2" smd custom
			(at 0 0.4445 180)
			(size 0.1397 0.1397)
			(layers "F.Cu" "F.Mask" "F.Paste")
			(net "SW_HDD_R33")
			(options
				(clearance outline)
				(anchor circle)
			)
			(primitives
				(gr_poly
					(pts
						(arc
							(start -0.1778 -0.2794)
							(mid -0.249642 -0.249642)
							(end -0.2794 -0.1778)
						)
						(arc
							(start -0.2794 0.1778)
							(mid -0.249642 0.249642)
							(end -0.1778 0.2794)
						)
						(arc
							(start 0.1778 0.2794)
							(mid 0.249642 0.249642)
							(end 0.2794 0.1778)
						)
						(arc
							(start 0.2794 -0.1778)
							(mid 0.249642 -0.249642)
							(end 0.1778 -0.2794)
						)
					)
					(width 0)
					(fill yes)
				)
			)
		)
	)
	(footprint ""
		(layer "F.Cu")
		(at 114.681 -146.939 -90)
		(property "Reference" "C226"
			(at 0 0 270)
			(layer "F.SilkS")
			(hide yes)
			(effects
				(font
					(size 1.27 1.27)
				)
			)
		)
		(property "Value" "SC10U16V6KX-2GP"
			(at -0.0762 -5.1308 270)
			(unlocked yes)
			(layer "F.Fab")
			(hide yes)
			(effects
				(font
					(size 1.016 1.016)
					(thickness 0.1524)
				)
			)
		)
		(property "Device Type" "C1206H71"
			(at -0.127 -6.6548 270)
			(unlocked yes)
			(layer "F.Fab")
			(hide yes)
			(effects
				(font
					(size 1.016 1.016)
					(thickness 0.1524)
				)
			)
		)
		(duplicate_pad_numbers_are_jumpers no)
		(fp_line
			(start -1.016 2.2352)
			(end -1.016 0.8382)
			(stroke
				(width 0.1524)
				(type default)
			)
			(layer "F.SilkS")
		)
		(fp_line
			(start 1.016 2.2352)
			(end -1.016 2.2352)
			(stroke
				(width 0.1524)
				(type default)
			)
			(layer "F.SilkS")
		)
		(fp_line
			(start 1.016 0.8382)
			(end 1.016 2.2352)
			(stroke
				(width 0.1524)
				(type default)
			)
			(layer "F.SilkS")
		)
		(fp_line
			(start -1.016 -0.8382)
			(end -1.016 -2.2352)
			(stroke
				(width 0.1524)
				(type default)
			)
			(layer "F.SilkS")
		)
		(fp_line
			(start -1.016 -2.2352)
			(end 1.016 -2.2352)
			(stroke
				(width 0.1524)
				(type default)
			)
			(layer "F.SilkS")
		)
		(fp_line
			(start 1.016 -2.2352)
			(end 1.016 -0.8382)
			(stroke
				(width 0.1524)
				(type default)
			)
			(layer "F.SilkS")
		)
		(fp_rect
			(start -1.0922 2.3114)
			(end 1.0922 -2.3114)
			(stroke
				(width 0)
				(type default)
			)
			(fill no)
			(layer "F.CrtYd")
		)
		(fp_poly
			(pts
				(xy 1.0922 -2.3114) (xy 1.0922 2.3114) (xy -1.0922 2.3114) (xy -1.0922 -2.3114)
			)
			(stroke
				(width 0)
				(type default)
			)
			(fill no)
			(layer "F.Fab")
		)
		(pad "1" smd rect
			(at 0 -1.397 270)
			(size 1.651 1.27)
			(layers "F.Cu" "F.Mask" "F.Paste")
			(net "P5V_HDD15")
		)
		(pad "2" smd rect
			(at 0 1.397 270)
			(size 1.651 1.27)
			(layers "F.Cu" "F.Mask" "F.Paste")
			(net "GND")
		)
	)
	(footprint ""
		(layer "F.Cu")
		(at 254.585978 -228.36505 -90)
		(property "Reference" "R116"
			(at 0 0 270)
			(layer "F.SilkS")
			(hide yes)
			(effects
				(font
					(size 1.27 1.27)
				)
			)
		)
		(property "Value" "10KR2F-2-GP"
			(at 0.064008 -3.993896 270)
			(unlocked yes)
			(layer "F.Fab")
			(hide yes)
			(effects
				(font
					(size 1.016 1.016)
					(thickness 0.1524)
				)
			)
		)
		(property "Device Type" "R402H16"
			(at 0.064008 -5.517896 270)
			(unlocked yes)
			(layer "F.Fab")
			(hide yes)
			(effects
				(font
					(size 1.016 1.016)
					(thickness 0.1524)
				)
			)
		)
		(duplicate_pad_numbers_are_jumpers no)
		(fp_line
			(start -0.508 -0.9398)
			(end -0.508 0.9398)
			(stroke
				(width 0.1524)
				(type default)
			)
			(layer "F.SilkS")
		)
		(fp_line
			(start 0.508 -0.9398)
			(end -0.508 -0.9398)
			(stroke
				(width 0.1524)
				(type default)
			)
			(layer "F.SilkS")
		)
		(fp_rect
			(start -0.508 0.9398)
			(end 0.508 -0.9398)
			(stroke
				(width 0)
				(type default)
			)
			(fill no)
			(layer "F.CrtYd")
		)
		(fp_rect
			(start -0.508 0.9398)
			(end 0.508 -0.9398)
			(stroke
				(width 0)
				(type default)
			)
			(fill no)
			(layer "F.Fab")
		)
		(pad "1" smd custom
			(at 0 -0.4445 270)
			(size 0.1397 0.1397)
			(layers "F.Cu" "F.Mask" "F.Paste")
			(net "P5V_B_1_SENSE")
			(options
				(clearance outline)
				(anchor circle)
			)
			(primitives
				(gr_poly
					(pts
						(arc
							(start -0.1778 -0.2794)
							(mid -0.249642 -0.249642)
							(end -0.2794 -0.1778)
						)
						(arc
							(start -0.2794 0.1778)
							(mid -0.249642 0.249642)
							(end -0.1778 0.2794)
						)
						(arc
							(start 0.1778 0.2794)
							(mid 0.249642 0.249642)
							(end 0.2794 0.1778)
						)
						(arc
							(start 0.2794 -0.1778)
							(mid 0.249642 -0.249642)
							(end 0.1778 -0.2794)
						)
					)
					(width 0)
					(fill yes)
				)
			)
		)
		(pad "2" smd custom
			(at 0 0.4445 270)
			(size 0.1397 0.1397)
			(layers "F.Cu" "F.Mask" "F.Paste")
			(net "GND")
			(options
				(clearance outline)
				(anchor circle)
			)
			(primitives
				(gr_poly
					(pts
						(arc
							(start -0.1778 -0.2794)
							(mid -0.249642 -0.249642)
							(end -0.2794 -0.1778)
						)
						(arc
							(start -0.2794 0.1778)
							(mid -0.249642 0.249642)
							(end -0.1778 0.2794)
						)
						(arc
							(start 0.1778 0.2794)
							(mid 0.249642 0.249642)
							(end 0.2794 0.1778)
						)
						(arc
							(start 0.2794 -0.1778)
							(mid 0.249642 -0.249642)
							(end 0.1778 -0.2794)
						)
					)
					(width 0)
					(fill yes)
				)
			)
		)
	)
	(footprint ""
		(layer "F.Cu")
		(at 83.82 -256.286 180)
		(property "Reference" "Q6"
			(at 0 0 180)
			(layer "F.SilkS")
			(hide yes)
			(effects
				(font
					(size 1.27 1.27)
				)
			)
		)
		(property "Value" "AO4406AL-GP"
			(at -3.707384 -1.5367 180)
			(unlocked yes)
			(layer "F.Fab")
			(hide yes)
			(effects
				(font
					(size 1.016 1.016)
					(thickness 0.1524)
				)
			)
		)
		(property "Device Type" "SOIC8H69"
			(at -3.707384 -3.0607 180)
			(unlocked yes)
			(layer "F.Fab")
			(hide yes)
			(effects
				(font
					(size 1.016 1.016)
					(thickness 0.1524)
				)
			)
		)
		(duplicate_pad_numbers_are_jumpers no)
		(fp_line
			(start 2.1336 1.4224)
			(end 2.1336 -1.4224)
			(stroke
				(width 0.1524)
				(type default)
			)
			(layer "F.SilkS")
		)
		(fp_line
			(start 2.1336 -1.4224)
			(end -2.7432 -1.4224)
			(stroke
				(width 0.1524)
				(type default)
			)
			(layer "F.SilkS")
		)
		(fp_line
			(start -2.1844 -0.0508)
			(end -2.7178 0.508)
			(stroke
				(width 0.1524)
				(type default)
			)
			(layer "F.SilkS")
		)
		(fp_line
			(start -2.6289 3.4417)
			(end -2.6289 1.4732)
			(stroke
				(width 0.381)
				(type default)
			)
			(layer "F.SilkS")
		)
		(fp_line
			(start -2.7178 -0.508)
			(end -2.1844 -0.0508)
			(stroke
				(width 0.1524)
				(type default)
			)
			(layer "F.SilkS")
		)
		(fp_line
			(start -2.7432 1.4224)
			(end 2.1336 1.4224)
			(stroke
				(width 0.1524)
				(type default)
			)
			(layer "F.SilkS")
		)
		(fp_line
			(start -2.7432 1.4224)
			(end -2.6416 1.4224)
			(stroke
				(width 0.1524)
				(type default)
			)
			(layer "F.SilkS")
		)
		(fp_line
			(start -2.7432 -1.4224)
			(end -2.7432 1.4224)
			(stroke
				(width 0.1524)
				(type default)
			)
			(layer "F.SilkS")
		)
		(fp_poly
			(pts
				(xy -2.2098 -1.4224) (xy -2.2098 1.4224) (xy 2.2098 1.4224) (xy 2.2098 -1.4224)
			)
			(stroke
				(width 0)
				(type default)
			)
			(fill yes)
			(layer "F.SilkS")
		)
		(fp_rect
			(start -2.450084 2.999994)
			(end 2.450084 -2.999994)
			(stroke
				(width 0)
				(type default)
			)
			(fill no)
			(layer "F.CrtYd")
		)
		(fp_poly
			(pts
				(xy -2.8194 3.6322) (xy -2.8194 -3.6322) (xy 2.8194 -3.6322) (xy 2.8194 1.18364) (xy 2.450084 1.18364)
				(xy 2.450084 -2.999994) (xy -2.450084 -2.999994) (xy -2.450084 2.999994) (xy 2.450084 2.999994)
				(xy 2.450084 1.18618) (xy 2.8194 1.18618) (xy 2.8194 3.6322)
			)
			(stroke
				(width 0)
				(type default)
			)
			(fill no)
			(layer "F.CrtYd")
		)
		(fp_rect
			(start -2.8194 3.6322)
			(end 2.8194 -3.6322)
			(stroke
				(width 0)
				(type default)
			)
			(fill no)
			(layer "F.Fab")
		)
		(pad "1" smd rect
			(at -1.905 2.54 180)
			(size 0.635 1.651)
			(layers "F.Cu" "F.Mask" "F.Paste")
			(net "P5V_HDD2")
		)
		(pad "2" smd rect
			(at -0.635 2.54 180)
			(size 0.635 1.651)
			(layers "F.Cu" "F.Mask" "F.Paste")
			(net "P5V_HDD2")
		)
		(pad "3" smd rect
			(at 0.635 2.54 180)
			(size 0.635 1.651)
			(layers "F.Cu" "F.Mask" "F.Paste")
			(net "P5V_HDD2")
		)
		(pad "4" smd rect
			(at 1.905 2.54 180)
			(size 0.635 1.651)
			(layers "F.Cu" "F.Mask" "F.Paste")
			(net "SW_HDD_P2")
		)
		(pad "5" smd rect
			(at 1.905 -2.54 180)
			(size 0.635 1.651)
			(layers "F.Cu" "F.Mask" "F.Paste")
			(net "P5V_B_1")
		)
		(pad "6" smd rect
			(at 0.635 -2.54 180)
			(size 0.635 1.651)
			(layers "F.Cu" "F.Mask" "F.Paste")
			(net "P5V_B_1")
		)
		(pad "7" smd rect
			(at -0.635 -2.54 180)
			(size 0.635 1.651)
			(layers "F.Cu" "F.Mask" "F.Paste")
			(net "P5V_B_1")
		)
		(pad "8" smd rect
			(at -1.905 -2.54 180)
			(size 0.635 1.651)
			(layers "F.Cu" "F.Mask" "F.Paste")
			(net "P5V_B_1")
		)
	)
	(footprint ""
		(layer "F.Cu")
		(at 329.819 -152.908 180)
		(property "Reference" "C264"
			(at 0 0 180)
			(layer "F.SilkS")
			(hide yes)
			(effects
				(font
					(size 1.27 1.27)
				)
			)
		)
		(property "Value" "SC1U16V3KX-5GP"
			(at 0 -2.8194 180)
			(unlocked yes)
			(layer "F.Fab")
			(hide yes)
			(effects
				(font
					(size 1.016 1.016)
					(thickness 0.1524)
				)
			)
		)
		(property "Device Type" "C603H36"
			(at 0 -4.3434 180)
			(unlocked yes)
			(layer "F.Fab")
			(hide yes)
			(effects
				(font
					(size 1.016 1.016)
					(thickness 0.1524)
				)
			)
		)
		(duplicate_pad_numbers_are_jumpers no)
		(fp_line
			(start 0.508 0)
			(end -0.508 0)
			(stroke
				(width 0.2032)
				(type default)
			)
			(layer "F.SilkS")
		)
		(fp_rect
			(start -0.5842 1.3335)
			(end 0.5842 -1.3335)
			(stroke
				(width 0)
				(type default)
			)
			(fill no)
			(layer "F.CrtYd")
		)
		(fp_rect
			(start -0.5842 1.3335)
			(end 0.5842 -1.3335)
			(stroke
				(width 0)
				(type default)
			)
			(fill no)
			(layer "F.Fab")
		)
		(pad "1" smd custom
			(at 0 -0.762 180)
			(size 0.2159 0.2159)
			(layers "F.Cu" "F.Mask" "F.Paste")
			(net "P5V_HDD18")
			(options
				(clearance outline)
				(anchor circle)
			)
			(primitives
				(gr_poly
					(pts
						(arc
							(start -0.3302 -0.4318)
							(mid -0.402042 -0.402042)
							(end -0.4318 -0.3302)
						)
						(arc
							(start -0.4318 0.3302)
							(mid -0.402042 0.402042)
							(end -0.3302 0.4318)
						)
						(arc
							(start 0.3302 0.4318)
							(mid 0.402042 0.402042)
							(end 0.4318 0.3302)
						)
						(arc
							(start 0.4318 -0.3302)
							(mid 0.402042 -0.402042)
							(end 0.3302 -0.4318)
						)
					)
					(width 0)
					(fill yes)
				)
			)
		)
		(pad "2" smd custom
			(at 0 0.762 180)
			(size 0.2159 0.2159)
			(layers "F.Cu" "F.Mask" "F.Paste")
			(net "GND")
			(options
				(clearance outline)
				(anchor circle)
			)
			(primitives
				(gr_poly
					(pts
						(arc
							(start -0.3302 -0.4318)
							(mid -0.402042 -0.402042)
							(end -0.4318 -0.3302)
						)
						(arc
							(start -0.4318 0.3302)
							(mid -0.402042 0.402042)
							(end -0.3302 0.4318)
						)
						(arc
							(start 0.3302 0.4318)
							(mid 0.402042 0.402042)
							(end 0.4318 0.3302)
						)
						(arc
							(start 0.4318 -0.3302)
							(mid 0.402042 -0.402042)
							(end 0.3302 -0.4318)
						)
					)
					(width 0)
					(fill yes)
				)
			)
		)
	)
	(footprint ""
		(layer "F.Cu")
		(at 325.550022 -258.910074 -90)
		(property "Reference" "HDDSAS6"
			(at 0 0 270)
			(layer "F.SilkS")
			(hide yes)
			(effects
				(font
					(size 1.27 1.27)
				)
			)
		)
		(property "Value" "SKT-SAS15P-14P-45-GP"
			(at -20.7645 -8.9789 270)
			(unlocked yes)
			(layer "F.Fab")
			(hide yes)
			(effects
				(font
					(size 1.016 1.016)
					(thickness 0.1524)
				)
			)
		)
		(property "Device Type" "10120818-001C-TRLF"
			(at -20.7645 -10.5029 270)
			(unlocked yes)
			(layer "F.Fab")
			(hide yes)
			(effects
				(font
					(size 1.016 1.016)
					(thickness 0.1524)
				)
			)
		)
		(duplicate_pad_numbers_are_jumpers no)
		(fp_line
			(start 1.651 4.2926)
			(end 1.651 3.0099)
			(stroke
				(width 0.1524)
				(type default)
			)
			(layer "F.SilkS")
		)
		(fp_line
			(start 8.509 4.2926)
			(end 1.651 4.2926)
			(stroke
				(width 0.1524)
				(type default)
			)
			(layer "F.SilkS")
		)
		(fp_line
			(start -23.4188 3.0099)
			(end -23.4188 -3.2512)
			(stroke
				(width 0.1524)
				(type default)
			)
			(layer "F.SilkS")
		)
		(fp_line
			(start 1.651 3.0099)
			(end -23.4188 3.0099)
			(stroke
				(width 0.1524)
				(type default)
			)
			(layer "F.SilkS")
		)
		(fp_line
			(start 8.509 3.0099)
			(end 8.509 4.2926)
			(stroke
				(width 0.1524)
				(type default)
			)
			(layer "F.SilkS")
		)
		(fp_line
			(start 23.4188 3.0099)
			(end 8.509 3.0099)
			(stroke
				(width 0.1524)
				(type default)
			)
			(layer "F.SilkS")
		)
		(fp_line
			(start -23.4188 -3.2512)
			(end 23.4188 -3.2512)
			(stroke
				(width 0.1524)
				(type default)
			)
			(layer "F.SilkS")
		)
		(fp_line
			(start 23.4188 -3.2512)
			(end 23.4188 3.0099)
			(stroke
				(width 0.1524)
				(type default)
			)
			(layer "F.SilkS")
		)
		(fp_line
			(start 15.5067 -3.3401)
			(end 16.2687 -3.3401)
			(stroke
				(width 0.3302)
				(type default)
			)
			(layer "F.SilkS")
		)
		(fp_poly
			(pts
				(xy 15.868904 -3.230372) (xy 16.503904 -3.865372) (xy 15.233904 -3.865372)
			)
			(stroke
				(width 0)
				(type default)
			)
			(fill yes)
			(layer "F.SilkS")
		)
		(fp_poly
			(pts
				(xy -22.8727 -2.7559) (xy 22.8727 -2.7559) (xy 22.8727 2.7559) (xy 8.255 2.7559) (xy 8.255 3.5179)
				(xy 1.905 3.5179) (xy 1.905 2.7559) (xy -22.8727 2.7559)
			)
			(stroke
				(width 0)
				(type default)
			)
			(fill no)
			(layer "F.CrtYd")
		)
		(fp_poly
			(pts
				(xy 1.397 4.5466) (xy 1.397 3.2639) (xy -23.6728 3.2639) (xy -23.6728 -3.5052) (xy 23.6728 -3.5052)
				(xy 23.6728 -0.00635) (xy 22.8727 -0.00635) (xy 22.8727 -2.7559) (xy -22.8727 -2.7559) (xy -22.8727 2.7559)
				(xy 1.905 2.7559) (xy 1.905 3.5179) (xy 8.255 3.5179) (xy 8.255 2.7559) (xy 22.8727 2.7559) (xy 22.8727 0.00635)
				(xy 23.6728 0.00635) (xy 23.6728 3.2639) (xy 8.763 3.2639) (xy 8.763 4.5466)
			)
			(stroke
				(width 0)
				(type default)
			)
			(fill no)
			(layer "F.CrtYd")
		)
		(fp_poly
			(pts
				(xy 1.397 4.5466) (xy 1.397 3.2639) (xy -23.6728 3.2639) (xy -23.6728 -3.5052) (xy 23.6728 -3.5052)
				(xy 23.6728 3.2639) (xy 8.763 3.2639) (xy 8.763 4.5466)
			)
			(stroke
				(width 0)
				(type default)
			)
			(fill no)
			(layer "F.Fab")
		)
		(pad "" np_thru_hole circle
			(at -18.874994 0 270)
			(size 0.254 0.254)
			(drill 1.3462)
			(layers "*.Cu" "*.Mask")
			(clearance 0.9017)
			(thermal_gap 0.9017)
		)
		(pad "" np_thru_hole circle
			(at 18.874994 0 270)
			(size 0.254 0.254)
			(drill 0.9398)
			(layers "*.Cu" "*.Mask")
			(clearance 0.6985)
			(thermal_gap 0.6985)
		)
		(pad "G1" smd rect
			(at 21.874988 0 270)
			(size 2.5908 2.5908)
			(layers "F.Cu" "F.Mask" "F.Paste")
			(net "GND")
		)
		(pad "G2" smd rect
			(at -21.874988 0 270)
			(size 2.5908 2.5908)
			(layers "F.Cu" "F.Mask" "F.Paste")
			(net "GND")
		)
		(pad "P1" smd rect
			(at 1.905 -1.82499 270)
			(size 0.6096 2.3622)
			(layers "F.Cu" "F.Mask" "F.Paste")
			(net "Net_1599")
		)
		(pad "P2" smd rect
			(at 0.635 -1.82499 270)
			(size 0.6096 2.3622)
			(layers "F.Cu" "F.Mask" "F.Paste")
			(net "Net_1600")
		)
		(pad "P3" smd rect
			(at -0.635 -1.82499 270)
			(size 0.6096 2.3622)
			(layers "F.Cu" "F.Mask" "F.Paste")
			(net "Net_1601")
		)
		(pad "P4" smd rect
			(at -1.905 -1.82499 270)
			(size 0.6096 2.3622)
			(layers "F.Cu" "F.Mask" "F.Paste")
			(net "GND")
		)
		(pad "P5" smd rect
			(at -3.175 -1.82499 270)
			(size 0.6096 2.3622)
			(layers "F.Cu" "F.Mask" "F.Paste")
			(net "HDD_PRSNT_6")
		)
		(pad "P6" smd rect
			(at -4.445 -1.82499 270)
			(size 0.6096 2.3622)
			(layers "F.Cu" "F.Mask" "F.Paste")
			(net "GND")
		)
		(pad "P7" smd rect
			(at -5.715 -1.82499 270)
			(size 0.6096 2.3622)
			(layers "F.Cu" "F.Mask" "F.Paste")
			(net "5V_PRE_6")
		)
		(pad "P8" smd rect
			(at -6.985 -1.82499 270)
			(size 0.6096 2.3622)
			(layers "F.Cu" "F.Mask" "F.Paste")
			(net "P5V_HDD6")
		)
		(pad "P9" smd rect
			(at -8.255 -1.82499 270)
			(size 0.6096 2.3622)
			(layers "F.Cu" "F.Mask" "F.Paste")
			(net "P5V_HDD6")
		)
		(pad "P10" smd rect
			(at -9.525 -1.82499 270)
			(size 0.6096 2.3622)
			(layers "F.Cu" "F.Mask" "F.Paste")
			(net "GND")
		)
		(pad "P11" smd rect
			(at -10.795 -1.82499 270)
			(size 0.6096 2.3622)
			(layers "F.Cu" "F.Mask" "F.Paste")
			(net "ACT_HDD_6")
		)
		(pad "P12" smd rect
			(at -12.065 -1.82499 270)
			(size 0.6096 2.3622)
			(layers "F.Cu" "F.Mask" "F.Paste")
			(net "GND")
		)
		(pad "P13" smd rect
			(at -13.335 -1.82499 270)
			(size 0.6096 2.3622)
			(layers "F.Cu" "F.Mask" "F.Paste")
			(net "12V_PRE_6")
		)
		(pad "P14" smd rect
			(at -14.605 -1.82499 270)
			(size 0.6096 2.3622)
			(layers "F.Cu" "F.Mask" "F.Paste")
			(net "P12V_HDD6")
		)
		(pad "P15" smd rect
			(at -15.875 -1.82499 270)
			(size 0.6096 2.3622)
			(layers "F.Cu" "F.Mask" "F.Paste")
			(net "P12V_HDD6")
		)
		(pad "S1" smd rect
			(at 15.875 -1.82499 270)
			(size 0.6096 2.3622)
			(layers "F.Cu" "F.Mask" "F.Paste")
			(net "GND")
		)
		(pad "S2" smd rect
			(at 14.605 -1.82499 270)
			(size 0.6096 2.3622)
			(layers "F.Cu" "F.Mask" "F.Paste")
			(net "SAS_HDD_RX_P6")
		)
		(pad "S3" smd rect
			(at 13.335 -1.82499 270)
			(size 0.6096 2.3622)
			(layers "F.Cu" "F.Mask" "F.Paste")
			(net "SAS_HDD_RX_N6")
		)
		(pad "S4" smd rect
			(at 12.065 -1.82499 270)
			(size 0.6096 2.3622)
			(layers "F.Cu" "F.Mask" "F.Paste")
			(net "GND")
		)
		(pad "S5" smd rect
			(at 10.795 -1.82499 270)
			(size 0.6096 2.3622)
			(layers "F.Cu" "F.Mask" "F.Paste")
			(net "PHY_DRV_B_TO_SCC_B_6_DN")
		)
		(pad "S6" smd rect
			(at 9.525 -1.82499 270)
			(size 0.6096 2.3622)
			(layers "F.Cu" "F.Mask" "F.Paste")
			(net "PHY_DRV_B_TO_SCC_B_6_DP")
		)
		(pad "S7" smd rect
			(at 8.255 -1.82499 270)
			(size 0.6096 2.3622)
			(layers "F.Cu" "F.Mask" "F.Paste")
			(net "GND")
		)
		(pad "S8" smd rect
			(at 7.480046 2.845054 270)
			(size 0.508 2.3622)
			(layers "F.Cu" "F.Mask" "F.Paste")
			(net "GND")
		)
		(pad "S9" smd rect
			(at 6.679946 2.845054 270)
			(size 0.508 2.3622)
			(layers "F.Cu" "F.Mask" "F.Paste")
			(net "Net_464")
		)
		(pad "S10" smd rect
			(at 5.8801 2.845054 270)
			(size 0.508 2.3622)
			(layers "F.Cu" "F.Mask" "F.Paste")
			(net "Net_356")
		)
		(pad "S11" smd rect
			(at 5.08 2.845054 270)
			(size 0.508 2.3622)
			(layers "F.Cu" "F.Mask" "F.Paste")
			(net "GND")
		)
		(pad "S12" smd rect
			(at 4.2799 2.845054 270)
			(size 0.508 2.3622)
			(layers "F.Cu" "F.Mask" "F.Paste")
			(net "Net_392")
		)
		(pad "S13" smd rect
			(at 3.480054 2.845054 270)
			(size 0.508 2.3622)
			(layers "F.Cu" "F.Mask" "F.Paste")
			(net "Net_428")
		)
		(pad "S14" smd rect
			(at 2.679954 2.845054 270)
			(size 0.508 2.3622)
			(layers "F.Cu" "F.Mask" "F.Paste")
			(net "GND")
		)
		(zone
			(layer "F.Cu")
			(hatch none 0.5)
			(connect_pads
				(clearance 0)
			)
			(min_thickness 0.25)
			(keepout
				(tracks allowed)
				(vias not_allowed)
				(pads allowed)
				(copperpour not_allowed)
				(footprints allowed)
			)
			(placement
				(enabled no)
				(sheetname "")
			)
			(fill
				(thermal_gap 0.5)
				(thermal_bridge_width 0.5)
				(island_removal_mode 0)
			)
			(polygon
				(pts
					(xy 329.207622 -275.648674) (xy 322.133722 -275.648674) (xy 322.133722 -282.582874) (xy 323.238622 -282.582874)
					(xy 323.238622 -278.468074) (xy 327.861422 -278.468074) (xy 327.861422 -282.582874) (xy 329.207622 -282.582874)
				)
			)
		)
		(zone
			(layer "F.Cu")
			(hatch none 0.5)
			(connect_pads
				(clearance 0)
			)
			(min_thickness 0.25)
			(keepout
				(tracks not_allowed)
				(vias allowed)
				(pads allowed)
				(copperpour not_allowed)
				(footprints allowed)
			)
			(placement
				(enabled no)
				(sheetname "")
			)
			(fill
				(thermal_gap 0.5)
				(thermal_bridge_width 0.5)
				(island_removal_mode 0)
			)
			(polygon
				(pts
					(xy 329.207622 -275.648674) (xy 322.133722 -275.648674) (xy 322.133722 -282.582874) (xy 323.238622 -282.582874)
					(xy 323.238622 -278.468074) (xy 327.861422 -278.468074) (xy 327.861422 -282.582874) (xy 329.207622 -282.582874)
				)
			)
		)
		(zone
			(layer "F.Cu")
			(hatch none 0.5)
			(connect_pads
				(clearance 0)
			)
			(min_thickness 0.25)
			(keepout
				(tracks not_allowed)
				(vias allowed)
				(pads allowed)
				(copperpour not_allowed)
				(footprints allowed)
			)
			(placement
				(enabled no)
				(sheetname "")
			)
			(fill
				(thermal_gap 0.5)
				(thermal_bridge_width 0.5)
				(island_removal_mode 0)
			)
			(polygon
				(pts
					(xy 329.207622 -242.171474) (xy 322.133722 -242.171474) (xy 322.133722 -235.237274) (xy 323.238622 -235.237274)
					(xy 323.238622 -239.352074) (xy 327.861422 -239.352074) (xy 327.861422 -235.237274) (xy 329.207622 -235.237274)
				)
			)
		)
		(zone
			(layer "F.Cu")
			(hatch none 0.5)
			(connect_pads
				(clearance 0)
			)
			(min_thickness 0.25)
			(keepout
				(tracks allowed)
				(vias not_allowed)
				(pads allowed)
				(copperpour not_allowed)
				(footprints allowed)
			)
			(placement
				(enabled no)
				(sheetname "")
			)
			(fill
				(thermal_gap 0.5)
				(thermal_bridge_width 0.5)
				(island_removal_mode 0)
			)
			(polygon
				(pts
					(xy 329.207622 -242.171474) (xy 322.133722 -242.171474) (xy 322.133722 -235.237274) (xy 323.238622 -235.237274)
					(xy 323.238622 -239.352074) (xy 327.861422 -239.352074) (xy 327.861422 -235.237274) (xy 329.207622 -235.237274)
				)
			)
		)
		(zone
			(layers "F.Cu" "B.Cu" "In1.Cu" "In2.Cu" "In3.Cu" "In4.Cu" "In5.Cu" "In6.Cu")
			(hatch none 0.5)
			(connect_pads
				(clearance 0)
			)
			(min_thickness 0.25)
			(keepout
				(tracks not_allowed)
				(vias allowed)
				(pads allowed)
				(copperpour not_allowed)
				(footprints allowed)
			)
			(placement
				(enabled no)
				(sheetname "")
			)
			(fill
				(thermal_gap 0.5)
				(thermal_bridge_width 0.5)
				(island_removal_mode 0)
			)
			(polygon
				(pts
					(arc
						(start 326.324722 -240.03508)
						(mid 324.775322 -240.03508)
						(end 326.324722 -240.03508)
					)
				)
			)
		)
		(zone
			(layers "F.Cu" "B.Cu" "In1.Cu" "In2.Cu" "In3.Cu" "In4.Cu" "In5.Cu" "In6.Cu")
			(hatch none 0.5)
			(connect_pads
				(clearance 0)
			)
			(min_thickness 0.25)
			(keepout
				(tracks not_allowed)
				(vias allowed)
				(pads allowed)
				(copperpour not_allowed)
				(footprints allowed)
			)
			(placement
				(enabled no)
				(sheetname "")
			)
			(fill
				(thermal_gap 0.5)
				(thermal_bridge_width 0.5)
				(island_removal_mode 0)
			)
			(polygon
				(pts
					(arc
						(start 326.527922 -277.785068)
						(mid 324.572122 -277.785068)
						(end 326.527922 -277.785068)
					)
				)
			)
		)
	)
	(footprint ""
		(layer "F.Cu")
		(at 467.5124 -5.3594 -90)
		(property "Reference" "R134"
			(at 0 0 270)
			(layer "F.SilkS")
			(hide yes)
			(effects
				(font
					(size 1.27 1.27)
				)
			)
		)
		(property "Value" "4K7R2F-GP"
			(at 0.064008 -3.993896 270)
			(unlocked yes)
			(layer "F.Fab")
			(hide yes)
			(effects
				(font
					(size 1.016 1.016)
					(thickness 0.1524)
				)
			)
		)
		(property "Device Type" "R402H16"
			(at 0.064008 -5.517896 270)
			(unlocked yes)
			(layer "F.Fab")
			(hide yes)
			(effects
				(font
					(size 1.016 1.016)
					(thickness 0.1524)
				)
			)
		)
		(duplicate_pad_numbers_are_jumpers no)
		(fp_line
			(start -0.508 -0.9398)
			(end -0.508 0.9398)
			(stroke
				(width 0.1524)
				(type default)
			)
			(layer "F.SilkS")
		)
		(fp_line
			(start 0.508 -0.9398)
			(end -0.508 -0.9398)
			(stroke
				(width 0.1524)
				(type default)
			)
			(layer "F.SilkS")
		)
		(fp_rect
			(start -0.508 0.9398)
			(end 0.508 -0.9398)
			(stroke
				(width 0)
				(type default)
			)
			(fill no)
			(layer "F.CrtYd")
		)
		(fp_rect
			(start -0.508 0.9398)
			(end 0.508 -0.9398)
			(stroke
				(width 0)
				(type default)
			)
			(fill no)
			(layer "F.Fab")
		)
		(pad "1" smd custom
			(at 0 -0.4445 270)
			(size 0.1397 0.1397)
			(layers "F.Cu" "F.Mask" "F.Paste")
			(net "P3V3_STBY_B")
			(options
				(clearance outline)
				(anchor circle)
			)
			(primitives
				(gr_poly
					(pts
						(arc
							(start -0.1778 -0.2794)
							(mid -0.249642 -0.249642)
							(end -0.2794 -0.1778)
						)
						(arc
							(start -0.2794 0.1778)
							(mid -0.249642 0.249642)
							(end -0.1778 0.2794)
						)
						(arc
							(start 0.1778 0.2794)
							(mid 0.249642 0.249642)
							(end 0.2794 0.1778)
						)
						(arc
							(start 0.2794 -0.1778)
							(mid 0.249642 -0.249642)
							(end 0.1778 -0.2794)
						)
					)
					(width 0)
					(fill yes)
				)
			)
		)
		(pad "2" smd custom
			(at 0 0.4445 270)
			(size 0.1397 0.1397)
			(layers "F.Cu" "F.Mask" "F.Paste")
			(net "TEMP2_A2")
			(options
				(clearance outline)
				(anchor circle)
			)
			(primitives
				(gr_poly
					(pts
						(arc
							(start -0.1778 -0.2794)
							(mid -0.249642 -0.249642)
							(end -0.2794 -0.1778)
						)
						(arc
							(start -0.2794 0.1778)
							(mid -0.249642 0.249642)
							(end -0.1778 0.2794)
						)
						(arc
							(start 0.1778 0.2794)
							(mid 0.249642 0.249642)
							(end 0.2794 0.1778)
						)
						(arc
							(start 0.2794 -0.1778)
							(mid 0.249642 -0.249642)
							(end 0.1778 -0.2794)
						)
					)
					(width 0)
					(fill yes)
				)
			)
		)
	)
	(footprint ""
		(layer "F.Cu")
		(at 238.633 -215.265)
		(property "Reference" "R88"
			(at 0 0 0)
			(layer "F.SilkS")
			(hide yes)
			(effects
				(font
					(size 1.27 1.27)
				)
			)
		)
		(property "Value" "0R2J-2-GP"
			(at 0.064008 -3.993896 0)
			(unlocked yes)
			(layer "F.Fab")
			(hide yes)
			(effects
				(font
					(size 1.016 1.016)
					(thickness 0.1524)
				)
			)
		)
		(property "Device Type" "R402H16"
			(at 0.064008 -5.517896 0)
			(unlocked yes)
			(layer "F.Fab")
			(hide yes)
			(effects
				(font
					(size 1.016 1.016)
					(thickness 0.1524)
				)
			)
		)
		(duplicate_pad_numbers_are_jumpers no)
		(fp_line
			(start -0.508 -0.9398)
			(end -0.508 0.9398)
			(stroke
				(width 0.1524)
				(type default)
			)
			(layer "F.SilkS")
		)
		(fp_line
			(start 0.508 -0.9398)
			(end -0.508 -0.9398)
			(stroke
				(width 0.1524)
				(type default)
			)
			(layer "F.SilkS")
		)
		(fp_rect
			(start -0.508 0.9398)
			(end 0.508 -0.9398)
			(stroke
				(width 0)
				(type default)
			)
			(fill no)
			(layer "F.CrtYd")
		)
		(fp_rect
			(start -0.508 0.9398)
			(end 0.508 -0.9398)
			(stroke
				(width 0)
				(type default)
			)
			(fill no)
			(layer "F.Fab")
		)
		(pad "1" smd custom
			(at 0 -0.4445)
			(size 0.1397 0.1397)
			(layers "F.Cu" "F.Mask" "F.Paste")
			(net "IO_EXP3_SDA")
			(options
				(clearance outline)
				(anchor circle)
			)
			(primitives
				(gr_poly
					(pts
						(arc
							(start -0.1778 -0.2794)
							(mid -0.249642 -0.249642)
							(end -0.2794 -0.1778)
						)
						(arc
							(start -0.2794 0.1778)
							(mid -0.249642 0.249642)
							(end -0.1778 0.2794)
						)
						(arc
							(start 0.1778 0.2794)
							(mid 0.249642 0.249642)
							(end 0.2794 0.1778)
						)
						(arc
							(start 0.2794 -0.1778)
							(mid 0.249642 -0.249642)
							(end 0.1778 -0.2794)
						)
					)
					(width 0)
					(fill yes)
				)
			)
		)
		(pad "2" smd custom
			(at 0 0.4445)
			(size 0.1397 0.1397)
			(layers "F.Cu" "F.Mask" "F.Paste")
			(net "I2C_DRIVE_B_PWR_SDA")
			(options
				(clearance outline)
				(anchor circle)
			)
			(primitives
				(gr_poly
					(pts
						(arc
							(start -0.1778 -0.2794)
							(mid -0.249642 -0.249642)
							(end -0.2794 -0.1778)
						)
						(arc
							(start -0.2794 0.1778)
							(mid -0.249642 0.249642)
							(end -0.1778 0.2794)
						)
						(arc
							(start 0.1778 0.2794)
							(mid 0.249642 0.249642)
							(end 0.2794 0.1778)
						)
						(arc
							(start 0.2794 -0.1778)
							(mid 0.249642 -0.249642)
							(end 0.1778 -0.2794)
						)
					)
					(width 0)
					(fill yes)
				)
			)
		)
	)
	(footprint ""
		(layer "F.Cu")
		(at 185.950098 -143.91005 -90)
		(property "Reference" "HDDSAS17"
			(at 0 0 270)
			(layer "F.SilkS")
			(hide yes)
			(effects
				(font
					(size 1.27 1.27)
				)
			)
		)
		(property "Value" "SKT-SAS15P-14P-45-GP"
			(at -20.7645 -8.9789 270)
			(unlocked yes)
			(layer "F.Fab")
			(hide yes)
			(effects
				(font
					(size 1.016 1.016)
					(thickness 0.1524)
				)
			)
		)
		(property "Device Type" "10120818-001C-TRLF"
			(at -20.7645 -10.5029 270)
			(unlocked yes)
			(layer "F.Fab")
			(hide yes)
			(effects
				(font
					(size 1.016 1.016)
					(thickness 0.1524)
				)
			)
		)
		(duplicate_pad_numbers_are_jumpers no)
		(fp_line
			(start 1.651 4.2926)
			(end 1.651 3.0099)
			(stroke
				(width 0.1524)
				(type default)
			)
			(layer "F.SilkS")
		)
		(fp_line
			(start 8.509 4.2926)
			(end 1.651 4.2926)
			(stroke
				(width 0.1524)
				(type default)
			)
			(layer "F.SilkS")
		)
		(fp_line
			(start -23.4188 3.0099)
			(end -23.4188 -3.2512)
			(stroke
				(width 0.1524)
				(type default)
			)
			(layer "F.SilkS")
		)
		(fp_line
			(start 1.651 3.0099)
			(end -23.4188 3.0099)
			(stroke
				(width 0.1524)
				(type default)
			)
			(layer "F.SilkS")
		)
		(fp_line
			(start 8.509 3.0099)
			(end 8.509 4.2926)
			(stroke
				(width 0.1524)
				(type default)
			)
			(layer "F.SilkS")
		)
		(fp_line
			(start 23.4188 3.0099)
			(end 8.509 3.0099)
			(stroke
				(width 0.1524)
				(type default)
			)
			(layer "F.SilkS")
		)
		(fp_line
			(start -23.4188 -3.2512)
			(end 23.4188 -3.2512)
			(stroke
				(width 0.1524)
				(type default)
			)
			(layer "F.SilkS")
		)
		(fp_line
			(start 23.4188 -3.2512)
			(end 23.4188 3.0099)
			(stroke
				(width 0.1524)
				(type default)
			)
			(layer "F.SilkS")
		)
		(fp_line
			(start 15.5067 -3.3401)
			(end 16.2687 -3.3401)
			(stroke
				(width 0.3302)
				(type default)
			)
			(layer "F.SilkS")
		)
		(fp_poly
			(pts
				(xy 15.868904 -3.230372) (xy 16.503904 -3.865372) (xy 15.233904 -3.865372)
			)
			(stroke
				(width 0)
				(type default)
			)
			(fill yes)
			(layer "F.SilkS")
		)
		(fp_poly
			(pts
				(xy -22.8727 -2.7559) (xy 22.8727 -2.7559) (xy 22.8727 2.7559) (xy 8.255 2.7559) (xy 8.255 3.5179)
				(xy 1.905 3.5179) (xy 1.905 2.7559) (xy -22.8727 2.7559)
			)
			(stroke
				(width 0)
				(type default)
			)
			(fill no)
			(layer "F.CrtYd")
		)
		(fp_poly
			(pts
				(xy 1.397 4.5466) (xy 1.397 3.2639) (xy -23.6728 3.2639) (xy -23.6728 -3.5052) (xy 23.6728 -3.5052)
				(xy 23.6728 -0.00635) (xy 22.8727 -0.00635) (xy 22.8727 -2.7559) (xy -22.8727 -2.7559) (xy -22.8727 2.7559)
				(xy 1.905 2.7559) (xy 1.905 3.5179) (xy 8.255 3.5179) (xy 8.255 2.7559) (xy 22.8727 2.7559) (xy 22.8727 0.00635)
				(xy 23.6728 0.00635) (xy 23.6728 3.2639) (xy 8.763 3.2639) (xy 8.763 4.5466)
			)
			(stroke
				(width 0)
				(type default)
			)
			(fill no)
			(layer "F.CrtYd")
		)
		(fp_poly
			(pts
				(xy 1.397 4.5466) (xy 1.397 3.2639) (xy -23.6728 3.2639) (xy -23.6728 -3.5052) (xy 23.6728 -3.5052)
				(xy 23.6728 3.2639) (xy 8.763 3.2639) (xy 8.763 4.5466)
			)
			(stroke
				(width 0)
				(type default)
			)
			(fill no)
			(layer "F.Fab")
		)
		(pad "" np_thru_hole circle
			(at -18.874994 0 270)
			(size 0.254 0.254)
			(drill 1.3462)
			(layers "*.Cu" "*.Mask")
			(clearance 0.9017)
			(thermal_gap 0.9017)
		)
		(pad "" np_thru_hole circle
			(at 18.874994 0 270)
			(size 0.254 0.254)
			(drill 0.9398)
			(layers "*.Cu" "*.Mask")
			(clearance 0.6985)
			(thermal_gap 0.6985)
		)
		(pad "G1" smd rect
			(at 21.874988 0 270)
			(size 2.5908 2.5908)
			(layers "F.Cu" "F.Mask" "F.Paste")
			(net "GND")
		)
		(pad "G2" smd rect
			(at -21.874988 0 270)
			(size 2.5908 2.5908)
			(layers "F.Cu" "F.Mask" "F.Paste")
			(net "GND")
		)
		(pad "P1" smd rect
			(at 1.905 -1.82499 270)
			(size 0.6096 2.3622)
			(layers "F.Cu" "F.Mask" "F.Paste")
			(net "Net_1719")
		)
		(pad "P2" smd rect
			(at 0.635 -1.82499 270)
			(size 0.6096 2.3622)
			(layers "F.Cu" "F.Mask" "F.Paste")
			(net "Net_1720")
		)
		(pad "P3" smd rect
			(at -0.635 -1.82499 270)
			(size 0.6096 2.3622)
			(layers "F.Cu" "F.Mask" "F.Paste")
			(net "Net_1721")
		)
		(pad "P4" smd rect
			(at -1.905 -1.82499 270)
			(size 0.6096 2.3622)
			(layers "F.Cu" "F.Mask" "F.Paste")
			(net "GND")
		)
		(pad "P5" smd rect
			(at -3.175 -1.82499 270)
			(size 0.6096 2.3622)
			(layers "F.Cu" "F.Mask" "F.Paste")
			(net "HDD_PRSNT_17")
		)
		(pad "P6" smd rect
			(at -4.445 -1.82499 270)
			(size 0.6096 2.3622)
			(layers "F.Cu" "F.Mask" "F.Paste")
			(net "GND")
		)
		(pad "P7" smd rect
			(at -5.715 -1.82499 270)
			(size 0.6096 2.3622)
			(layers "F.Cu" "F.Mask" "F.Paste")
			(net "5V_PRE_17")
		)
		(pad "P8" smd rect
			(at -6.985 -1.82499 270)
			(size 0.6096 2.3622)
			(layers "F.Cu" "F.Mask" "F.Paste")
			(net "P5V_HDD17")
		)
		(pad "P9" smd rect
			(at -8.255 -1.82499 270)
			(size 0.6096 2.3622)
			(layers "F.Cu" "F.Mask" "F.Paste")
			(net "P5V_HDD17")
		)
		(pad "P10" smd rect
			(at -9.525 -1.82499 270)
			(size 0.6096 2.3622)
			(layers "F.Cu" "F.Mask" "F.Paste")
			(net "GND")
		)
		(pad "P11" smd rect
			(at -10.795 -1.82499 270)
			(size 0.6096 2.3622)
			(layers "F.Cu" "F.Mask" "F.Paste")
			(net "ACT_HDD_17")
		)
		(pad "P12" smd rect
			(at -12.065 -1.82499 270)
			(size 0.6096 2.3622)
			(layers "F.Cu" "F.Mask" "F.Paste")
			(net "GND")
		)
		(pad "P13" smd rect
			(at -13.335 -1.82499 270)
			(size 0.6096 2.3622)
			(layers "F.Cu" "F.Mask" "F.Paste")
			(net "12V_PRE_17")
		)
		(pad "P14" smd rect
			(at -14.605 -1.82499 270)
			(size 0.6096 2.3622)
			(layers "F.Cu" "F.Mask" "F.Paste")
			(net "P12V_HDD17")
		)
		(pad "P15" smd rect
			(at -15.875 -1.82499 270)
			(size 0.6096 2.3622)
			(layers "F.Cu" "F.Mask" "F.Paste")
			(net "P12V_HDD17")
		)
		(pad "S1" smd rect
			(at 15.875 -1.82499 270)
			(size 0.6096 2.3622)
			(layers "F.Cu" "F.Mask" "F.Paste")
			(net "GND")
		)
		(pad "S2" smd rect
			(at 14.605 -1.82499 270)
			(size 0.6096 2.3622)
			(layers "F.Cu" "F.Mask" "F.Paste")
			(net "SAS_HDD_RX_P17")
		)
		(pad "S3" smd rect
			(at 13.335 -1.82499 270)
			(size 0.6096 2.3622)
			(layers "F.Cu" "F.Mask" "F.Paste")
			(net "SAS_HDD_RX_N17")
		)
		(pad "S4" smd rect
			(at 12.065 -1.82499 270)
			(size 0.6096 2.3622)
			(layers "F.Cu" "F.Mask" "F.Paste")
			(net "GND")
		)
		(pad "S5" smd rect
			(at 10.795 -1.82499 270)
			(size 0.6096 2.3622)
			(layers "F.Cu" "F.Mask" "F.Paste")
			(net "PHY_DRV_B_TO_SCC_B_17_DN")
		)
		(pad "S6" smd rect
			(at 9.525 -1.82499 270)
			(size 0.6096 2.3622)
			(layers "F.Cu" "F.Mask" "F.Paste")
			(net "PHY_DRV_B_TO_SCC_B_17_DP")
		)
		(pad "S7" smd rect
			(at 8.255 -1.82499 270)
			(size 0.6096 2.3622)
			(layers "F.Cu" "F.Mask" "F.Paste")
			(net "GND")
		)
		(pad "S8" smd rect
			(at 7.480046 2.845054 270)
			(size 0.508 2.3622)
			(layers "F.Cu" "F.Mask" "F.Paste")
			(net "GND")
		)
		(pad "S9" smd rect
			(at 6.679946 2.845054 270)
			(size 0.508 2.3622)
			(layers "F.Cu" "F.Mask" "F.Paste")
			(net "Net_440")
		)
		(pad "S10" smd rect
			(at 5.8801 2.845054 270)
			(size 0.508 2.3622)
			(layers "F.Cu" "F.Mask" "F.Paste")
			(net "Net_332")
		)
		(pad "S11" smd rect
			(at 5.08 2.845054 270)
			(size 0.508 2.3622)
			(layers "F.Cu" "F.Mask" "F.Paste")
			(net "GND")
		)
		(pad "S12" smd rect
			(at 4.2799 2.845054 270)
			(size 0.508 2.3622)
			(layers "F.Cu" "F.Mask" "F.Paste")
			(net "Net_368")
		)
		(pad "S13" smd rect
			(at 3.480054 2.845054 270)
			(size 0.508 2.3622)
			(layers "F.Cu" "F.Mask" "F.Paste")
			(net "Net_404")
		)
		(pad "S14" smd rect
			(at 2.679954 2.845054 270)
			(size 0.508 2.3622)
			(layers "F.Cu" "F.Mask" "F.Paste")
			(net "GND")
		)
		(zone
			(layer "F.Cu")
			(hatch none 0.5)
			(connect_pads
				(clearance 0)
			)
			(min_thickness 0.25)
			(keepout
				(tracks not_allowed)
				(vias allowed)
				(pads allowed)
				(copperpour not_allowed)
				(footprints allowed)
			)
			(placement
				(enabled no)
				(sheetname "")
			)
			(fill
				(thermal_gap 0.5)
				(thermal_bridge_width 0.5)
				(island_removal_mode 0)
			)
			(polygon
				(pts
					(xy 189.607698 -160.64865) (xy 182.533798 -160.64865) (xy 182.533798 -167.58285) (xy 183.638698 -167.58285)
					(xy 183.638698 -163.46805) (xy 188.261498 -163.46805) (xy 188.261498 -167.58285) (xy 189.607698 -167.58285)
				)
			)
		)
		(zone
			(layer "F.Cu")
			(hatch none 0.5)
			(connect_pads
				(clearance 0)
			)
			(min_thickness 0.25)
			(keepout
				(tracks allowed)
				(vias not_allowed)
				(pads allowed)
				(copperpour not_allowed)
				(footprints allowed)
			)
			(placement
				(enabled no)
				(sheetname "")
			)
			(fill
				(thermal_gap 0.5)
				(thermal_bridge_width 0.5)
				(island_removal_mode 0)
			)
			(polygon
				(pts
					(xy 189.607698 -160.64865) (xy 182.533798 -160.64865) (xy 182.533798 -167.58285) (xy 183.638698 -167.58285)
					(xy 183.638698 -163.46805) (xy 188.261498 -163.46805) (xy 188.261498 -167.58285) (xy 189.607698 -167.58285)
				)
			)
		)
		(zone
			(layer "F.Cu")
			(hatch none 0.5)
			(connect_pads
				(clearance 0)
			)
			(min_thickness 0.25)
			(keepout
				(tracks allowed)
				(vias not_allowed)
				(pads allowed)
				(copperpour not_allowed)
				(footprints allowed)
			)
			(placement
				(enabled no)
				(sheetname "")
			)
			(fill
				(thermal_gap 0.5)
				(thermal_bridge_width 0.5)
				(island_removal_mode 0)
			)
			(polygon
				(pts
					(xy 189.607698 -127.17145) (xy 182.533798 -127.17145) (xy 182.533798 -120.23725) (xy 183.638698 -120.23725)
					(xy 183.638698 -124.35205) (xy 188.261498 -124.35205) (xy 188.261498 -120.23725) (xy 189.607698 -120.23725)
				)
			)
		)
		(zone
			(layer "F.Cu")
			(hatch none 0.5)
			(connect_pads
				(clearance 0)
			)
			(min_thickness 0.25)
			(keepout
				(tracks not_allowed)
				(vias allowed)
				(pads allowed)
				(copperpour not_allowed)
				(footprints allowed)
			)
			(placement
				(enabled no)
				(sheetname "")
			)
			(fill
				(thermal_gap 0.5)
				(thermal_bridge_width 0.5)
				(island_removal_mode 0)
			)
			(polygon
				(pts
					(xy 189.607698 -127.17145) (xy 182.533798 -127.17145) (xy 182.533798 -120.23725) (xy 183.638698 -120.23725)
					(xy 183.638698 -124.35205) (xy 188.261498 -124.35205) (xy 188.261498 -120.23725) (xy 189.607698 -120.23725)
				)
			)
		)
		(zone
			(layers "F.Cu" "B.Cu" "In1.Cu" "In2.Cu" "In3.Cu" "In4.Cu" "In5.Cu" "In6.Cu")
			(hatch none 0.5)
			(connect_pads
				(clearance 0)
			)
			(min_thickness 0.25)
			(keepout
				(tracks not_allowed)
				(vias allowed)
				(pads allowed)
				(copperpour not_allowed)
				(footprints allowed)
			)
			(placement
				(enabled no)
				(sheetname "")
			)
			(fill
				(thermal_gap 0.5)
				(thermal_bridge_width 0.5)
				(island_removal_mode 0)
			)
			(polygon
				(pts
					(arc
						(start 186.724798 -125.035056)
						(mid 185.175398 -125.035056)
						(end 186.724798 -125.035056)
					)
				)
			)
		)
		(zone
			(layers "F.Cu" "B.Cu" "In1.Cu" "In2.Cu" "In3.Cu" "In4.Cu" "In5.Cu" "In6.Cu")
			(hatch none 0.5)
			(connect_pads
				(clearance 0)
			)
			(min_thickness 0.25)
			(keepout
				(tracks not_allowed)
				(vias allowed)
				(pads allowed)
				(copperpour not_allowed)
				(footprints allowed)
			)
			(placement
				(enabled no)
				(sheetname "")
			)
			(fill
				(thermal_gap 0.5)
				(thermal_bridge_width 0.5)
				(island_removal_mode 0)
			)
			(polygon
				(pts
					(arc
						(start 186.927998 -162.785044)
						(mid 184.972198 -162.785044)
						(end 186.927998 -162.785044)
					)
				)
			)
		)
	)
	(footprint ""
		(layer "F.Cu")
		(at 398.145 -13.335 180)
		(property "Reference" "R823"
			(at 0 0 180)
			(layer "F.SilkS")
			(hide yes)
			(effects
				(font
					(size 1.27 1.27)
				)
			)
		)
		(property "Value" "0R2J-2-GP"
			(at 0.064008 -3.993896 180)
			(unlocked yes)
			(layer "F.Fab")
			(hide yes)
			(effects
				(font
					(size 1.016 1.016)
					(thickness 0.1524)
				)
			)
		)
		(property "Device Type" "R402H16"
			(at 0.064008 -5.517896 180)
			(unlocked yes)
			(layer "F.Fab")
			(hide yes)
			(effects
				(font
					(size 1.016 1.016)
					(thickness 0.1524)
				)
			)
		)
		(duplicate_pad_numbers_are_jumpers no)
		(fp_line
			(start 0.508 -0.9398)
			(end -0.508 -0.9398)
			(stroke
				(width 0.1524)
				(type default)
			)
			(layer "F.SilkS")
		)
		(fp_line
			(start -0.508 -0.9398)
			(end -0.508 0.9398)
			(stroke
				(width 0.1524)
				(type default)
			)
			(layer "F.SilkS")
		)
		(fp_rect
			(start -0.508 0.9398)
			(end 0.508 -0.9398)
			(stroke
				(width 0)
				(type default)
			)
			(fill no)
			(layer "F.CrtYd")
		)
		(fp_rect
			(start -0.508 0.9398)
			(end 0.508 -0.9398)
			(stroke
				(width 0)
				(type default)
			)
			(fill no)
			(layer "F.Fab")
		)
		(pad "1" smd custom
			(at 0 -0.4445 180)
			(size 0.1397 0.1397)
			(layers "F.Cu" "F.Mask" "F.Paste")
			(net "SW_HDD_G32")
			(options
				(clearance outline)
				(anchor circle)
			)
			(primitives
				(gr_poly
					(pts
						(arc
							(start -0.1778 -0.2794)
							(mid -0.249642 -0.249642)
							(end -0.2794 -0.1778)
						)
						(arc
							(start -0.2794 0.1778)
							(mid -0.249642 0.249642)
							(end -0.1778 0.2794)
						)
						(arc
							(start 0.1778 0.2794)
							(mid 0.249642 0.249642)
							(end 0.2794 0.1778)
						)
						(arc
							(start 0.2794 -0.1778)
							(mid 0.249642 -0.249642)
							(end 0.1778 -0.2794)
						)
					)
					(width 0)
					(fill yes)
				)
			)
		)
		(pad "2" smd custom
			(at 0 0.4445 180)
			(size 0.1397 0.1397)
			(layers "F.Cu" "F.Mask" "F.Paste")
			(net "SW_HDD_R32")
			(options
				(clearance outline)
				(anchor circle)
			)
			(primitives
				(gr_poly
					(pts
						(arc
							(start -0.1778 -0.2794)
							(mid -0.249642 -0.249642)
							(end -0.2794 -0.1778)
						)
						(arc
							(start -0.2794 0.1778)
							(mid -0.249642 0.249642)
							(end -0.1778 0.2794)
						)
						(arc
							(start 0.1778 0.2794)
							(mid 0.249642 0.249642)
							(end 0.2794 0.1778)
						)
						(arc
							(start 0.2794 -0.1778)
							(mid 0.249642 -0.249642)
							(end 0.1778 -0.2794)
						)
					)
					(width 0)
					(fill yes)
				)
			)
		)
	)
	(footprint ""
		(layer "F.Cu")
		(at 459.8162 -155.575 -90)
		(property "Reference" "R577"
			(at 0 0 270)
			(layer "F.SilkS")
			(hide yes)
			(effects
				(font
					(size 1.27 1.27)
				)
			)
		)
		(property "Value" "2R6F-GP"
			(at -0.0508 -4.8514 270)
			(unlocked yes)
			(layer "F.Fab")
			(hide yes)
			(effects
				(font
					(size 1.016 1.016)
					(thickness 0.1524)
				)
			)
		)
		(property "Device Type" "R1206H26"
			(at 0 -6.3754 270)
			(unlocked yes)
			(layer "F.Fab")
			(hide yes)
			(effects
				(font
					(size 1.016 1.016)
					(thickness 0.1524)
				)
			)
		)
		(duplicate_pad_numbers_are_jumpers no)
		(fp_line
			(start -1.016 2.2352)
			(end -1.016 -2.2352)
			(stroke
				(width 0.1524)
				(type default)
			)
			(layer "F.SilkS")
		)
		(fp_line
			(start 1.016 2.2352)
			(end -1.016 2.2352)
			(stroke
				(width 0.1524)
				(type default)
			)
			(layer "F.SilkS")
		)
		(fp_line
			(start -1.016 -2.2352)
			(end 1.016 -2.2352)
			(stroke
				(width 0.1524)
				(type default)
			)
			(layer "F.SilkS")
		)
		(fp_line
			(start 1.016 -2.2352)
			(end 1.016 2.2352)
			(stroke
				(width 0.1524)
				(type default)
			)
			(layer "F.SilkS")
		)
		(fp_rect
			(start -1.0922 2.3114)
			(end 1.0922 -2.3114)
			(stroke
				(width 0)
				(type default)
			)
			(fill no)
			(layer "F.CrtYd")
		)
		(fp_poly
			(pts
				(xy -1.0922 -2.3114) (xy 1.0922 -2.3114) (xy 1.0922 2.3114) (xy -1.0922 2.3114)
			)
			(stroke
				(width 0)
				(type default)
			)
			(fill no)
			(layer "F.Fab")
		)
		(pad "1" smd rect
			(at 0 -1.397 270)
			(size 1.651 1.27)
			(layers "F.Cu" "F.Mask" "F.Paste")
			(net "P12V_HDD22")
		)
		(pad "2" smd rect
			(at 0 1.397 270)
			(size 1.651 1.27)
			(layers "F.Cu" "F.Mask" "F.Paste")
			(net "12V_PRE_22")
		)
	)
	(footprint ""
		(layer "F.Cu")
		(at 15.24 -133.096 180)
		(property "Reference" "R362"
			(at 0 0 180)
			(layer "F.SilkS")
			(hide yes)
			(effects
				(font
					(size 1.27 1.27)
				)
			)
		)
		(property "Value" "200KR2F-L-GP"
			(at 0.064008 -3.993896 180)
			(unlocked yes)
			(layer "F.Fab")
			(hide yes)
			(effects
				(font
					(size 1.016 1.016)
					(thickness 0.1524)
				)
			)
		)
		(property "Device Type" "R402H16"
			(at 0.064008 -5.517896 180)
			(unlocked yes)
			(layer "F.Fab")
			(hide yes)
			(effects
				(font
					(size 1.016 1.016)
					(thickness 0.1524)
				)
			)
		)
		(duplicate_pad_numbers_are_jumpers no)
		(fp_line
			(start 0.508 -0.9398)
			(end -0.508 -0.9398)
			(stroke
				(width 0.1524)
				(type default)
			)
			(layer "F.SilkS")
		)
		(fp_line
			(start -0.508 -0.9398)
			(end -0.508 0.9398)
			(stroke
				(width 0.1524)
				(type default)
			)
			(layer "F.SilkS")
		)
		(fp_rect
			(start -0.508 0.9398)
			(end 0.508 -0.9398)
			(stroke
				(width 0)
				(type default)
			)
			(fill no)
			(layer "F.CrtYd")
		)
		(fp_rect
			(start -0.508 0.9398)
			(end 0.508 -0.9398)
			(stroke
				(width 0)
				(type default)
			)
			(fill no)
			(layer "F.Fab")
		)
		(pad "1" smd custom
			(at 0 -0.4445 180)
			(size 0.1397 0.1397)
			(layers "F.Cu" "F.Mask" "F.Paste")
			(net "SW_HDD_R12")
			(options
				(clearance outline)
				(anchor circle)
			)
			(primitives
				(gr_poly
					(pts
						(arc
							(start -0.1778 -0.2794)
							(mid -0.249642 -0.249642)
							(end -0.2794 -0.1778)
						)
						(arc
							(start -0.2794 0.1778)
							(mid -0.249642 0.249642)
							(end -0.1778 0.2794)
						)
						(arc
							(start 0.1778 0.2794)
							(mid 0.249642 0.249642)
							(end 0.2794 0.1778)
						)
						(arc
							(start 0.2794 -0.1778)
							(mid 0.249642 -0.249642)
							(end 0.1778 -0.2794)
						)
					)
					(width 0)
					(fill yes)
				)
			)
		)
		(pad "2" smd custom
			(at 0 0.4445 180)
			(size 0.1397 0.1397)
			(layers "F.Cu" "F.Mask" "F.Paste")
			(net "SW_HDD_N12")
			(options
				(clearance outline)
				(anchor circle)
			)
			(primitives
				(gr_poly
					(pts
						(arc
							(start -0.1778 -0.2794)
							(mid -0.249642 -0.249642)
							(end -0.2794 -0.1778)
						)
						(arc
							(start -0.2794 0.1778)
							(mid -0.249642 0.249642)
							(end -0.1778 0.2794)
						)
						(arc
							(start 0.1778 0.2794)
							(mid 0.249642 0.249642)
							(end 0.2794 0.1778)
						)
						(arc
							(start 0.2794 -0.1778)
							(mid 0.249642 -0.249642)
							(end 0.1778 -0.2794)
						)
					)
					(width 0)
					(fill yes)
				)
			)
		)
	)
	(footprint ""
		(layer "F.Cu")
		(at 254.2413 -214.31504)
		(property "Reference" "R118"
			(at 0 0 0)
			(layer "F.SilkS")
			(hide yes)
			(effects
				(font
					(size 1.27 1.27)
				)
			)
		)
		(property "Value" "0R2J-2-GP"
			(at 0.064008 -3.993896 0)
			(unlocked yes)
			(layer "F.Fab")
			(hide yes)
			(effects
				(font
					(size 1.016 1.016)
					(thickness 0.1524)
				)
			)
		)
		(property "Device Type" "R402H16"
			(at 0.064008 -5.517896 0)
			(unlocked yes)
			(layer "F.Fab")
			(hide yes)
			(effects
				(font
					(size 1.016 1.016)
					(thickness 0.1524)
				)
			)
		)
		(duplicate_pad_numbers_are_jumpers no)
		(fp_line
			(start -0.508 -0.9398)
			(end -0.508 0.9398)
			(stroke
				(width 0.1524)
				(type default)
			)
			(layer "F.SilkS")
		)
		(fp_line
			(start 0.508 -0.9398)
			(end -0.508 -0.9398)
			(stroke
				(width 0.1524)
				(type default)
			)
			(layer "F.SilkS")
		)
		(fp_rect
			(start -0.508 0.9398)
			(end 0.508 -0.9398)
			(stroke
				(width 0)
				(type default)
			)
			(fill no)
			(layer "F.CrtYd")
		)
		(fp_rect
			(start -0.508 0.9398)
			(end 0.508 -0.9398)
			(stroke
				(width 0)
				(type default)
			)
			(fill no)
			(layer "F.Fab")
		)
		(pad "1" smd custom
			(at 0 -0.4445)
			(size 0.1397 0.1397)
			(layers "F.Cu" "F.Mask" "F.Paste")
			(net "VOL_SEN_SDA")
			(options
				(clearance outline)
				(anchor circle)
			)
			(primitives
				(gr_poly
					(pts
						(arc
							(start -0.1778 -0.2794)
							(mid -0.249642 -0.249642)
							(end -0.2794 -0.1778)
						)
						(arc
							(start -0.2794 0.1778)
							(mid -0.249642 0.249642)
							(end -0.1778 0.2794)
						)
						(arc
							(start 0.1778 0.2794)
							(mid 0.249642 0.249642)
							(end 0.2794 0.1778)
						)
						(arc
							(start 0.2794 -0.1778)
							(mid 0.249642 -0.249642)
							(end 0.1778 -0.2794)
						)
					)
					(width 0)
					(fill yes)
				)
			)
		)
		(pad "2" smd custom
			(at 0 0.4445)
			(size 0.1397 0.1397)
			(layers "F.Cu" "F.Mask" "F.Paste")
			(net "I2C_DPB_B_SDA_BUF")
			(options
				(clearance outline)
				(anchor circle)
			)
			(primitives
				(gr_poly
					(pts
						(arc
							(start -0.1778 -0.2794)
							(mid -0.249642 -0.249642)
							(end -0.2794 -0.1778)
						)
						(arc
							(start -0.2794 0.1778)
							(mid -0.249642 0.249642)
							(end -0.1778 0.2794)
						)
						(arc
							(start 0.1778 0.2794)
							(mid 0.249642 0.249642)
							(end 0.2794 0.1778)
						)
						(arc
							(start 0.2794 -0.1778)
							(mid 0.249642 -0.249642)
							(end 0.1778 -0.2794)
						)
					)
					(width 0)
					(fill yes)
				)
			)
		)
	)
	(footprint ""
		(layer "F.Cu")
		(at 441.349892 -180.399944)
		(property "Reference" "LED11"
			(at 0 0 0)
			(layer "F.SilkS")
			(hide yes)
			(effects
				(font
					(size 1.27 1.27)
				)
			)
		)
		(property "Value" "LED-BY-19-GP"
			(at -2.132076 1.414018 0)
			(unlocked yes)
			(layer "F.Fab")
			(hide yes)
			(effects
				(font
					(size 1.016 1.016)
					(thickness 0.1524)
				)
			)
		)
		(property "Device Type" "LED-1615-4PH26"
			(at -2.132076 -0.109982 0)
			(unlocked yes)
			(layer "F.Fab")
			(hide yes)
			(effects
				(font
					(size 1.016 1.016)
					(thickness 0.1524)
				)
			)
		)
		(duplicate_pad_numbers_are_jumpers no)
		(fp_line
			(start -1.2954 0.254)
			(end -1.2954 1.6002)
			(stroke
				(width 0.508)
				(type default)
			)
			(layer "F.SilkS")
		)
		(fp_line
			(start -1.2954 1.6002)
			(end 1.2954 1.6002)
			(stroke
				(width 0.508)
				(type default)
			)
			(layer "F.SilkS")
		)
		(fp_line
			(start -1.1176 -1.4224)
			(end 1.1176 -1.4224)
			(stroke
				(width 0.1524)
				(type default)
			)
			(layer "F.SilkS")
		)
		(fp_line
			(start -1.1176 1.4224)
			(end -1.1176 -1.4224)
			(stroke
				(width 0.1524)
				(type default)
			)
			(layer "F.SilkS")
		)
		(fp_line
			(start 1.1176 -1.4224)
			(end 1.1176 1.4224)
			(stroke
				(width 0.1524)
				(type default)
			)
			(layer "F.SilkS")
		)
		(fp_line
			(start 1.1176 1.4224)
			(end -1.1176 1.4224)
			(stroke
				(width 0.1524)
				(type default)
			)
			(layer "F.SilkS")
		)
		(fp_line
			(start 1.2954 1.6002)
			(end 1.2954 0.254)
			(stroke
				(width 0.508)
				(type default)
			)
			(layer "F.SilkS")
		)
		(fp_rect
			(start -0.7493 0.8001)
			(end 0.7493 -0.8001)
			(stroke
				(width 0)
				(type default)
			)
			(fill no)
			(layer "F.CrtYd")
		)
		(fp_poly
			(pts
				(xy -1.3716 1.6764) (xy -1.3716 -1.6764) (xy 1.3716 -1.6764) (xy 1.3716 0.0635) (xy 0.7493 0.0635)
				(xy 0.7493 -0.8001) (xy -0.7493 -0.8001) (xy -0.7493 0.8001) (xy 0.7493 0.8001) (xy 0.7493 0.0762)
				(xy 1.3716 0.0762) (xy 1.3716 1.6764)
			)
			(stroke
				(width 0)
				(type default)
			)
			(fill no)
			(layer "F.CrtYd")
		)
		(fp_rect
			(start -1.3716 1.6764)
			(end 1.3716 -1.6764)
			(stroke
				(width 0)
				(type default)
			)
			(fill no)
			(layer "F.Fab")
		)
		(pad "1" smd rect
			(at 0.50038 -0.73025)
			(size 0.7112 0.8636)
			(layers "F.Cu" "F.Mask" "F.Paste")
			(net "DRV_ACT_10")
		)
		(pad "2" smd rect
			(at -0.50038 -0.73025)
			(size 0.7112 0.8636)
			(layers "F.Cu" "F.Mask" "F.Paste")
			(net "FLT_HDD10")
		)
		(pad "3" smd rect
			(at 0.50038 0.73025)
			(size 0.7112 0.8636)
			(layers "F.Cu" "F.Mask" "F.Paste")
			(net "DRV_ACT_10_N")
		)
		(pad "4" smd rect
			(at -0.50038 0.73025)
			(size 0.7112 0.8636)
			(layers "F.Cu" "F.Mask" "F.Paste")
			(net "FLT_HDD10_N")
		)
	)
	(footprint ""
		(layer "F.Cu")
		(at 143.999966 -65.39992)
		(property "Reference" "LED17"
			(at 0 0 0)
			(layer "F.SilkS")
			(hide yes)
			(effects
				(font
					(size 1.27 1.27)
				)
			)
		)
		(property "Value" "LED-BY-19-GP"
			(at -2.132076 1.414018 0)
			(unlocked yes)
			(layer "F.Fab")
			(hide yes)
			(effects
				(font
					(size 1.016 1.016)
					(thickness 0.1524)
				)
			)
		)
		(property "Device Type" "LED-1615-4PH26"
			(at -2.132076 -0.109982 0)
			(unlocked yes)
			(layer "F.Fab")
			(hide yes)
			(effects
				(font
					(size 1.016 1.016)
					(thickness 0.1524)
				)
			)
		)
		(duplicate_pad_numbers_are_jumpers no)
		(fp_line
			(start -1.2954 0.254)
			(end -1.2954 1.6002)
			(stroke
				(width 0.508)
				(type default)
			)
			(layer "F.SilkS")
		)
		(fp_line
			(start -1.2954 1.6002)
			(end 1.2954 1.6002)
			(stroke
				(width 0.508)
				(type default)
			)
			(layer "F.SilkS")
		)
		(fp_line
			(start -1.1176 -1.4224)
			(end 1.1176 -1.4224)
			(stroke
				(width 0.1524)
				(type default)
			)
			(layer "F.SilkS")
		)
		(fp_line
			(start -1.1176 1.4224)
			(end -1.1176 -1.4224)
			(stroke
				(width 0.1524)
				(type default)
			)
			(layer "F.SilkS")
		)
		(fp_line
			(start 1.1176 -1.4224)
			(end 1.1176 1.4224)
			(stroke
				(width 0.1524)
				(type default)
			)
			(layer "F.SilkS")
		)
		(fp_line
			(start 1.1176 1.4224)
			(end -1.1176 1.4224)
			(stroke
				(width 0.1524)
				(type default)
			)
			(layer "F.SilkS")
		)
		(fp_line
			(start 1.2954 1.6002)
			(end 1.2954 0.254)
			(stroke
				(width 0.508)
				(type default)
			)
			(layer "F.SilkS")
		)
		(fp_rect
			(start -0.7493 0.8001)
			(end 0.7493 -0.8001)
			(stroke
				(width 0)
				(type default)
			)
			(fill no)
			(layer "F.CrtYd")
		)
		(fp_poly
			(pts
				(xy -1.3716 1.6764) (xy -1.3716 -1.6764) (xy 1.3716 -1.6764) (xy 1.3716 0.0635) (xy 0.7493 0.0635)
				(xy 0.7493 -0.8001) (xy -0.7493 -0.8001) (xy -0.7493 0.8001) (xy 0.7493 0.8001) (xy 0.7493 0.0762)
				(xy 1.3716 0.0762) (xy 1.3716 1.6764)
			)
			(stroke
				(width 0)
				(type default)
			)
			(fill no)
			(layer "F.CrtYd")
		)
		(fp_rect
			(start -1.3716 1.6764)
			(end 1.3716 -1.6764)
			(stroke
				(width 0)
				(type default)
			)
			(fill no)
			(layer "F.Fab")
		)
		(pad "1" smd rect
			(at 0.50038 -0.73025)
			(size 0.7112 0.8636)
			(layers "F.Cu" "F.Mask" "F.Paste")
			(net "DRV_ACT_16")
		)
		(pad "2" smd rect
			(at -0.50038 -0.73025)
			(size 0.7112 0.8636)
			(layers "F.Cu" "F.Mask" "F.Paste")
			(net "FLT_HDD16")
		)
		(pad "3" smd rect
			(at 0.50038 0.73025)
			(size 0.7112 0.8636)
			(layers "F.Cu" "F.Mask" "F.Paste")
			(net "DRV_ACT_16_N")
		)
		(pad "4" smd rect
			(at -0.50038 0.73025)
			(size 0.7112 0.8636)
			(layers "F.Cu" "F.Mask" "F.Paste")
			(net "FLT_HDD16_N")
		)
	)
	(footprint ""
		(layer "F.Cu")
		(at 438.643776 -217.413586 -90)
		(property "Reference" "R306"
			(at 0 0 270)
			(layer "F.SilkS")
			(hide yes)
			(effects
				(font
					(size 1.27 1.27)
				)
			)
		)
		(property "Value" "4K7R2F-GP"
			(at 0.064008 -3.993896 270)
			(unlocked yes)
			(layer "F.Fab")
			(hide yes)
			(effects
				(font
					(size 1.016 1.016)
					(thickness 0.1524)
				)
			)
		)
		(property "Device Type" "R402H16"
			(at 0.064008 -5.517896 270)
			(unlocked yes)
			(layer "F.Fab")
			(hide yes)
			(effects
				(font
					(size 1.016 1.016)
					(thickness 0.1524)
				)
			)
		)
		(duplicate_pad_numbers_are_jumpers no)
		(fp_line
			(start -0.508 -0.9398)
			(end -0.508 0.9398)
			(stroke
				(width 0.1524)
				(type default)
			)
			(layer "F.SilkS")
		)
		(fp_line
			(start 0.508 -0.9398)
			(end -0.508 -0.9398)
			(stroke
				(width 0.1524)
				(type default)
			)
			(layer "F.SilkS")
		)
		(fp_rect
			(start -0.508 0.9398)
			(end 0.508 -0.9398)
			(stroke
				(width 0)
				(type default)
			)
			(fill no)
			(layer "F.CrtYd")
		)
		(fp_rect
			(start -0.508 0.9398)
			(end 0.508 -0.9398)
			(stroke
				(width 0)
				(type default)
			)
			(fill no)
			(layer "F.Fab")
		)
		(pad "1" smd custom
			(at 0 -0.4445 270)
			(size 0.1397 0.1397)
			(layers "F.Cu" "F.Mask" "F.Paste")
			(net "DRIVE_B_10_FLT_LED")
			(options
				(clearance outline)
				(anchor circle)
			)
			(primitives
				(gr_poly
					(pts
						(arc
							(start -0.1778 -0.2794)
							(mid -0.249642 -0.249642)
							(end -0.2794 -0.1778)
						)
						(arc
							(start -0.2794 0.1778)
							(mid -0.249642 0.249642)
							(end -0.1778 0.2794)
						)
						(arc
							(start 0.1778 0.2794)
							(mid 0.249642 0.249642)
							(end 0.2794 0.1778)
						)
						(arc
							(start 0.2794 -0.1778)
							(mid 0.249642 -0.249642)
							(end 0.1778 -0.2794)
						)
					)
					(width 0)
					(fill yes)
				)
			)
		)
		(pad "2" smd custom
			(at 0 0.4445 270)
			(size 0.1397 0.1397)
			(layers "F.Cu" "F.Mask" "F.Paste")
			(net "GND")
			(options
				(clearance outline)
				(anchor circle)
			)
			(primitives
				(gr_poly
					(pts
						(arc
							(start -0.1778 -0.2794)
							(mid -0.249642 -0.249642)
							(end -0.2794 -0.1778)
						)
						(arc
							(start -0.2794 0.1778)
							(mid -0.249642 0.249642)
							(end -0.1778 0.2794)
						)
						(arc
							(start 0.1778 0.2794)
							(mid 0.249642 0.249642)
							(end 0.2794 0.1778)
						)
						(arc
							(start 0.2794 -0.1778)
							(mid 0.249642 -0.249642)
							(end 0.1778 -0.2794)
						)
					)
					(width 0)
					(fill yes)
				)
			)
		)
	)
	(footprint ""
		(layer "F.Cu")
		(at 177.8 -32.004 -90)
		(property "Reference" "C408"
			(at 0 0 270)
			(layer "F.SilkS")
			(hide yes)
			(effects
				(font
					(size 1.27 1.27)
				)
			)
		)
		(property "Value" "SC10U16V6KX-2GP"
			(at -0.0762 -5.1308 270)
			(unlocked yes)
			(layer "F.Fab")
			(hide yes)
			(effects
				(font
					(size 1.016 1.016)
					(thickness 0.1524)
				)
			)
		)
		(property "Device Type" "C1206H71"
			(at -0.127 -6.6548 270)
			(unlocked yes)
			(layer "F.Fab")
			(hide yes)
			(effects
				(font
					(size 1.016 1.016)
					(thickness 0.1524)
				)
			)
		)
		(duplicate_pad_numbers_are_jumpers no)
		(fp_line
			(start -1.016 2.2352)
			(end -1.016 0.8382)
			(stroke
				(width 0.1524)
				(type default)
			)
			(layer "F.SilkS")
		)
		(fp_line
			(start 1.016 2.2352)
			(end -1.016 2.2352)
			(stroke
				(width 0.1524)
				(type default)
			)
			(layer "F.SilkS")
		)
		(fp_line
			(start 1.016 0.8382)
			(end 1.016 2.2352)
			(stroke
				(width 0.1524)
				(type default)
			)
			(layer "F.SilkS")
		)
		(fp_line
			(start -1.016 -0.8382)
			(end -1.016 -2.2352)
			(stroke
				(width 0.1524)
				(type default)
			)
			(layer "F.SilkS")
		)
		(fp_line
			(start -1.016 -2.2352)
			(end 1.016 -2.2352)
			(stroke
				(width 0.1524)
				(type default)
			)
			(layer "F.SilkS")
		)
		(fp_line
			(start 1.016 -2.2352)
			(end 1.016 -0.8382)
			(stroke
				(width 0.1524)
				(type default)
			)
			(layer "F.SilkS")
		)
		(fp_rect
			(start -1.0922 2.3114)
			(end 1.0922 -2.3114)
			(stroke
				(width 0)
				(type default)
			)
			(fill no)
			(layer "F.CrtYd")
		)
		(fp_poly
			(pts
				(xy 1.0922 -2.3114) (xy 1.0922 2.3114) (xy -1.0922 2.3114) (xy -1.0922 -2.3114)
			)
			(stroke
				(width 0)
				(type default)
			)
			(fill no)
			(layer "F.Fab")
		)
		(pad "1" smd rect
			(at 0 -1.397 270)
			(size 1.651 1.27)
			(layers "F.Cu" "F.Mask" "F.Paste")
			(net "P5V_HDD29")
		)
		(pad "2" smd rect
			(at 0 1.397 270)
			(size 1.651 1.27)
			(layers "F.Cu" "F.Mask" "F.Paste")
			(net "GND")
		)
	)
	(footprint ""
		(layer "F.Cu")
		(at 65.83553 -244.990874 90)
		(property "Reference" "VIA3"
			(at 0 0 90)
			(layer "F.SilkS")
			(hide yes)
			(effects
				(font
					(size 1.27 1.27)
				)
			)
		)
		(property "Value" "100OHM-8L-2D36MM-L18-GP"
			(at 3.8989 0.5715 90)
			(unlocked yes)
			(layer "F.Fab")
			(hide yes)
			(effects
				(font
					(size 1.016 1.016)
					(thickness 0.1524)
				)
			)
		)
		(property "Device Type" "VIA-PCIE-4P-414097"
			(at 3.8989 -0.9525 90)
			(unlocked yes)
			(layer "F.Fab")
			(hide yes)
			(effects
				(font
					(size 1.016 1.016)
					(thickness 0.1524)
				)
			)
		)
		(duplicate_pad_numbers_are_jumpers no)
		(fp_rect
			(start -2.0701 0.4826)
			(end 2.0701 -0.4826)
			(stroke
				(width 0)
				(type default)
			)
			(fill no)
			(layer "F.CrtYd")
		)
		(fp_rect
			(start -2.0701 0.4826)
			(end 2.0701 -0.4826)
			(stroke
				(width 0)
				(type default)
			)
			(fill no)
			(layer "F.Fab")
		)
		(pad "1" thru_hole circle
			(at -1.5875 0 90)
			(size 0.508 0.508)
			(drill 0.254)
			(layers "*.Cu" "*.Mask")
			(remove_unused_layers no)
			(net "GND")
			(clearance 0.2286)
			(thermal_gap 0.2286)
		)
		(pad "2" thru_hole circle
			(at -0.5715 0 90)
			(size 0.508 0.508)
			(drill 0.254)
			(layers "*.Cu" "*.Mask")
			(remove_unused_layers no)
			(net "PHY_SCC_B_TO_DRV_B_1_DP")
			(clearance 0.2286)
			(thermal_gap 0.2286)
		)
		(pad "3" thru_hole circle
			(at 0.5715 0 90)
			(size 0.508 0.508)
			(drill 0.254)
			(layers "*.Cu" "*.Mask")
			(remove_unused_layers no)
			(net "PHY_SCC_B_TO_DRV_B_1_DN")
			(clearance 0.2286)
			(thermal_gap 0.2286)
		)
		(pad "4" thru_hole circle
			(at 1.5875 0 90)
			(size 0.508 0.508)
			(drill 0.254)
			(layers "*.Cu" "*.Mask")
			(remove_unused_layers no)
			(net "GND")
			(clearance 0.2286)
			(thermal_gap 0.2286)
		)
	)
	(footprint ""
		(layer "F.Cu")
		(at 41.242996 -363.1438)
		(property "Reference" "R928"
			(at 0 0 0)
			(layer "F.SilkS")
			(hide yes)
			(effects
				(font
					(size 1.27 1.27)
				)
			)
		)
		(property "Value" "100KR2F-L1-GP"
			(at 0.064008 -3.993896 0)
			(unlocked yes)
			(layer "F.Fab")
			(hide yes)
			(effects
				(font
					(size 1.016 1.016)
					(thickness 0.1524)
				)
			)
		)
		(property "Device Type" "R402H16"
			(at 0.064008 -5.517896 0)
			(unlocked yes)
			(layer "F.Fab")
			(hide yes)
			(effects
				(font
					(size 1.016 1.016)
					(thickness 0.1524)
				)
			)
		)
		(duplicate_pad_numbers_are_jumpers no)
		(fp_line
			(start -0.508 -0.9398)
			(end -0.508 0.9398)
			(stroke
				(width 0.1524)
				(type default)
			)
			(layer "F.SilkS")
		)
		(fp_line
			(start 0.508 -0.9398)
			(end -0.508 -0.9398)
			(stroke
				(width 0.1524)
				(type default)
			)
			(layer "F.SilkS")
		)
		(fp_rect
			(start -0.508 0.9398)
			(end 0.508 -0.9398)
			(stroke
				(width 0)
				(type default)
			)
			(fill no)
			(layer "F.CrtYd")
		)
		(fp_rect
			(start -0.508 0.9398)
			(end 0.508 -0.9398)
			(stroke
				(width 0)
				(type default)
			)
			(fill no)
			(layer "F.Fab")
		)
		(pad "1" smd custom
			(at 0 -0.4445)
			(size 0.1397 0.1397)
			(layers "F.Cu" "F.Mask" "F.Paste")
			(net "SCC_B_FULL_PWR_EN")
			(options
				(clearance outline)
				(anchor circle)
			)
			(primitives
				(gr_poly
					(pts
						(arc
							(start -0.1778 -0.2794)
							(mid -0.249642 -0.249642)
							(end -0.2794 -0.1778)
						)
						(arc
							(start -0.2794 0.1778)
							(mid -0.249642 0.249642)
							(end -0.1778 0.2794)
						)
						(arc
							(start 0.1778 0.2794)
							(mid 0.249642 0.249642)
							(end 0.2794 0.1778)
						)
						(arc
							(start 0.2794 -0.1778)
							(mid 0.249642 -0.249642)
							(end 0.1778 -0.2794)
						)
					)
					(width 0)
					(fill yes)
				)
			)
		)
		(pad "2" smd custom
			(at 0 0.4445)
			(size 0.1397 0.1397)
			(layers "F.Cu" "F.Mask" "F.Paste")
			(net "GND")
			(options
				(clearance outline)
				(anchor circle)
			)
			(primitives
				(gr_poly
					(pts
						(arc
							(start -0.1778 -0.2794)
							(mid -0.249642 -0.249642)
							(end -0.2794 -0.1778)
						)
						(arc
							(start -0.2794 0.1778)
							(mid -0.249642 0.249642)
							(end -0.1778 0.2794)
						)
						(arc
							(start 0.1778 0.2794)
							(mid 0.249642 0.249642)
							(end 0.2794 0.1778)
						)
						(arc
							(start 0.2794 -0.1778)
							(mid 0.249642 -0.249642)
							(end 0.1778 -0.2794)
						)
					)
					(width 0)
					(fill yes)
				)
			)
		)
	)
	(footprint ""
		(layer "F.Cu")
		(at 475.742 -26.162 180)
		(property "Reference" "Q183"
			(at 0 0 180)
			(layer "F.SilkS")
			(hide yes)
			(effects
				(font
					(size 1.27 1.27)
				)
			)
		)
		(property "Value" "AO4406AL-GP"
			(at -3.707384 -1.5367 180)
			(unlocked yes)
			(layer "F.Fab")
			(hide yes)
			(effects
				(font
					(size 1.016 1.016)
					(thickness 0.1524)
				)
			)
		)
		(property "Device Type" "SOIC8H69"
			(at -3.707384 -3.0607 180)
			(unlocked yes)
			(layer "F.Fab")
			(hide yes)
			(effects
				(font
					(size 1.016 1.016)
					(thickness 0.1524)
				)
			)
		)
		(duplicate_pad_numbers_are_jumpers no)
		(fp_line
			(start 2.1336 1.4224)
			(end 2.1336 -1.4224)
			(stroke
				(width 0.1524)
				(type default)
			)
			(layer "F.SilkS")
		)
		(fp_line
			(start 2.1336 -1.4224)
			(end -2.7432 -1.4224)
			(stroke
				(width 0.1524)
				(type default)
			)
			(layer "F.SilkS")
		)
		(fp_line
			(start -2.1844 -0.0508)
			(end -2.7178 0.508)
			(stroke
				(width 0.1524)
				(type default)
			)
			(layer "F.SilkS")
		)
		(fp_line
			(start -2.6289 3.4417)
			(end -2.6289 1.4732)
			(stroke
				(width 0.381)
				(type default)
			)
			(layer "F.SilkS")
		)
		(fp_line
			(start -2.7178 -0.508)
			(end -2.1844 -0.0508)
			(stroke
				(width 0.1524)
				(type default)
			)
			(layer "F.SilkS")
		)
		(fp_line
			(start -2.7432 1.4224)
			(end 2.1336 1.4224)
			(stroke
				(width 0.1524)
				(type default)
			)
			(layer "F.SilkS")
		)
		(fp_line
			(start -2.7432 1.4224)
			(end -2.6416 1.4224)
			(stroke
				(width 0.1524)
				(type default)
			)
			(layer "F.SilkS")
		)
		(fp_line
			(start -2.7432 -1.4224)
			(end -2.7432 1.4224)
			(stroke
				(width 0.1524)
				(type default)
			)
			(layer "F.SilkS")
		)
		(fp_poly
			(pts
				(xy -2.2098 -1.4224) (xy -2.2098 1.4224) (xy 2.2098 1.4224) (xy 2.2098 -1.4224)
			)
			(stroke
				(width 0)
				(type default)
			)
			(fill yes)
			(layer "F.SilkS")
		)
		(fp_rect
			(start -2.450084 2.999994)
			(end 2.450084 -2.999994)
			(stroke
				(width 0)
				(type default)
			)
			(fill no)
			(layer "F.CrtYd")
		)
		(fp_poly
			(pts
				(xy -2.8194 3.6322) (xy -2.8194 -3.6322) (xy 2.8194 -3.6322) (xy 2.8194 1.18364) (xy 2.450084 1.18364)
				(xy 2.450084 -2.999994) (xy -2.450084 -2.999994) (xy -2.450084 2.999994) (xy 2.450084 2.999994)
				(xy 2.450084 1.18618) (xy 2.8194 1.18618) (xy 2.8194 3.6322)
			)
			(stroke
				(width 0)
				(type default)
			)
			(fill no)
			(layer "F.CrtYd")
		)
		(fp_rect
			(start -2.8194 3.6322)
			(end 2.8194 -3.6322)
			(stroke
				(width 0)
				(type default)
			)
			(fill no)
			(layer "F.Fab")
		)
		(pad "1" smd rect
			(at -1.905 2.54 180)
			(size 0.635 1.651)
			(layers "F.Cu" "F.Mask" "F.Paste")
			(net "P5V_HDD35")
		)
		(pad "2" smd rect
			(at -0.635 2.54 180)
			(size 0.635 1.651)
			(layers "F.Cu" "F.Mask" "F.Paste")
			(net "P5V_HDD35")
		)
		(pad "3" smd rect
			(at 0.635 2.54 180)
			(size 0.635 1.651)
			(layers "F.Cu" "F.Mask" "F.Paste")
			(net "P5V_HDD35")
		)
		(pad "4" smd rect
			(at 1.905 2.54 180)
			(size 0.635 1.651)
			(layers "F.Cu" "F.Mask" "F.Paste")
			(net "SW_HDD_P35")
		)
		(pad "5" smd rect
			(at 1.905 -2.54 180)
			(size 0.635 1.651)
			(layers "F.Cu" "F.Mask" "F.Paste")
			(net "P5V_B_4")
		)
		(pad "6" smd rect
			(at 0.635 -2.54 180)
			(size 0.635 1.651)
			(layers "F.Cu" "F.Mask" "F.Paste")
			(net "P5V_B_4")
		)
		(pad "7" smd rect
			(at -0.635 -2.54 180)
			(size 0.635 1.651)
			(layers "F.Cu" "F.Mask" "F.Paste")
			(net "P5V_B_4")
		)
		(pad "8" smd rect
			(at -1.905 -2.54 180)
			(size 0.635 1.651)
			(layers "F.Cu" "F.Mask" "F.Paste")
			(net "P5V_B_4")
		)
	)
	(footprint ""
		(layer "F.Cu")
		(at 114.8334 -33.782 -90)
		(property "Reference" "C381"
			(at 0 0 270)
			(layer "F.SilkS")
			(hide yes)
			(effects
				(font
					(size 1.27 1.27)
				)
			)
		)
		(property "Value" "SC1U16V3KX-5GP"
			(at 0 -2.8194 270)
			(unlocked yes)
			(layer "F.Fab")
			(hide yes)
			(effects
				(font
					(size 1.016 1.016)
					(thickness 0.1524)
				)
			)
		)
		(property "Device Type" "C603H36"
			(at 0 -4.3434 270)
			(unlocked yes)
			(layer "F.Fab")
			(hide yes)
			(effects
				(font
					(size 1.016 1.016)
					(thickness 0.1524)
				)
			)
		)
		(duplicate_pad_numbers_are_jumpers no)
		(fp_line
			(start 0.508 0)
			(end -0.508 0)
			(stroke
				(width 0.2032)
				(type default)
			)
			(layer "F.SilkS")
		)
		(fp_rect
			(start -0.5842 1.3335)
			(end 0.5842 -1.3335)
			(stroke
				(width 0)
				(type default)
			)
			(fill no)
			(layer "F.CrtYd")
		)
		(fp_rect
			(start -0.5842 1.3335)
			(end 0.5842 -1.3335)
			(stroke
				(width 0)
				(type default)
			)
			(fill no)
			(layer "F.Fab")
		)
		(pad "1" smd custom
			(at 0 -0.762 270)
			(size 0.2159 0.2159)
			(layers "F.Cu" "F.Mask" "F.Paste")
			(net "P5V_HDD27")
			(options
				(clearance outline)
				(anchor circle)
			)
			(primitives
				(gr_poly
					(pts
						(arc
							(start -0.3302 -0.4318)
							(mid -0.402042 -0.402042)
							(end -0.4318 -0.3302)
						)
						(arc
							(start -0.4318 0.3302)
							(mid -0.402042 0.402042)
							(end -0.3302 0.4318)
						)
						(arc
							(start 0.3302 0.4318)
							(mid 0.402042 0.402042)
							(end 0.4318 0.3302)
						)
						(arc
							(start 0.4318 -0.3302)
							(mid 0.402042 -0.402042)
							(end 0.3302 -0.4318)
						)
					)
					(width 0)
					(fill yes)
				)
			)
		)
		(pad "2" smd custom
			(at 0 0.762 270)
			(size 0.2159 0.2159)
			(layers "F.Cu" "F.Mask" "F.Paste")
			(net "GND")
			(options
				(clearance outline)
				(anchor circle)
			)
			(primitives
				(gr_poly
					(pts
						(arc
							(start -0.3302 -0.4318)
							(mid -0.402042 -0.402042)
							(end -0.4318 -0.3302)
						)
						(arc
							(start -0.4318 0.3302)
							(mid -0.402042 0.402042)
							(end -0.3302 0.4318)
						)
						(arc
							(start 0.3302 0.4318)
							(mid 0.402042 0.402042)
							(end 0.4318 0.3302)
						)
						(arc
							(start 0.4318 -0.3302)
							(mid 0.402042 -0.402042)
							(end 0.3302 -0.4318)
						)
					)
					(width 0)
					(fill yes)
				)
			)
		)
	)
	(footprint ""
		(layer "F.Cu")
		(at 426.085 -147.066 -90)
		(property "Reference" "R552"
			(at 0 0 270)
			(layer "F.SilkS")
			(hide yes)
			(effects
				(font
					(size 1.27 1.27)
				)
			)
		)
		(property "Value" "2R6F-GP"
			(at -0.0508 -4.8514 270)
			(unlocked yes)
			(layer "F.Fab")
			(hide yes)
			(effects
				(font
					(size 1.016 1.016)
					(thickness 0.1524)
				)
			)
		)
		(property "Device Type" "R1206H26"
			(at 0 -6.3754 270)
			(unlocked yes)
			(layer "F.Fab")
			(hide yes)
			(effects
				(font
					(size 1.016 1.016)
					(thickness 0.1524)
				)
			)
		)
		(duplicate_pad_numbers_are_jumpers no)
		(fp_line
			(start -1.016 2.2352)
			(end -1.016 -2.2352)
			(stroke
				(width 0.1524)
				(type default)
			)
			(layer "F.SilkS")
		)
		(fp_line
			(start 1.016 2.2352)
			(end -1.016 2.2352)
			(stroke
				(width 0.1524)
				(type default)
			)
			(layer "F.SilkS")
		)
		(fp_line
			(start -1.016 -2.2352)
			(end 1.016 -2.2352)
			(stroke
				(width 0.1524)
				(type default)
			)
			(layer "F.SilkS")
		)
		(fp_line
			(start 1.016 -2.2352)
			(end 1.016 2.2352)
			(stroke
				(width 0.1524)
				(type default)
			)
			(layer "F.SilkS")
		)
		(fp_rect
			(start -1.0922 2.3114)
			(end 1.0922 -2.3114)
			(stroke
				(width 0)
				(type default)
			)
			(fill no)
			(layer "F.CrtYd")
		)
		(fp_poly
			(pts
				(xy -1.0922 -2.3114) (xy 1.0922 -2.3114) (xy 1.0922 2.3114) (xy -1.0922 2.3114)
			)
			(stroke
				(width 0)
				(type default)
			)
			(fill no)
			(layer "F.Fab")
		)
		(pad "1" smd rect
			(at 0 -1.397 270)
			(size 1.651 1.27)
			(layers "F.Cu" "F.Mask" "F.Paste")
			(net "P5V_HDD21")
		)
		(pad "2" smd rect
			(at 0 1.397 270)
			(size 1.651 1.27)
			(layers "F.Cu" "F.Mask" "F.Paste")
			(net "5V_PRE_21")
		)
	)
	(footprint ""
		(layer "F.Cu")
		(at 369.57 -135.509 90)
		(property "Reference" "R523"
			(at 0 0 90)
			(layer "F.SilkS")
			(hide yes)
			(effects
				(font
					(size 1.27 1.27)
				)
			)
		)
		(property "Value" "200KR2F-L-GP"
			(at 0.064008 -3.993896 90)
			(unlocked yes)
			(layer "F.Fab")
			(hide yes)
			(effects
				(font
					(size 1.016 1.016)
					(thickness 0.1524)
				)
			)
		)
		(property "Device Type" "R402H16"
			(at 0.064008 -5.517896 90)
			(unlocked yes)
			(layer "F.Fab")
			(hide yes)
			(effects
				(font
					(size 1.016 1.016)
					(thickness 0.1524)
				)
			)
		)
		(duplicate_pad_numbers_are_jumpers no)
		(fp_line
			(start 0.508 -0.9398)
			(end -0.508 -0.9398)
			(stroke
				(width 0.1524)
				(type default)
			)
			(layer "F.SilkS")
		)
		(fp_line
			(start -0.508 -0.9398)
			(end -0.508 0.9398)
			(stroke
				(width 0.1524)
				(type default)
			)
			(layer "F.SilkS")
		)
		(fp_rect
			(start -0.508 0.9398)
			(end 0.508 -0.9398)
			(stroke
				(width 0)
				(type default)
			)
			(fill no)
			(layer "F.CrtYd")
		)
		(fp_rect
			(start -0.508 0.9398)
			(end 0.508 -0.9398)
			(stroke
				(width 0)
				(type default)
			)
			(fill no)
			(layer "F.Fab")
		)
		(pad "1" smd custom
			(at 0 -0.4445 90)
			(size 0.1397 0.1397)
			(layers "F.Cu" "F.Mask" "F.Paste")
			(net "SW_HDD_R19")
			(options
				(clearance outline)
				(anchor circle)
			)
			(primitives
				(gr_poly
					(pts
						(arc
							(start -0.1778 -0.2794)
							(mid -0.249642 -0.249642)
							(end -0.2794 -0.1778)
						)
						(arc
							(start -0.2794 0.1778)
							(mid -0.249642 0.249642)
							(end -0.1778 0.2794)
						)
						(arc
							(start 0.1778 0.2794)
							(mid 0.249642 0.249642)
							(end 0.2794 0.1778)
						)
						(arc
							(start 0.2794 -0.1778)
							(mid 0.249642 -0.249642)
							(end 0.1778 -0.2794)
						)
					)
					(width 0)
					(fill yes)
				)
			)
		)
		(pad "2" smd custom
			(at 0 0.4445 90)
			(size 0.1397 0.1397)
			(layers "F.Cu" "F.Mask" "F.Paste")
			(net "SW_HDD_N19")
			(options
				(clearance outline)
				(anchor circle)
			)
			(primitives
				(gr_poly
					(pts
						(arc
							(start -0.1778 -0.2794)
							(mid -0.249642 -0.249642)
							(end -0.2794 -0.1778)
						)
						(arc
							(start -0.2794 0.1778)
							(mid -0.249642 0.249642)
							(end -0.1778 0.2794)
						)
						(arc
							(start 0.1778 0.2794)
							(mid 0.249642 0.249642)
							(end 0.2794 0.1778)
						)
						(arc
							(start 0.2794 -0.1778)
							(mid 0.249642 -0.249642)
							(end 0.1778 -0.2794)
						)
					)
					(width 0)
					(fill yes)
				)
			)
		)
	)
	(footprint ""
		(layer "F.Cu")
		(at 173.99 -361.696)
		(property "Reference" "C546"
			(at 0 0 0)
			(layer "F.SilkS")
			(hide yes)
			(effects
				(font
					(size 1.27 1.27)
				)
			)
		)
		(property "Value" "SCD1U25V2KX-2-GP"
			(at 1.1811 -2.7051 0)
			(unlocked yes)
			(layer "F.Fab")
			(hide yes)
			(effects
				(font
					(size 1.016 1.016)
					(thickness 0.1524)
				)
			)
		)
		(property "Device Type" "C402H22"
			(at 1.1811 -4.2291 0)
			(unlocked yes)
			(layer "F.Fab")
			(hide yes)
			(effects
				(font
					(size 1.016 1.016)
					(thickness 0.1524)
				)
			)
		)
		(duplicate_pad_numbers_are_jumpers no)
		(fp_rect
			(start -0.4318 0.9525)
			(end 0.4318 -0.9525)
			(stroke
				(width 0)
				(type default)
			)
			(fill no)
			(layer "F.CrtYd")
		)
		(fp_rect
			(start -0.4318 0.9525)
			(end 0.4318 -0.9525)
			(stroke
				(width 0)
				(type default)
			)
			(fill no)
			(layer "F.Fab")
		)
		(pad "1" smd custom
			(at 0 -0.4445)
			(size 0.1524 0.1524)
			(layers "F.Cu" "F.Mask" "F.Paste")
			(net "MB0_ISET_R")
			(options
				(clearance outline)
				(anchor circle)
			)
			(primitives
				(gr_poly
					(pts
						(arc
							(start 0.3048 -0.2032)
							(mid 0.275042 -0.275042)
							(end 0.2032 -0.3048)
						)
						(arc
							(start -0.2032 -0.3048)
							(mid -0.275042 -0.275042)
							(end -0.3048 -0.2032)
						)
						(arc
							(start -0.3048 0.2032)
							(mid -0.275042 0.275042)
							(end -0.2032 0.3048)
						)
						(arc
							(start 0.2032 0.3048)
							(mid 0.275042 0.275042)
							(end 0.3048 0.2032)
						)
					)
					(width 0)
					(fill yes)
				)
			)
		)
		(pad "2" smd custom
			(at 0 0.4445)
			(size 0.1524 0.1524)
			(layers "F.Cu" "F.Mask" "F.Paste")
			(net "AGND_CURRENT_MON")
			(options
				(clearance outline)
				(anchor circle)
			)
			(primitives
				(gr_poly
					(pts
						(arc
							(start 0.3048 -0.2032)
							(mid 0.275042 -0.275042)
							(end 0.2032 -0.3048)
						)
						(arc
							(start -0.2032 -0.3048)
							(mid -0.275042 -0.275042)
							(end -0.3048 -0.2032)
						)
						(arc
							(start -0.3048 0.2032)
							(mid -0.275042 0.275042)
							(end -0.2032 0.3048)
						)
						(arc
							(start 0.2032 0.3048)
							(mid 0.275042 0.275042)
							(end 0.3048 0.2032)
						)
					)
					(width 0)
					(fill yes)
				)
			)
		)
	)
	(footprint ""
		(layer "F.Cu")
		(at 288.064448 -347.541342 180)
		(property "Reference" "R1072"
			(at 0 0 180)
			(layer "F.SilkS")
			(hide yes)
			(effects
				(font
					(size 1.27 1.27)
				)
			)
		)
		(property "Value" "4K7R2F-GP"
			(at 0.064008 -3.993896 180)
			(unlocked yes)
			(layer "F.Fab")
			(hide yes)
			(effects
				(font
					(size 1.016 1.016)
					(thickness 0.1524)
				)
			)
		)
		(property "Device Type" "R402H16"
			(at 0.064008 -5.517896 180)
			(unlocked yes)
			(layer "F.Fab")
			(hide yes)
			(effects
				(font
					(size 1.016 1.016)
					(thickness 0.1524)
				)
			)
		)
		(duplicate_pad_numbers_are_jumpers no)
		(fp_line
			(start 0.508 -0.9398)
			(end -0.508 -0.9398)
			(stroke
				(width 0.1524)
				(type default)
			)
			(layer "F.SilkS")
		)
		(fp_line
			(start -0.508 -0.9398)
			(end -0.508 0.9398)
			(stroke
				(width 0.1524)
				(type default)
			)
			(layer "F.SilkS")
		)
		(fp_rect
			(start -0.508 0.9398)
			(end 0.508 -0.9398)
			(stroke
				(width 0)
				(type default)
			)
			(fill no)
			(layer "F.CrtYd")
		)
		(fp_rect
			(start -0.508 0.9398)
			(end 0.508 -0.9398)
			(stroke
				(width 0)
				(type default)
			)
			(fill no)
			(layer "F.Fab")
		)
		(pad "1" smd custom
			(at 0 -0.4445 180)
			(size 0.1397 0.1397)
			(layers "F.Cu" "F.Mask" "F.Paste")
			(net "P3V3_STBY_B")
			(options
				(clearance outline)
				(anchor circle)
			)
			(primitives
				(gr_poly
					(pts
						(arc
							(start -0.1778 -0.2794)
							(mid -0.249642 -0.249642)
							(end -0.2794 -0.1778)
						)
						(arc
							(start -0.2794 0.1778)
							(mid -0.249642 0.249642)
							(end -0.1778 0.2794)
						)
						(arc
							(start 0.1778 0.2794)
							(mid 0.249642 0.249642)
							(end 0.2794 0.1778)
						)
						(arc
							(start 0.2794 -0.1778)
							(mid 0.249642 -0.249642)
							(end 0.1778 -0.2794)
						)
					)
					(width 0)
					(fill yes)
				)
			)
		)
		(pad "2" smd custom
			(at 0 0.4445 180)
			(size 0.1397 0.1397)
			(layers "F.Cu" "F.Mask" "F.Paste")
			(net "MAX31790_B_ADD0")
			(options
				(clearance outline)
				(anchor circle)
			)
			(primitives
				(gr_poly
					(pts
						(arc
							(start -0.1778 -0.2794)
							(mid -0.249642 -0.249642)
							(end -0.2794 -0.1778)
						)
						(arc
							(start -0.2794 0.1778)
							(mid -0.249642 0.249642)
							(end -0.1778 0.2794)
						)
						(arc
							(start 0.1778 0.2794)
							(mid 0.249642 0.249642)
							(end 0.2794 0.1778)
						)
						(arc
							(start 0.2794 -0.1778)
							(mid 0.249642 -0.249642)
							(end 0.1778 -0.2794)
						)
					)
					(width 0)
					(fill yes)
				)
			)
		)
	)
	(footprint ""
		(layer "F.Cu")
		(at 265.075924 -367.448846 180)
		(property "Reference" "R1"
			(at 0 0 180)
			(layer "F.SilkS")
			(hide yes)
			(effects
				(font
					(size 1.27 1.27)
				)
			)
		)
		(property "Value" "10KR2F-2-GP"
			(at 0.064008 -3.993896 180)
			(unlocked yes)
			(layer "F.Fab")
			(hide yes)
			(effects
				(font
					(size 1.016 1.016)
					(thickness 0.1524)
				)
			)
		)
		(property "Device Type" "R402H16"
			(at 0.064008 -5.517896 180)
			(unlocked yes)
			(layer "F.Fab")
			(hide yes)
			(effects
				(font
					(size 1.016 1.016)
					(thickness 0.1524)
				)
			)
		)
		(duplicate_pad_numbers_are_jumpers no)
		(fp_line
			(start 0.508 -0.9398)
			(end -0.508 -0.9398)
			(stroke
				(width 0.1524)
				(type default)
			)
			(layer "F.SilkS")
		)
		(fp_line
			(start -0.508 -0.9398)
			(end -0.508 0.9398)
			(stroke
				(width 0.1524)
				(type default)
			)
			(layer "F.SilkS")
		)
		(fp_rect
			(start -0.508 0.9398)
			(end 0.508 -0.9398)
			(stroke
				(width 0)
				(type default)
			)
			(fill no)
			(layer "F.CrtYd")
		)
		(fp_rect
			(start -0.508 0.9398)
			(end 0.508 -0.9398)
			(stroke
				(width 0)
				(type default)
			)
			(fill no)
			(layer "F.Fab")
		)
		(pad "1" smd custom
			(at 0 -0.4445 180)
			(size 0.1397 0.1397)
			(layers "F.Cu" "F.Mask" "F.Paste")
			(net "P12V_IN")
			(options
				(clearance outline)
				(anchor circle)
			)
			(primitives
				(gr_poly
					(pts
						(arc
							(start -0.1778 -0.2794)
							(mid -0.249642 -0.249642)
							(end -0.2794 -0.1778)
						)
						(arc
							(start -0.2794 0.1778)
							(mid -0.249642 0.249642)
							(end -0.1778 0.2794)
						)
						(arc
							(start 0.1778 0.2794)
							(mid 0.249642 0.249642)
							(end 0.2794 0.1778)
						)
						(arc
							(start 0.2794 -0.1778)
							(mid 0.249642 -0.249642)
							(end 0.1778 -0.2794)
						)
					)
					(width 0)
					(fill yes)
				)
			)
		)
		(pad "2" smd custom
			(at 0 0.4445 180)
			(size 0.1397 0.1397)
			(layers "F.Cu" "F.Mask" "F.Paste")
			(net "DPB_PWR_BTN_BUF_B")
			(options
				(clearance outline)
				(anchor circle)
			)
			(primitives
				(gr_poly
					(pts
						(arc
							(start -0.1778 -0.2794)
							(mid -0.249642 -0.249642)
							(end -0.2794 -0.1778)
						)
						(arc
							(start -0.2794 0.1778)
							(mid -0.249642 0.249642)
							(end -0.1778 0.2794)
						)
						(arc
							(start 0.1778 0.2794)
							(mid 0.249642 0.249642)
							(end 0.2794 0.1778)
						)
						(arc
							(start 0.2794 -0.1778)
							(mid 0.249642 -0.249642)
							(end 0.1778 -0.2794)
						)
					)
					(width 0)
					(fill yes)
				)
			)
		)
	)
	(footprint ""
		(layer "F.Cu")
		(at 126.9746 -31.623)
		(property "Reference" "C388"
			(at 0 0 0)
			(layer "F.SilkS")
			(hide yes)
			(effects
				(font
					(size 1.27 1.27)
				)
			)
		)
		(property "Value" "SCD01U50V2KX-1GP"
			(at 1.1811 -2.7051 0)
			(unlocked yes)
			(layer "F.Fab")
			(hide yes)
			(effects
				(font
					(size 1.016 1.016)
					(thickness 0.1524)
				)
			)
		)
		(property "Device Type" "C402H22"
			(at 1.1811 -4.2291 0)
			(unlocked yes)
			(layer "F.Fab")
			(hide yes)
			(effects
				(font
					(size 1.016 1.016)
					(thickness 0.1524)
				)
			)
		)
		(duplicate_pad_numbers_are_jumpers no)
		(fp_rect
			(start -0.4318 0.9525)
			(end 0.4318 -0.9525)
			(stroke
				(width 0)
				(type default)
			)
			(fill no)
			(layer "F.CrtYd")
		)
		(fp_rect
			(start -0.4318 0.9525)
			(end 0.4318 -0.9525)
			(stroke
				(width 0)
				(type default)
			)
			(fill no)
			(layer "F.Fab")
		)
		(pad "1" smd custom
			(at 0 -0.4445)
			(size 0.1524 0.1524)
			(layers "F.Cu" "F.Mask" "F.Paste")
			(net "HDD_PRSNT_27")
			(options
				(clearance outline)
				(anchor circle)
			)
			(primitives
				(gr_poly
					(pts
						(arc
							(start 0.3048 -0.2032)
							(mid 0.275042 -0.275042)
							(end 0.2032 -0.3048)
						)
						(arc
							(start -0.2032 -0.3048)
							(mid -0.275042 -0.275042)
							(end -0.3048 -0.2032)
						)
						(arc
							(start -0.3048 0.2032)
							(mid -0.275042 0.275042)
							(end -0.2032 0.3048)
						)
						(arc
							(start 0.2032 0.3048)
							(mid 0.275042 0.275042)
							(end 0.3048 0.2032)
						)
					)
					(width 0)
					(fill yes)
				)
			)
		)
		(pad "2" smd custom
			(at 0 0.4445)
			(size 0.1524 0.1524)
			(layers "F.Cu" "F.Mask" "F.Paste")
			(net "GND")
			(options
				(clearance outline)
				(anchor circle)
			)
			(primitives
				(gr_poly
					(pts
						(arc
							(start 0.3048 -0.2032)
							(mid 0.275042 -0.275042)
							(end 0.2032 -0.3048)
						)
						(arc
							(start -0.2032 -0.3048)
							(mid -0.275042 -0.275042)
							(end -0.3048 -0.2032)
						)
						(arc
							(start -0.3048 0.2032)
							(mid -0.275042 0.275042)
							(end -0.2032 0.3048)
						)
						(arc
							(start 0.2032 0.3048)
							(mid 0.275042 0.275042)
							(end 0.3048 0.2032)
						)
					)
					(width 0)
					(fill yes)
				)
			)
		)
	)
	(footprint ""
		(layer "F.Cu")
		(at 464.566 -27.813 -90)
		(property "Reference" "R865"
			(at 0 0 270)
			(layer "F.SilkS")
			(hide yes)
			(effects
				(font
					(size 1.27 1.27)
				)
			)
		)
		(property "Value" "300KR2F-GP"
			(at 0.064008 -3.993896 270)
			(unlocked yes)
			(layer "F.Fab")
			(hide yes)
			(effects
				(font
					(size 1.016 1.016)
					(thickness 0.1524)
				)
			)
		)
		(property "Device Type" "R402H16"
			(at 0.064008 -5.517896 270)
			(unlocked yes)
			(layer "F.Fab")
			(hide yes)
			(effects
				(font
					(size 1.016 1.016)
					(thickness 0.1524)
				)
			)
		)
		(duplicate_pad_numbers_are_jumpers no)
		(fp_line
			(start -0.508 -0.9398)
			(end -0.508 0.9398)
			(stroke
				(width 0.1524)
				(type default)
			)
			(layer "F.SilkS")
		)
		(fp_line
			(start 0.508 -0.9398)
			(end -0.508 -0.9398)
			(stroke
				(width 0.1524)
				(type default)
			)
			(layer "F.SilkS")
		)
		(fp_rect
			(start -0.508 0.9398)
			(end 0.508 -0.9398)
			(stroke
				(width 0)
				(type default)
			)
			(fill no)
			(layer "F.CrtYd")
		)
		(fp_rect
			(start -0.508 0.9398)
			(end 0.508 -0.9398)
			(stroke
				(width 0)
				(type default)
			)
			(fill no)
			(layer "F.Fab")
		)
		(pad "1" smd custom
			(at 0 -0.4445 270)
			(size 0.1397 0.1397)
			(layers "F.Cu" "F.Mask" "F.Paste")
			(net "SW_HDD_N34")
			(options
				(clearance outline)
				(anchor circle)
			)
			(primitives
				(gr_poly
					(pts
						(arc
							(start -0.1778 -0.2794)
							(mid -0.249642 -0.249642)
							(end -0.2794 -0.1778)
						)
						(arc
							(start -0.2794 0.1778)
							(mid -0.249642 0.249642)
							(end -0.1778 0.2794)
						)
						(arc
							(start 0.1778 0.2794)
							(mid 0.249642 0.249642)
							(end 0.2794 0.1778)
						)
						(arc
							(start 0.2794 -0.1778)
							(mid 0.249642 -0.249642)
							(end 0.1778 -0.2794)
						)
					)
					(width 0)
					(fill yes)
				)
			)
		)
		(pad "2" smd custom
			(at 0 0.4445 270)
			(size 0.1397 0.1397)
			(layers "F.Cu" "F.Mask" "F.Paste")
			(net "P12V_B")
			(options
				(clearance outline)
				(anchor circle)
			)
			(primitives
				(gr_poly
					(pts
						(arc
							(start -0.1778 -0.2794)
							(mid -0.249642 -0.249642)
							(end -0.2794 -0.1778)
						)
						(arc
							(start -0.2794 0.1778)
							(mid -0.249642 0.249642)
							(end -0.1778 0.2794)
						)
						(arc
							(start 0.1778 0.2794)
							(mid 0.249642 0.249642)
							(end 0.2794 0.1778)
						)
						(arc
							(start 0.2794 -0.1778)
							(mid 0.249642 -0.249642)
							(end 0.1778 -0.2794)
						)
					)
					(width 0)
					(fill yes)
				)
			)
		)
	)
	(footprint ""
		(layer "F.Cu")
		(at 473.202 -129.286)
		(property "Reference" "R611"
			(at 0 0 0)
			(layer "F.SilkS")
			(hide yes)
			(effects
				(font
					(size 1.27 1.27)
				)
			)
		)
		(property "Value" "4K7R2F-GP"
			(at 0.064008 -3.993896 0)
			(unlocked yes)
			(layer "F.Fab")
			(hide yes)
			(effects
				(font
					(size 1.016 1.016)
					(thickness 0.1524)
				)
			)
		)
		(property "Device Type" "R402H16"
			(at 0.064008 -5.517896 0)
			(unlocked yes)
			(layer "F.Fab")
			(hide yes)
			(effects
				(font
					(size 1.016 1.016)
					(thickness 0.1524)
				)
			)
		)
		(duplicate_pad_numbers_are_jumpers no)
		(fp_line
			(start -0.508 -0.9398)
			(end -0.508 0.9398)
			(stroke
				(width 0.1524)
				(type default)
			)
			(layer "F.SilkS")
		)
		(fp_line
			(start 0.508 -0.9398)
			(end -0.508 -0.9398)
			(stroke
				(width 0.1524)
				(type default)
			)
			(layer "F.SilkS")
		)
		(fp_rect
			(start -0.508 0.9398)
			(end 0.508 -0.9398)
			(stroke
				(width 0)
				(type default)
			)
			(fill no)
			(layer "F.CrtYd")
		)
		(fp_rect
			(start -0.508 0.9398)
			(end 0.508 -0.9398)
			(stroke
				(width 0)
				(type default)
			)
			(fill no)
			(layer "F.Fab")
		)
		(pad "1" smd custom
			(at 0 -0.4445)
			(size 0.1397 0.1397)
			(layers "F.Cu" "F.Mask" "F.Paste")
			(net "SW_PWR_R_HDD23")
			(options
				(clearance outline)
				(anchor circle)
			)
			(primitives
				(gr_poly
					(pts
						(arc
							(start -0.1778 -0.2794)
							(mid -0.249642 -0.249642)
							(end -0.2794 -0.1778)
						)
						(arc
							(start -0.2794 0.1778)
							(mid -0.249642 0.249642)
							(end -0.1778 0.2794)
						)
						(arc
							(start 0.1778 0.2794)
							(mid 0.249642 0.249642)
							(end 0.2794 0.1778)
						)
						(arc
							(start 0.2794 -0.1778)
							(mid 0.249642 -0.249642)
							(end 0.1778 -0.2794)
						)
					)
					(width 0)
					(fill yes)
				)
			)
		)
		(pad "2" smd custom
			(at 0 0.4445)
			(size 0.1397 0.1397)
			(layers "F.Cu" "F.Mask" "F.Paste")
			(net "GND")
			(options
				(clearance outline)
				(anchor circle)
			)
			(primitives
				(gr_poly
					(pts
						(arc
							(start -0.1778 -0.2794)
							(mid -0.249642 -0.249642)
							(end -0.2794 -0.1778)
						)
						(arc
							(start -0.2794 0.1778)
							(mid -0.249642 0.249642)
							(end -0.1778 0.2794)
						)
						(arc
							(start 0.1778 0.2794)
							(mid 0.249642 0.249642)
							(end 0.2794 0.1778)
						)
						(arc
							(start 0.2794 -0.1778)
							(mid 0.249642 -0.249642)
							(end 0.1778 -0.2794)
						)
					)
					(width 0)
					(fill yes)
				)
			)
		)
	)
	(footprint ""
		(layer "F.Cu")
		(at 468.122 -137.033 180)
		(property "Reference" "R615"
			(at 0 0 180)
			(layer "F.SilkS")
			(hide yes)
			(effects
				(font
					(size 1.27 1.27)
				)
			)
		)
		(property "Value" "200KR2F-L-GP"
			(at 0.064008 -3.993896 180)
			(unlocked yes)
			(layer "F.Fab")
			(hide yes)
			(effects
				(font
					(size 1.016 1.016)
					(thickness 0.1524)
				)
			)
		)
		(property "Device Type" "R402H16"
			(at 0.064008 -5.517896 180)
			(unlocked yes)
			(layer "F.Fab")
			(hide yes)
			(effects
				(font
					(size 1.016 1.016)
					(thickness 0.1524)
				)
			)
		)
		(duplicate_pad_numbers_are_jumpers no)
		(fp_line
			(start 0.508 -0.9398)
			(end -0.508 -0.9398)
			(stroke
				(width 0.1524)
				(type default)
			)
			(layer "F.SilkS")
		)
		(fp_line
			(start -0.508 -0.9398)
			(end -0.508 0.9398)
			(stroke
				(width 0.1524)
				(type default)
			)
			(layer "F.SilkS")
		)
		(fp_rect
			(start -0.508 0.9398)
			(end 0.508 -0.9398)
			(stroke
				(width 0)
				(type default)
			)
			(fill no)
			(layer "F.CrtYd")
		)
		(fp_rect
			(start -0.508 0.9398)
			(end 0.508 -0.9398)
			(stroke
				(width 0)
				(type default)
			)
			(fill no)
			(layer "F.Fab")
		)
		(pad "1" smd custom
			(at 0 -0.4445 180)
			(size 0.1397 0.1397)
			(layers "F.Cu" "F.Mask" "F.Paste")
			(net "SW_HDD_R23")
			(options
				(clearance outline)
				(anchor circle)
			)
			(primitives
				(gr_poly
					(pts
						(arc
							(start -0.1778 -0.2794)
							(mid -0.249642 -0.249642)
							(end -0.2794 -0.1778)
						)
						(arc
							(start -0.2794 0.1778)
							(mid -0.249642 0.249642)
							(end -0.1778 0.2794)
						)
						(arc
							(start 0.1778 0.2794)
							(mid 0.249642 0.249642)
							(end 0.2794 0.1778)
						)
						(arc
							(start 0.2794 -0.1778)
							(mid 0.249642 -0.249642)
							(end 0.1778 -0.2794)
						)
					)
					(width 0)
					(fill yes)
				)
			)
		)
		(pad "2" smd custom
			(at 0 0.4445 180)
			(size 0.1397 0.1397)
			(layers "F.Cu" "F.Mask" "F.Paste")
			(net "SW_HDD_N23")
			(options
				(clearance outline)
				(anchor circle)
			)
			(primitives
				(gr_poly
					(pts
						(arc
							(start -0.1778 -0.2794)
							(mid -0.249642 -0.249642)
							(end -0.2794 -0.1778)
						)
						(arc
							(start -0.2794 0.1778)
							(mid -0.249642 0.249642)
							(end -0.1778 0.2794)
						)
						(arc
							(start 0.1778 0.2794)
							(mid 0.249642 0.249642)
							(end 0.2794 0.1778)
						)
						(arc
							(start 0.2794 -0.1778)
							(mid 0.249642 -0.249642)
							(end 0.1778 -0.2794)
						)
					)
					(width 0)
					(fill yes)
				)
			)
		)
	)
	(footprint ""
		(layer "F.Cu")
		(at 111.76 -214.249)
		(property "Reference" "R253"
			(at 0 0 0)
			(layer "F.SilkS")
			(hide yes)
			(effects
				(font
					(size 1.27 1.27)
				)
			)
		)
		(property "Value" "130R3F-GP"
			(at -0.0254 -2.5146 0)
			(unlocked yes)
			(layer "F.Fab")
			(hide yes)
			(effects
				(font
					(size 1.016 1.016)
					(thickness 0.1524)
				)
			)
		)
		(property "Device Type" "R603H22"
			(at -0.0254 -4.0386 0)
			(unlocked yes)
			(layer "F.Fab")
			(hide yes)
			(effects
				(font
					(size 1.016 1.016)
					(thickness 0.1524)
				)
			)
		)
		(duplicate_pad_numbers_are_jumpers no)
		(fp_line
			(start -0.4826 0)
			(end -0.2032 0)
			(stroke
				(width 0.2032)
				(type default)
			)
			(layer "F.SilkS")
		)
		(fp_line
			(start 0.2032 0)
			(end 0.4826 0)
			(stroke
				(width 0.2032)
				(type default)
			)
			(layer "F.SilkS")
		)
		(fp_rect
			(start -0.5842 1.3335)
			(end 0.5842 -1.3335)
			(stroke
				(width 0)
				(type default)
			)
			(fill no)
			(layer "F.CrtYd")
		)
		(fp_rect
			(start -0.5842 1.3335)
			(end 0.5842 -1.3335)
			(stroke
				(width 0)
				(type default)
			)
			(fill no)
			(layer "F.Fab")
		)
		(pad "1" smd custom
			(at 0 -0.762)
			(size 0.2159 0.2159)
			(layers "F.Cu" "F.Mask" "F.Paste")
			(net "P5V_B_1")
			(options
				(clearance outline)
				(anchor circle)
			)
			(primitives
				(gr_poly
					(pts
						(arc
							(start -0.3302 -0.4318)
							(mid -0.402042 -0.402042)
							(end -0.4318 -0.3302)
						)
						(arc
							(start -0.4318 0.3302)
							(mid -0.402042 0.402042)
							(end -0.3302 0.4318)
						)
						(arc
							(start 0.3302 0.4318)
							(mid 0.402042 0.402042)
							(end 0.4318 0.3302)
						)
						(arc
							(start 0.4318 -0.3302)
							(mid 0.402042 -0.402042)
							(end 0.3302 -0.4318)
						)
					)
					(width 0)
					(fill yes)
				)
			)
		)
		(pad "2" smd custom
			(at 0 0.762)
			(size 0.2159 0.2159)
			(layers "F.Cu" "F.Mask" "F.Paste")
			(net "FLT_HDD3")
			(options
				(clearance outline)
				(anchor circle)
			)
			(primitives
				(gr_poly
					(pts
						(arc
							(start -0.3302 -0.4318)
							(mid -0.402042 -0.402042)
							(end -0.4318 -0.3302)
						)
						(arc
							(start -0.4318 0.3302)
							(mid -0.402042 0.402042)
							(end -0.3302 0.4318)
						)
						(arc
							(start 0.3302 0.4318)
							(mid 0.402042 0.402042)
							(end 0.4318 0.3302)
						)
						(arc
							(start 0.4318 -0.3302)
							(mid 0.402042 -0.402042)
							(end 0.3302 -0.4318)
						)
					)
					(width 0)
					(fill yes)
				)
			)
		)
	)
	(footprint ""
		(layer "F.Cu")
		(at 307.068982 -332.979776 180)
		(property "Reference" "C26"
			(at 0 0 180)
			(layer "F.SilkS")
			(hide yes)
			(effects
				(font
					(size 1.27 1.27)
				)
			)
		)
		(property "Value" "SCD1U16V2KX-3GP"
			(at 1.1811 -2.7051 180)
			(unlocked yes)
			(layer "F.Fab")
			(hide yes)
			(effects
				(font
					(size 1.016 1.016)
					(thickness 0.1524)
				)
			)
		)
		(property "Device Type" "C402H22"
			(at 1.1811 -4.2291 180)
			(unlocked yes)
			(layer "F.Fab")
			(hide yes)
			(effects
				(font
					(size 1.016 1.016)
					(thickness 0.1524)
				)
			)
		)
		(duplicate_pad_numbers_are_jumpers no)
		(fp_rect
			(start -0.4318 0.9525)
			(end 0.4318 -0.9525)
			(stroke
				(width 0)
				(type default)
			)
			(fill no)
			(layer "F.CrtYd")
		)
		(fp_rect
			(start -0.4318 0.9525)
			(end 0.4318 -0.9525)
			(stroke
				(width 0)
				(type default)
			)
			(fill no)
			(layer "F.Fab")
		)
		(pad "1" smd custom
			(at 0 -0.4445 180)
			(size 0.1524 0.1524)
			(layers "F.Cu" "F.Mask" "F.Paste")
			(net "P3V3_IN")
			(options
				(clearance outline)
				(anchor circle)
			)
			(primitives
				(gr_poly
					(pts
						(arc
							(start 0.3048 -0.2032)
							(mid 0.275042 -0.275042)
							(end 0.2032 -0.3048)
						)
						(arc
							(start -0.2032 -0.3048)
							(mid -0.275042 -0.275042)
							(end -0.3048 -0.2032)
						)
						(arc
							(start -0.3048 0.2032)
							(mid -0.275042 0.275042)
							(end -0.2032 0.3048)
						)
						(arc
							(start 0.2032 0.3048)
							(mid 0.275042 0.275042)
							(end 0.3048 0.2032)
						)
					)
					(width 0)
					(fill yes)
				)
			)
		)
		(pad "2" smd custom
			(at 0 0.4445 180)
			(size 0.1524 0.1524)
			(layers "F.Cu" "F.Mask" "F.Paste")
			(net "GND")
			(options
				(clearance outline)
				(anchor circle)
			)
			(primitives
				(gr_poly
					(pts
						(arc
							(start 0.3048 -0.2032)
							(mid 0.275042 -0.275042)
							(end 0.2032 -0.3048)
						)
						(arc
							(start -0.2032 -0.3048)
							(mid -0.275042 -0.275042)
							(end -0.3048 -0.2032)
						)
						(arc
							(start -0.3048 0.2032)
							(mid -0.275042 0.275042)
							(end -0.2032 0.3048)
						)
						(arc
							(start 0.2032 0.3048)
							(mid 0.275042 0.275042)
							(end 0.3048 0.2032)
						)
					)
					(width 0)
					(fill yes)
				)
			)
		)
	)
	(footprint ""
		(layer "F.Cu")
		(at 158.663386 -130.21945 90)
		(property "Reference" "C236"
			(at 0 0 90)
			(layer "F.SilkS")
			(hide yes)
			(effects
				(font
					(size 1.27 1.27)
				)
			)
		)
		(property "Value" "SCD01U16V1KX-GP"
			(at -2.8321 -1.7399 90)
			(unlocked yes)
			(layer "F.Fab")
			(hide yes)
			(effects
				(font
					(size 1.016 1.016)
					(thickness 0.1524)
				)
			)
		)
		(property "Device Type" "C0201H13"
			(at -2.8321 -3.2639 90)
			(unlocked yes)
			(layer "F.Fab")
			(hide yes)
			(effects
				(font
					(size 1.016 1.016)
					(thickness 0.1524)
				)
			)
		)
		(duplicate_pad_numbers_are_jumpers no)
		(fp_rect
			(start -0.2794 0.6477)
			(end 0.2794 -0.6477)
			(stroke
				(width 0)
				(type default)
			)
			(fill no)
			(layer "F.CrtYd")
		)
		(fp_rect
			(start -0.2794 0.6477)
			(end 0.2794 -0.6477)
			(stroke
				(width 0)
				(type default)
			)
			(fill no)
			(layer "F.Fab")
		)
		(pad "1" smd custom
			(at 0 -0.2794 90)
			(size 0.0762 0.0762)
			(layers "F.Cu" "F.Mask" "F.Paste")
			(net "SAS_HDD_RX_N16")
			(options
				(clearance outline)
				(anchor circle)
			)
			(primitives
				(gr_poly
					(pts
						(arc
							(start 0.1524 -0.127)
							(mid 0.137521 -0.162921)
							(end 0.1016 -0.1778)
						)
						(arc
							(start -0.1016 -0.1778)
							(mid -0.137521 -0.162921)
							(end -0.1524 -0.127)
						)
						(arc
							(start -0.1524 0.127)
							(mid -0.137521 0.162921)
							(end -0.1016 0.1778)
						)
						(arc
							(start 0.1016 0.1778)
							(mid 0.137521 0.162921)
							(end 0.1524 0.127)
						)
					)
					(width 0)
					(fill yes)
				)
			)
		)
		(pad "2" smd custom
			(at 0 0.2794 90)
			(size 0.0762 0.0762)
			(layers "F.Cu" "F.Mask" "F.Paste")
			(net "PHY_SCC_B_TO_DRV_B_16_DN")
			(options
				(clearance outline)
				(anchor circle)
			)
			(primitives
				(gr_poly
					(pts
						(arc
							(start 0.1524 -0.127)
							(mid 0.137521 -0.162921)
							(end 0.1016 -0.1778)
						)
						(arc
							(start -0.1016 -0.1778)
							(mid -0.137521 -0.162921)
							(end -0.1524 -0.127)
						)
						(arc
							(start -0.1524 0.127)
							(mid -0.137521 0.162921)
							(end -0.1016 0.1778)
						)
						(arc
							(start 0.1016 0.1778)
							(mid 0.137521 0.162921)
							(end 0.1524 0.127)
						)
					)
					(width 0)
					(fill yes)
				)
			)
		)
	)
	(footprint ""
		(layer "F.Cu")
		(at 130.302 -151.003 90)
		(property "Reference" "R419"
			(at 0 0 90)
			(layer "F.SilkS")
			(hide yes)
			(effects
				(font
					(size 1.27 1.27)
				)
			)
		)
		(property "Value" "220R3F-1-GP"
			(at -0.0254 -2.5146 90)
			(unlocked yes)
			(layer "F.Fab")
			(hide yes)
			(effects
				(font
					(size 1.016 1.016)
					(thickness 0.1524)
				)
			)
		)
		(property "Device Type" "R603H22"
			(at -0.0254 -4.0386 90)
			(unlocked yes)
			(layer "F.Fab")
			(hide yes)
			(effects
				(font
					(size 1.016 1.016)
					(thickness 0.1524)
				)
			)
		)
		(duplicate_pad_numbers_are_jumpers no)
		(fp_line
			(start 0.2032 0)
			(end 0.4826 0)
			(stroke
				(width 0.2032)
				(type default)
			)
			(layer "F.SilkS")
		)
		(fp_line
			(start -0.4826 0)
			(end -0.2032 0)
			(stroke
				(width 0.2032)
				(type default)
			)
			(layer "F.SilkS")
		)
		(fp_rect
			(start -0.5842 1.3335)
			(end 0.5842 -1.3335)
			(stroke
				(width 0)
				(type default)
			)
			(fill no)
			(layer "F.CrtYd")
		)
		(fp_rect
			(start -0.5842 1.3335)
			(end 0.5842 -1.3335)
			(stroke
				(width 0)
				(type default)
			)
			(fill no)
			(layer "F.Fab")
		)
		(pad "1" smd custom
			(at 0 -0.762 90)
			(size 0.2159 0.2159)
			(layers "F.Cu" "F.Mask" "F.Paste")
			(net "HDD_PRSNT_15")
			(options
				(clearance outline)
				(anchor circle)
			)
			(primitives
				(gr_poly
					(pts
						(arc
							(start -0.3302 -0.4318)
							(mid -0.402042 -0.402042)
							(end -0.4318 -0.3302)
						)
						(arc
							(start -0.4318 0.3302)
							(mid -0.402042 0.402042)
							(end -0.3302 0.4318)
						)
						(arc
							(start 0.3302 0.4318)
							(mid 0.402042 0.402042)
							(end 0.4318 0.3302)
						)
						(arc
							(start 0.4318 -0.3302)
							(mid 0.402042 -0.402042)
							(end 0.3302 -0.4318)
						)
					)
					(width 0)
					(fill yes)
				)
			)
		)
		(pad "2" smd custom
			(at 0 0.762 90)
			(size 0.2159 0.2159)
			(layers "F.Cu" "F.Mask" "F.Paste")
			(net "DRIVE_B_15_INS")
			(options
				(clearance outline)
				(anchor circle)
			)
			(primitives
				(gr_poly
					(pts
						(arc
							(start -0.3302 -0.4318)
							(mid -0.402042 -0.402042)
							(end -0.4318 -0.3302)
						)
						(arc
							(start -0.4318 0.3302)
							(mid -0.402042 0.402042)
							(end -0.3302 0.4318)
						)
						(arc
							(start 0.3302 0.4318)
							(mid 0.402042 0.402042)
							(end 0.4318 0.3302)
						)
						(arc
							(start 0.4318 -0.3302)
							(mid 0.402042 -0.402042)
							(end 0.3302 -0.4318)
						)
					)
					(width 0)
					(fill yes)
				)
			)
		)
	)
	(footprint ""
		(layer "F.Cu")
		(at 98.806 -266.065 90)
		(property "Reference" "R193"
			(at 0 0 90)
			(layer "F.SilkS")
			(hide yes)
			(effects
				(font
					(size 1.27 1.27)
				)
			)
		)
		(property "Value" "220R3F-1-GP"
			(at -0.0254 -2.5146 90)
			(unlocked yes)
			(layer "F.Fab")
			(hide yes)
			(effects
				(font
					(size 1.016 1.016)
					(thickness 0.1524)
				)
			)
		)
		(property "Device Type" "R603H22"
			(at -0.0254 -4.0386 90)
			(unlocked yes)
			(layer "F.Fab")
			(hide yes)
			(effects
				(font
					(size 1.016 1.016)
					(thickness 0.1524)
				)
			)
		)
		(duplicate_pad_numbers_are_jumpers no)
		(fp_line
			(start 0.2032 0)
			(end 0.4826 0)
			(stroke
				(width 0.2032)
				(type default)
			)
			(layer "F.SilkS")
		)
		(fp_line
			(start -0.4826 0)
			(end -0.2032 0)
			(stroke
				(width 0.2032)
				(type default)
			)
			(layer "F.SilkS")
		)
		(fp_rect
			(start -0.5842 1.3335)
			(end 0.5842 -1.3335)
			(stroke
				(width 0)
				(type default)
			)
			(fill no)
			(layer "F.CrtYd")
		)
		(fp_rect
			(start -0.5842 1.3335)
			(end 0.5842 -1.3335)
			(stroke
				(width 0)
				(type default)
			)
			(fill no)
			(layer "F.Fab")
		)
		(pad "1" smd custom
			(at 0 -0.762 90)
			(size 0.2159 0.2159)
			(layers "F.Cu" "F.Mask" "F.Paste")
			(net "HDD_PRSNT_2")
			(options
				(clearance outline)
				(anchor circle)
			)
			(primitives
				(gr_poly
					(pts
						(arc
							(start -0.3302 -0.4318)
							(mid -0.402042 -0.402042)
							(end -0.4318 -0.3302)
						)
						(arc
							(start -0.4318 0.3302)
							(mid -0.402042 0.402042)
							(end -0.3302 0.4318)
						)
						(arc
							(start 0.3302 0.4318)
							(mid 0.402042 0.402042)
							(end 0.4318 0.3302)
						)
						(arc
							(start 0.4318 -0.3302)
							(mid 0.402042 -0.402042)
							(end 0.3302 -0.4318)
						)
					)
					(width 0)
					(fill yes)
				)
			)
		)
		(pad "2" smd custom
			(at 0 0.762 90)
			(size 0.2159 0.2159)
			(layers "F.Cu" "F.Mask" "F.Paste")
			(net "DRIVE_B_2_INS")
			(options
				(clearance outline)
				(anchor circle)
			)
			(primitives
				(gr_poly
					(pts
						(arc
							(start -0.3302 -0.4318)
							(mid -0.402042 -0.402042)
							(end -0.4318 -0.3302)
						)
						(arc
							(start -0.4318 0.3302)
							(mid -0.402042 0.402042)
							(end -0.3302 0.4318)
						)
						(arc
							(start 0.3302 0.4318)
							(mid 0.402042 0.402042)
							(end 0.4318 0.3302)
						)
						(arc
							(start 0.4318 -0.3302)
							(mid 0.402042 -0.402042)
							(end 0.3302 -0.4318)
						)
					)
					(width 0)
					(fill yes)
				)
			)
		)
	)
	(footprint ""
		(layer "F.Cu")
		(at 59.749944 -28.910026 -90)
		(property "Reference" "HDDSAS25"
			(at 0 0 270)
			(layer "F.SilkS")
			(hide yes)
			(effects
				(font
					(size 1.27 1.27)
				)
			)
		)
		(property "Value" "SKT-SAS15P-14P-45-GP"
			(at -20.7645 -8.9789 270)
			(unlocked yes)
			(layer "F.Fab")
			(hide yes)
			(effects
				(font
					(size 1.016 1.016)
					(thickness 0.1524)
				)
			)
		)
		(property "Device Type" "10120818-001C-TRLF"
			(at -20.7645 -10.5029 270)
			(unlocked yes)
			(layer "F.Fab")
			(hide yes)
			(effects
				(font
					(size 1.016 1.016)
					(thickness 0.1524)
				)
			)
		)
		(duplicate_pad_numbers_are_jumpers no)
		(fp_line
			(start 1.651 4.2926)
			(end 1.651 3.0099)
			(stroke
				(width 0.1524)
				(type default)
			)
			(layer "F.SilkS")
		)
		(fp_line
			(start 8.509 4.2926)
			(end 1.651 4.2926)
			(stroke
				(width 0.1524)
				(type default)
			)
			(layer "F.SilkS")
		)
		(fp_line
			(start -23.4188 3.0099)
			(end -23.4188 -3.2512)
			(stroke
				(width 0.1524)
				(type default)
			)
			(layer "F.SilkS")
		)
		(fp_line
			(start 1.651 3.0099)
			(end -23.4188 3.0099)
			(stroke
				(width 0.1524)
				(type default)
			)
			(layer "F.SilkS")
		)
		(fp_line
			(start 8.509 3.0099)
			(end 8.509 4.2926)
			(stroke
				(width 0.1524)
				(type default)
			)
			(layer "F.SilkS")
		)
		(fp_line
			(start 23.4188 3.0099)
			(end 8.509 3.0099)
			(stroke
				(width 0.1524)
				(type default)
			)
			(layer "F.SilkS")
		)
		(fp_line
			(start -23.4188 -3.2512)
			(end 23.4188 -3.2512)
			(stroke
				(width 0.1524)
				(type default)
			)
			(layer "F.SilkS")
		)
		(fp_line
			(start 23.4188 -3.2512)
			(end 23.4188 3.0099)
			(stroke
				(width 0.1524)
				(type default)
			)
			(layer "F.SilkS")
		)
		(fp_line
			(start 15.5067 -3.3401)
			(end 16.2687 -3.3401)
			(stroke
				(width 0.3302)
				(type default)
			)
			(layer "F.SilkS")
		)
		(fp_poly
			(pts
				(xy 15.868904 -3.230372) (xy 16.503904 -3.865372) (xy 15.233904 -3.865372)
			)
			(stroke
				(width 0)
				(type default)
			)
			(fill yes)
			(layer "F.SilkS")
		)
		(fp_poly
			(pts
				(xy -22.8727 -2.7559) (xy 22.8727 -2.7559) (xy 22.8727 2.7559) (xy 8.255 2.7559) (xy 8.255 3.5179)
				(xy 1.905 3.5179) (xy 1.905 2.7559) (xy -22.8727 2.7559)
			)
			(stroke
				(width 0)
				(type default)
			)
			(fill no)
			(layer "F.CrtYd")
		)
		(fp_poly
			(pts
				(xy 1.397 4.5466) (xy 1.397 3.2639) (xy -23.6728 3.2639) (xy -23.6728 -3.5052) (xy 23.6728 -3.5052)
				(xy 23.6728 -0.00635) (xy 22.8727 -0.00635) (xy 22.8727 -2.7559) (xy -22.8727 -2.7559) (xy -22.8727 2.7559)
				(xy 1.905 2.7559) (xy 1.905 3.5179) (xy 8.255 3.5179) (xy 8.255 2.7559) (xy 22.8727 2.7559) (xy 22.8727 0.00635)
				(xy 23.6728 0.00635) (xy 23.6728 3.2639) (xy 8.763 3.2639) (xy 8.763 4.5466)
			)
			(stroke
				(width 0)
				(type default)
			)
			(fill no)
			(layer "F.CrtYd")
		)
		(fp_poly
			(pts
				(xy 1.397 4.5466) (xy 1.397 3.2639) (xy -23.6728 3.2639) (xy -23.6728 -3.5052) (xy 23.6728 -3.5052)
				(xy 23.6728 3.2639) (xy 8.763 3.2639) (xy 8.763 4.5466)
			)
			(stroke
				(width 0)
				(type default)
			)
			(fill no)
			(layer "F.Fab")
		)
		(pad "" np_thru_hole circle
			(at -18.874994 0 270)
			(size 0.254 0.254)
			(drill 1.3462)
			(layers "*.Cu" "*.Mask")
			(clearance 0.9017)
			(thermal_gap 0.9017)
		)
		(pad "" np_thru_hole circle
			(at 18.874994 0 270)
			(size 0.254 0.254)
			(drill 0.9398)
			(layers "*.Cu" "*.Mask")
			(clearance 0.6985)
			(thermal_gap 0.6985)
		)
		(pad "G1" smd rect
			(at 21.874988 0 270)
			(size 2.5908 2.5908)
			(layers "F.Cu" "F.Mask" "F.Paste")
			(net "GND")
		)
		(pad "G2" smd rect
			(at -21.874988 0 270)
			(size 2.5908 2.5908)
			(layers "F.Cu" "F.Mask" "F.Paste")
			(net "GND")
		)
		(pad "P1" smd rect
			(at 1.905 -1.82499 270)
			(size 0.6096 2.3622)
			(layers "F.Cu" "F.Mask" "F.Paste")
			(net "Net_1674")
		)
		(pad "P2" smd rect
			(at 0.635 -1.82499 270)
			(size 0.6096 2.3622)
			(layers "F.Cu" "F.Mask" "F.Paste")
			(net "Net_1675")
		)
		(pad "P3" smd rect
			(at -0.635 -1.82499 270)
			(size 0.6096 2.3622)
			(layers "F.Cu" "F.Mask" "F.Paste")
			(net "Net_1676")
		)
		(pad "P4" smd rect
			(at -1.905 -1.82499 270)
			(size 0.6096 2.3622)
			(layers "F.Cu" "F.Mask" "F.Paste")
			(net "GND")
		)
		(pad "P5" smd rect
			(at -3.175 -1.82499 270)
			(size 0.6096 2.3622)
			(layers "F.Cu" "F.Mask" "F.Paste")
			(net "HDD_PRSNT_25")
		)
		(pad "P6" smd rect
			(at -4.445 -1.82499 270)
			(size 0.6096 2.3622)
			(layers "F.Cu" "F.Mask" "F.Paste")
			(net "GND")
		)
		(pad "P7" smd rect
			(at -5.715 -1.82499 270)
			(size 0.6096 2.3622)
			(layers "F.Cu" "F.Mask" "F.Paste")
			(net "5V_PRE_25")
		)
		(pad "P8" smd rect
			(at -6.985 -1.82499 270)
			(size 0.6096 2.3622)
			(layers "F.Cu" "F.Mask" "F.Paste")
			(net "P5V_HDD25")
		)
		(pad "P9" smd rect
			(at -8.255 -1.82499 270)
			(size 0.6096 2.3622)
			(layers "F.Cu" "F.Mask" "F.Paste")
			(net "P5V_HDD25")
		)
		(pad "P10" smd rect
			(at -9.525 -1.82499 270)
			(size 0.6096 2.3622)
			(layers "F.Cu" "F.Mask" "F.Paste")
			(net "GND")
		)
		(pad "P11" smd rect
			(at -10.795 -1.82499 270)
			(size 0.6096 2.3622)
			(layers "F.Cu" "F.Mask" "F.Paste")
			(net "ACT_HDD_25")
		)
		(pad "P12" smd rect
			(at -12.065 -1.82499 270)
			(size 0.6096 2.3622)
			(layers "F.Cu" "F.Mask" "F.Paste")
			(net "GND")
		)
		(pad "P13" smd rect
			(at -13.335 -1.82499 270)
			(size 0.6096 2.3622)
			(layers "F.Cu" "F.Mask" "F.Paste")
			(net "12V_PRE_25")
		)
		(pad "P14" smd rect
			(at -14.605 -1.82499 270)
			(size 0.6096 2.3622)
			(layers "F.Cu" "F.Mask" "F.Paste")
			(net "P12V_HDD25")
		)
		(pad "P15" smd rect
			(at -15.875 -1.82499 270)
			(size 0.6096 2.3622)
			(layers "F.Cu" "F.Mask" "F.Paste")
			(net "P12V_HDD25")
		)
		(pad "S1" smd rect
			(at 15.875 -1.82499 270)
			(size 0.6096 2.3622)
			(layers "F.Cu" "F.Mask" "F.Paste")
			(net "GND")
		)
		(pad "S2" smd rect
			(at 14.605 -1.82499 270)
			(size 0.6096 2.3622)
			(layers "F.Cu" "F.Mask" "F.Paste")
			(net "SAS_HDD_RX_P25")
		)
		(pad "S3" smd rect
			(at 13.335 -1.82499 270)
			(size 0.6096 2.3622)
			(layers "F.Cu" "F.Mask" "F.Paste")
			(net "SAS_HDD_RX_N25")
		)
		(pad "S4" smd rect
			(at 12.065 -1.82499 270)
			(size 0.6096 2.3622)
			(layers "F.Cu" "F.Mask" "F.Paste")
			(net "GND")
		)
		(pad "S5" smd rect
			(at 10.795 -1.82499 270)
			(size 0.6096 2.3622)
			(layers "F.Cu" "F.Mask" "F.Paste")
			(net "PHY_DRV_B_TO_SCC_B_25_DN")
		)
		(pad "S6" smd rect
			(at 9.525 -1.82499 270)
			(size 0.6096 2.3622)
			(layers "F.Cu" "F.Mask" "F.Paste")
			(net "PHY_DRV_B_TO_SCC_B_25_DP")
		)
		(pad "S7" smd rect
			(at 8.255 -1.82499 270)
			(size 0.6096 2.3622)
			(layers "F.Cu" "F.Mask" "F.Paste")
			(net "GND")
		)
		(pad "S8" smd rect
			(at 7.480046 2.845054 270)
			(size 0.508 2.3622)
			(layers "F.Cu" "F.Mask" "F.Paste")
			(net "GND")
		)
		(pad "S9" smd rect
			(at 6.679946 2.845054 270)
			(size 0.508 2.3622)
			(layers "F.Cu" "F.Mask" "F.Paste")
			(net "Net_449")
		)
		(pad "S10" smd rect
			(at 5.8801 2.845054 270)
			(size 0.508 2.3622)
			(layers "F.Cu" "F.Mask" "F.Paste")
			(net "Net_341")
		)
		(pad "S11" smd rect
			(at 5.08 2.845054 270)
			(size 0.508 2.3622)
			(layers "F.Cu" "F.Mask" "F.Paste")
			(net "GND")
		)
		(pad "S12" smd rect
			(at 4.2799 2.845054 270)
			(size 0.508 2.3622)
			(layers "F.Cu" "F.Mask" "F.Paste")
			(net "Net_377")
		)
		(pad "S13" smd rect
			(at 3.480054 2.845054 270)
			(size 0.508 2.3622)
			(layers "F.Cu" "F.Mask" "F.Paste")
			(net "Net_413")
		)
		(pad "S14" smd rect
			(at 2.679954 2.845054 270)
			(size 0.508 2.3622)
			(layers "F.Cu" "F.Mask" "F.Paste")
			(net "GND")
		)
		(zone
			(layer "F.Cu")
			(hatch none 0.5)
			(connect_pads
				(clearance 0)
			)
			(min_thickness 0.25)
			(keepout
				(tracks allowed)
				(vias not_allowed)
				(pads allowed)
				(copperpour not_allowed)
				(footprints allowed)
			)
			(placement
				(enabled no)
				(sheetname "")
			)
			(fill
				(thermal_gap 0.5)
				(thermal_bridge_width 0.5)
				(island_removal_mode 0)
			)
			(polygon
				(pts
					(xy 63.407544 -45.648626) (xy 56.333644 -45.648626) (xy 56.333644 -52.582826) (xy 57.438544 -52.582826)
					(xy 57.438544 -48.468026) (xy 62.061344 -48.468026) (xy 62.061344 -52.582826) (xy 63.407544 -52.582826)
				)
			)
		)
		(zone
			(layer "F.Cu")
			(hatch none 0.5)
			(connect_pads
				(clearance 0)
			)
			(min_thickness 0.25)
			(keepout
				(tracks not_allowed)
				(vias allowed)
				(pads allowed)
				(copperpour not_allowed)
				(footprints allowed)
			)
			(placement
				(enabled no)
				(sheetname "")
			)
			(fill
				(thermal_gap 0.5)
				(thermal_bridge_width 0.5)
				(island_removal_mode 0)
			)
			(polygon
				(pts
					(xy 63.407544 -45.648626) (xy 56.333644 -45.648626) (xy 56.333644 -52.582826) (xy 57.438544 -52.582826)
					(xy 57.438544 -48.468026) (xy 62.061344 -48.468026) (xy 62.061344 -52.582826) (xy 63.407544 -52.582826)
				)
			)
		)
		(zone
			(layer "F.Cu")
			(hatch none 0.5)
			(connect_pads
				(clearance 0)
			)
			(min_thickness 0.25)
			(keepout
				(tracks allowed)
				(vias not_allowed)
				(pads allowed)
				(copperpour not_allowed)
				(footprints allowed)
			)
			(placement
				(enabled no)
				(sheetname "")
			)
			(fill
				(thermal_gap 0.5)
				(thermal_bridge_width 0.5)
				(island_removal_mode 0)
			)
			(polygon
				(pts
					(xy 63.407544 -12.171426) (xy 56.333644 -12.171426) (xy 56.333644 -5.237226) (xy 57.438544 -5.237226)
					(xy 57.438544 -9.352026) (xy 62.061344 -9.352026) (xy 62.061344 -5.237226) (xy 63.407544 -5.237226)
				)
			)
		)
		(zone
			(layer "F.Cu")
			(hatch none 0.5)
			(connect_pads
				(clearance 0)
			)
			(min_thickness 0.25)
			(keepout
				(tracks not_allowed)
				(vias allowed)
				(pads allowed)
				(copperpour not_allowed)
				(footprints allowed)
			)
			(placement
				(enabled no)
				(sheetname "")
			)
			(fill
				(thermal_gap 0.5)
				(thermal_bridge_width 0.5)
				(island_removal_mode 0)
			)
			(polygon
				(pts
					(xy 63.407544 -12.171426) (xy 56.333644 -12.171426) (xy 56.333644 -5.237226) (xy 57.438544 -5.237226)
					(xy 57.438544 -9.352026) (xy 62.061344 -9.352026) (xy 62.061344 -5.237226) (xy 63.407544 -5.237226)
				)
			)
		)
		(zone
			(layers "F.Cu" "B.Cu" "In1.Cu" "In2.Cu" "In3.Cu" "In4.Cu" "In5.Cu" "In6.Cu")
			(hatch none 0.5)
			(connect_pads
				(clearance 0)
			)
			(min_thickness 0.25)
			(keepout
				(tracks not_allowed)
				(vias allowed)
				(pads allowed)
				(copperpour not_allowed)
				(footprints allowed)
			)
			(placement
				(enabled no)
				(sheetname "")
			)
			(fill
				(thermal_gap 0.5)
				(thermal_bridge_width 0.5)
				(island_removal_mode 0)
			)
			(polygon
				(pts
					(arc
						(start 60.524644 -10.035032)
						(mid 58.975244 -10.035032)
						(end 60.524644 -10.035032)
					)
				)
			)
		)
		(zone
			(layers "F.Cu" "B.Cu" "In1.Cu" "In2.Cu" "In3.Cu" "In4.Cu" "In5.Cu" "In6.Cu")
			(hatch none 0.5)
			(connect_pads
				(clearance 0)
			)
			(min_thickness 0.25)
			(keepout
				(tracks not_allowed)
				(vias allowed)
				(pads allowed)
				(copperpour not_allowed)
				(footprints allowed)
			)
			(placement
				(enabled no)
				(sheetname "")
			)
			(fill
				(thermal_gap 0.5)
				(thermal_bridge_width 0.5)
				(island_removal_mode 0)
			)
			(polygon
				(pts
					(arc
						(start 60.727844 -47.78502)
						(mid 58.772044 -47.78502)
						(end 60.727844 -47.78502)
					)
				)
			)
		)
	)
	(footprint ""
		(layer "F.Cu")
		(at 14.859 -25.527 90)
		(property "Reference" "C351"
			(at 0 0 90)
			(layer "F.SilkS")
			(hide yes)
			(effects
				(font
					(size 1.27 1.27)
				)
			)
		)
		(property "Value" "SCD033U25V2KX-GP"
			(at 1.1811 -2.7051 90)
			(unlocked yes)
			(layer "F.Fab")
			(hide yes)
			(effects
				(font
					(size 1.016 1.016)
					(thickness 0.1524)
				)
			)
		)
		(property "Device Type" "C402H22"
			(at 1.1811 -4.2291 90)
			(unlocked yes)
			(layer "F.Fab")
			(hide yes)
			(effects
				(font
					(size 1.016 1.016)
					(thickness 0.1524)
				)
			)
		)
		(duplicate_pad_numbers_are_jumpers no)
		(fp_rect
			(start -0.4318 0.9525)
			(end 0.4318 -0.9525)
			(stroke
				(width 0)
				(type default)
			)
			(fill no)
			(layer "F.CrtYd")
		)
		(fp_rect
			(start -0.4318 0.9525)
			(end 0.4318 -0.9525)
			(stroke
				(width 0)
				(type default)
			)
			(fill no)
			(layer "F.Fab")
		)
		(pad "1" smd custom
			(at 0 -0.4445 90)
			(size 0.1524 0.1524)
			(layers "F.Cu" "F.Mask" "F.Paste")
			(net "P12V_B")
			(options
				(clearance outline)
				(anchor circle)
			)
			(primitives
				(gr_poly
					(pts
						(arc
							(start 0.3048 -0.2032)
							(mid 0.275042 -0.275042)
							(end 0.2032 -0.3048)
						)
						(arc
							(start -0.2032 -0.3048)
							(mid -0.275042 -0.275042)
							(end -0.3048 -0.2032)
						)
						(arc
							(start -0.3048 0.2032)
							(mid -0.275042 0.275042)
							(end -0.2032 0.3048)
						)
						(arc
							(start 0.2032 0.3048)
							(mid 0.275042 0.275042)
							(end 0.3048 0.2032)
						)
					)
					(width 0)
					(fill yes)
				)
			)
		)
		(pad "2" smd custom
			(at 0 0.4445 90)
			(size 0.1524 0.1524)
			(layers "F.Cu" "F.Mask" "F.Paste")
			(net "SW_HDD_N24")
			(options
				(clearance outline)
				(anchor circle)
			)
			(primitives
				(gr_poly
					(pts
						(arc
							(start 0.3048 -0.2032)
							(mid 0.275042 -0.275042)
							(end 0.2032 -0.3048)
						)
						(arc
							(start -0.2032 -0.3048)
							(mid -0.275042 -0.275042)
							(end -0.3048 -0.2032)
						)
						(arc
							(start -0.3048 0.2032)
							(mid -0.275042 0.275042)
							(end -0.2032 0.3048)
						)
						(arc
							(start 0.2032 0.3048)
							(mid 0.275042 0.275042)
							(end 0.3048 0.2032)
						)
					)
					(width 0)
					(fill yes)
				)
			)
		)
	)
	(footprint ""
		(layer "F.Cu")
		(at 469.519 -24.257)
		(property "Reference" "Q186"
			(at 0 0 0)
			(layer "F.SilkS")
			(hide yes)
			(effects
				(font
					(size 1.27 1.27)
				)
			)
		)
		(property "Value" "AO4407AL-GP"
			(at -3.707384 -1.5367 0)
			(unlocked yes)
			(layer "F.Fab")
			(hide yes)
			(effects
				(font
					(size 1.016 1.016)
					(thickness 0.1524)
				)
			)
		)
		(property "Device Type" "SOIC8H69"
			(at -3.707384 -3.0607 0)
			(unlocked yes)
			(layer "F.Fab")
			(hide yes)
			(effects
				(font
					(size 1.016 1.016)
					(thickness 0.1524)
				)
			)
		)
		(duplicate_pad_numbers_are_jumpers no)
		(fp_line
			(start -2.7432 -1.4224)
			(end -2.7432 1.4224)
			(stroke
				(width 0.1524)
				(type default)
			)
			(layer "F.SilkS")
		)
		(fp_line
			(start -2.7432 1.4224)
			(end -2.6416 1.4224)
			(stroke
				(width 0.1524)
				(type default)
			)
			(layer "F.SilkS")
		)
		(fp_line
			(start -2.7432 1.4224)
			(end 2.1336 1.4224)
			(stroke
				(width 0.1524)
				(type default)
			)
			(layer "F.SilkS")
		)
		(fp_line
			(start -2.7178 -0.508)
			(end -2.1844 -0.0508)
			(stroke
				(width 0.1524)
				(type default)
			)
			(layer "F.SilkS")
		)
		(fp_line
			(start -2.6289 3.4417)
			(end -2.6289 1.4732)
			(stroke
				(width 0.381)
				(type default)
			)
			(layer "F.SilkS")
		)
		(fp_line
			(start -2.1844 -0.0508)
			(end -2.7178 0.508)
			(stroke
				(width 0.1524)
				(type default)
			)
			(layer "F.SilkS")
		)
		(fp_line
			(start 2.1336 -1.4224)
			(end -2.7432 -1.4224)
			(stroke
				(width 0.1524)
				(type default)
			)
			(layer "F.SilkS")
		)
		(fp_line
			(start 2.1336 1.4224)
			(end 2.1336 -1.4224)
			(stroke
				(width 0.1524)
				(type default)
			)
			(layer "F.SilkS")
		)
		(fp_poly
			(pts
				(xy -2.2098 -1.4224) (xy -2.2098 1.4224) (xy 2.2098 1.4224) (xy 2.2098 -1.4224)
			)
			(stroke
				(width 0)
				(type default)
			)
			(fill yes)
			(layer "F.SilkS")
		)
		(fp_rect
			(start -2.450084 2.999994)
			(end 2.450084 -2.999994)
			(stroke
				(width 0)
				(type default)
			)
			(fill no)
			(layer "F.CrtYd")
		)
		(fp_poly
			(pts
				(xy -2.8194 3.6322) (xy -2.8194 -3.6322) (xy 2.8194 -3.6322) (xy 2.8194 1.18364) (xy 2.450084 1.18364)
				(xy 2.450084 -2.999994) (xy -2.450084 -2.999994) (xy -2.450084 2.999994) (xy 2.450084 2.999994)
				(xy 2.450084 1.18618) (xy 2.8194 1.18618) (xy 2.8194 3.6322)
			)
			(stroke
				(width 0)
				(type default)
			)
			(fill no)
			(layer "F.CrtYd")
		)
		(fp_rect
			(start -2.8194 3.6322)
			(end 2.8194 -3.6322)
			(stroke
				(width 0)
				(type default)
			)
			(fill no)
			(layer "F.Fab")
		)
		(pad "1" smd rect
			(at -1.905 2.54)
			(size 0.635 1.651)
			(layers "F.Cu" "F.Mask" "F.Paste")
			(net "P12V_B")
		)
		(pad "2" smd rect
			(at -0.635 2.54)
			(size 0.635 1.651)
			(layers "F.Cu" "F.Mask" "F.Paste")
			(net "P12V_B")
		)
		(pad "3" smd rect
			(at 0.635 2.54)
			(size 0.635 1.651)
			(layers "F.Cu" "F.Mask" "F.Paste")
			(net "P12V_B")
		)
		(pad "4" smd rect
			(at 1.905 2.54)
			(size 0.635 1.651)
			(layers "F.Cu" "F.Mask" "F.Paste")
			(net "SW_HDD_N35")
		)
		(pad "5" smd rect
			(at 1.905 -2.54)
			(size 0.635 1.651)
			(layers "F.Cu" "F.Mask" "F.Paste")
			(net "P12V_HDD35")
		)
		(pad "6" smd rect
			(at 0.635 -2.54)
			(size 0.635 1.651)
			(layers "F.Cu" "F.Mask" "F.Paste")
			(net "P12V_HDD35")
		)
		(pad "7" smd rect
			(at -0.635 -2.54)
			(size 0.635 1.651)
			(layers "F.Cu" "F.Mask" "F.Paste")
			(net "P12V_HDD35")
		)
		(pad "8" smd rect
			(at -1.905 -2.54)
			(size 0.635 1.651)
			(layers "F.Cu" "F.Mask" "F.Paste")
			(net "P12V_HDD35")
		)
	)
	(footprint ""
		(layer "F.Cu")
		(at 396.367 -128.651 180)
		(property "Reference" "R538"
			(at 0 0 180)
			(layer "F.SilkS")
			(hide yes)
			(effects
				(font
					(size 1.27 1.27)
				)
			)
		)
		(property "Value" "1KR2F-3-GP"
			(at 0.064008 -3.993896 180)
			(unlocked yes)
			(layer "F.Fab")
			(hide yes)
			(effects
				(font
					(size 1.016 1.016)
					(thickness 0.1524)
				)
			)
		)
		(property "Device Type" "R402H16"
			(at 0.064008 -5.517896 180)
			(unlocked yes)
			(layer "F.Fab")
			(hide yes)
			(effects
				(font
					(size 1.016 1.016)
					(thickness 0.1524)
				)
			)
		)
		(duplicate_pad_numbers_are_jumpers no)
		(fp_line
			(start 0.508 -0.9398)
			(end -0.508 -0.9398)
			(stroke
				(width 0.1524)
				(type default)
			)
			(layer "F.SilkS")
		)
		(fp_line
			(start -0.508 -0.9398)
			(end -0.508 0.9398)
			(stroke
				(width 0.1524)
				(type default)
			)
			(layer "F.SilkS")
		)
		(fp_rect
			(start -0.508 0.9398)
			(end 0.508 -0.9398)
			(stroke
				(width 0)
				(type default)
			)
			(fill no)
			(layer "F.CrtYd")
		)
		(fp_rect
			(start -0.508 0.9398)
			(end 0.508 -0.9398)
			(stroke
				(width 0)
				(type default)
			)
			(fill no)
			(layer "F.Fab")
		)
		(pad "1" smd custom
			(at 0 -0.4445 180)
			(size 0.1397 0.1397)
			(layers "F.Cu" "F.Mask" "F.Paste")
			(net "P3V3_STBY_B")
			(options
				(clearance outline)
				(anchor circle)
			)
			(primitives
				(gr_poly
					(pts
						(arc
							(start -0.1778 -0.2794)
							(mid -0.249642 -0.249642)
							(end -0.2794 -0.1778)
						)
						(arc
							(start -0.2794 0.1778)
							(mid -0.249642 0.249642)
							(end -0.1778 0.2794)
						)
						(arc
							(start 0.1778 0.2794)
							(mid 0.249642 0.249642)
							(end 0.2794 0.1778)
						)
						(arc
							(start 0.2794 -0.1778)
							(mid 0.249642 -0.249642)
							(end 0.1778 -0.2794)
						)
					)
					(width 0)
					(fill yes)
				)
			)
		)
		(pad "2" smd custom
			(at 0 0.4445 180)
			(size 0.1397 0.1397)
			(layers "F.Cu" "F.Mask" "F.Paste")
			(net "SW_PWR_R_HDD20")
			(options
				(clearance outline)
				(anchor circle)
			)
			(primitives
				(gr_poly
					(pts
						(arc
							(start -0.1778 -0.2794)
							(mid -0.249642 -0.249642)
							(end -0.2794 -0.1778)
						)
						(arc
							(start -0.2794 0.1778)
							(mid -0.249642 0.249642)
							(end -0.1778 0.2794)
						)
						(arc
							(start 0.1778 0.2794)
							(mid 0.249642 0.249642)
							(end 0.2794 0.1778)
						)
						(arc
							(start 0.2794 -0.1778)
							(mid 0.249642 -0.249642)
							(end 0.1778 -0.2794)
						)
					)
					(width 0)
					(fill yes)
				)
			)
		)
	)
	(footprint ""
		(layer "F.Cu")
		(at 280.444448 -353.383342 90)
		(property "Reference" "R1074"
			(at 0 0 90)
			(layer "F.SilkS")
			(hide yes)
			(effects
				(font
					(size 1.27 1.27)
				)
			)
		)
		(property "Value" "4K7R2F-GP"
			(at 0.064008 -3.993896 90)
			(unlocked yes)
			(layer "F.Fab")
			(hide yes)
			(effects
				(font
					(size 1.016 1.016)
					(thickness 0.1524)
				)
			)
		)
		(property "Device Type" "R402H16"
			(at 0.064008 -5.517896 90)
			(unlocked yes)
			(layer "F.Fab")
			(hide yes)
			(effects
				(font
					(size 1.016 1.016)
					(thickness 0.1524)
				)
			)
		)
		(duplicate_pad_numbers_are_jumpers no)
		(fp_line
			(start 0.508 -0.9398)
			(end -0.508 -0.9398)
			(stroke
				(width 0.1524)
				(type default)
			)
			(layer "F.SilkS")
		)
		(fp_line
			(start -0.508 -0.9398)
			(end -0.508 0.9398)
			(stroke
				(width 0.1524)
				(type default)
			)
			(layer "F.SilkS")
		)
		(fp_rect
			(start -0.508 0.9398)
			(end 0.508 -0.9398)
			(stroke
				(width 0)
				(type default)
			)
			(fill no)
			(layer "F.CrtYd")
		)
		(fp_rect
			(start -0.508 0.9398)
			(end 0.508 -0.9398)
			(stroke
				(width 0)
				(type default)
			)
			(fill no)
			(layer "F.Fab")
		)
		(pad "1" smd custom
			(at 0 -0.4445 90)
			(size 0.1397 0.1397)
			(layers "F.Cu" "F.Mask" "F.Paste")
			(net "P3V3_STBY_B")
			(options
				(clearance outline)
				(anchor circle)
			)
			(primitives
				(gr_poly
					(pts
						(arc
							(start -0.1778 -0.2794)
							(mid -0.249642 -0.249642)
							(end -0.2794 -0.1778)
						)
						(arc
							(start -0.2794 0.1778)
							(mid -0.249642 0.249642)
							(end -0.1778 0.2794)
						)
						(arc
							(start 0.1778 0.2794)
							(mid 0.249642 0.249642)
							(end 0.2794 0.1778)
						)
						(arc
							(start 0.2794 -0.1778)
							(mid 0.249642 -0.249642)
							(end 0.1778 -0.2794)
						)
					)
					(width 0)
					(fill yes)
				)
			)
		)
		(pad "2" smd custom
			(at 0 0.4445 90)
			(size 0.1397 0.1397)
			(layers "F.Cu" "F.Mask" "F.Paste")
			(net "MAX31790_B_FAIL")
			(options
				(clearance outline)
				(anchor circle)
			)
			(primitives
				(gr_poly
					(pts
						(arc
							(start -0.1778 -0.2794)
							(mid -0.249642 -0.249642)
							(end -0.2794 -0.1778)
						)
						(arc
							(start -0.2794 0.1778)
							(mid -0.249642 0.249642)
							(end -0.1778 0.2794)
						)
						(arc
							(start 0.1778 0.2794)
							(mid 0.249642 0.249642)
							(end 0.2794 0.1778)
						)
						(arc
							(start 0.2794 -0.1778)
							(mid 0.249642 -0.249642)
							(end 0.1778 -0.2794)
						)
					)
					(width 0)
					(fill yes)
				)
			)
		)
	)
	(footprint ""
		(layer "F.Cu")
		(at 77.851 -265.684 -90)
		(property "Reference" "C60"
			(at 0 0 270)
			(layer "F.SilkS")
			(hide yes)
			(effects
				(font
					(size 1.27 1.27)
				)
			)
		)
		(property "Value" "SC4D7U25V5KX-1-GP"
			(at -0.0762 -6.1214 270)
			(unlocked yes)
			(layer "F.Fab")
			(hide yes)
			(effects
				(font
					(size 1.016 1.016)
					(thickness 0.1524)
				)
			)
		)
		(property "Device Type" "C805H58"
			(at -0.0762 -8.1534 270)
			(unlocked yes)
			(layer "F.Fab")
			(hide yes)
			(effects
				(font
					(size 1.016 1.016)
					(thickness 0.1524)
				)
			)
		)
		(duplicate_pad_numbers_are_jumpers no)
		(fp_line
			(start 0.635 0)
			(end -0.635 0)
			(stroke
				(width 0.508)
				(type default)
			)
			(layer "F.SilkS")
		)
		(fp_rect
			(start -0.9652 1.778)
			(end 0.9652 -1.778)
			(stroke
				(width 0)
				(type default)
			)
			(fill no)
			(layer "F.CrtYd")
		)
		(fp_poly
			(pts
				(xy -0.9652 -1.778) (xy 0.9652 -1.778) (xy 0.9652 1.778) (xy -0.9652 1.778)
			)
			(stroke
				(width 0)
				(type default)
			)
			(fill no)
			(layer "F.Fab")
		)
		(pad "1" smd rect
			(at 0 -0.9652 270)
			(size 1.397 1.143)
			(layers "F.Cu" "F.Mask" "F.Paste")
			(net "P12V_HDD2")
		)
		(pad "2" smd rect
			(at 0 0.9652 270)
			(size 1.397 1.143)
			(layers "F.Cu" "F.Mask" "F.Paste")
			(net "GND")
		)
	)
	(footprint ""
		(layer "F.Cu")
		(at 127.15875 -133.75005 -90)
		(property "Reference" "VIA32"
			(at 0 0 270)
			(layer "F.SilkS")
			(hide yes)
			(effects
				(font
					(size 1.27 1.27)
				)
			)
		)
		(property "Value" "100OHM-8L-2D36MM-L16-GP"
			(at -3.4036 -0.4572 270)
			(unlocked yes)
			(layer "F.Fab")
			(hide yes)
			(effects
				(font
					(size 1.016 1.016)
					(thickness 0.1524)
				)
			)
		)
		(property "Device Type" "VIA-PCIE-4P-427097"
			(at -3.4036 -1.9812 270)
			(unlocked yes)
			(layer "F.Fab")
			(hide yes)
			(effects
				(font
					(size 1.016 1.016)
					(thickness 0.1524)
				)
			)
		)
		(duplicate_pad_numbers_are_jumpers no)
		(fp_rect
			(start -2.1336 0.4826)
			(end 2.1336 -0.4826)
			(stroke
				(width 0)
				(type default)
			)
			(fill no)
			(layer "F.CrtYd")
		)
		(fp_rect
			(start -2.1336 0.4826)
			(end 2.1336 -0.4826)
			(stroke
				(width 0)
				(type default)
			)
			(fill no)
			(layer "F.Fab")
		)
		(pad "1" thru_hole circle
			(at -1.651 0 270)
			(size 0.508 0.508)
			(drill 0.254)
			(layers "*.Cu" "*.Mask")
			(remove_unused_layers no)
			(net "GND")
			(clearance 0.2286)
			(thermal_gap 0.2286)
		)
		(pad "2" thru_hole circle
			(at -0.635 0 270)
			(size 0.508 0.508)
			(drill 0.254)
			(layers "*.Cu" "*.Mask")
			(remove_unused_layers no)
			(net "PHY_DRV_B_TO_SCC_B_15_DP")
			(clearance 0.2286)
			(thermal_gap 0.2286)
		)
		(pad "3" thru_hole circle
			(at 0.635 0 270)
			(size 0.508 0.508)
			(drill 0.254)
			(layers "*.Cu" "*.Mask")
			(remove_unused_layers no)
			(net "PHY_DRV_B_TO_SCC_B_15_DN")
			(clearance 0.2286)
			(thermal_gap 0.2286)
		)
		(pad "4" thru_hole circle
			(at 1.651 0 270)
			(size 0.508 0.508)
			(drill 0.254)
			(layers "*.Cu" "*.Mask")
			(remove_unused_layers no)
			(net "GND")
			(clearance 0.2286)
			(thermal_gap 0.2286)
		)
	)
	(footprint ""
		(layer "F.Cu")
		(at 220.7006 -301.371 180)
		(property "Reference" "R509"
			(at 0 0 180)
			(layer "F.SilkS")
			(hide yes)
			(effects
				(font
					(size 1.27 1.27)
				)
			)
		)
		(property "Value" "10KR2F-2-GP"
			(at 0.064008 -3.993896 180)
			(unlocked yes)
			(layer "F.Fab")
			(hide yes)
			(effects
				(font
					(size 1.016 1.016)
					(thickness 0.1524)
				)
			)
		)
		(property "Device Type" "R402H16"
			(at 0.064008 -5.517896 180)
			(unlocked yes)
			(layer "F.Fab")
			(hide yes)
			(effects
				(font
					(size 1.016 1.016)
					(thickness 0.1524)
				)
			)
		)
		(duplicate_pad_numbers_are_jumpers no)
		(fp_line
			(start 0.508 -0.9398)
			(end -0.508 -0.9398)
			(stroke
				(width 0.1524)
				(type default)
			)
			(layer "F.SilkS")
		)
		(fp_line
			(start -0.508 -0.9398)
			(end -0.508 0.9398)
			(stroke
				(width 0.1524)
				(type default)
			)
			(layer "F.SilkS")
		)
		(fp_rect
			(start -0.508 0.9398)
			(end 0.508 -0.9398)
			(stroke
				(width 0)
				(type default)
			)
			(fill no)
			(layer "F.CrtYd")
		)
		(fp_rect
			(start -0.508 0.9398)
			(end 0.508 -0.9398)
			(stroke
				(width 0)
				(type default)
			)
			(fill no)
			(layer "F.Fab")
		)
		(pad "1" smd custom
			(at 0 -0.4445 180)
			(size 0.1397 0.1397)
			(layers "F.Cu" "F.Mask" "F.Paste")
			(net "P3V3_STBY_A")
			(options
				(clearance outline)
				(anchor circle)
			)
			(primitives
				(gr_poly
					(pts
						(arc
							(start -0.1778 -0.2794)
							(mid -0.249642 -0.249642)
							(end -0.2794 -0.1778)
						)
						(arc
							(start -0.2794 0.1778)
							(mid -0.249642 0.249642)
							(end -0.1778 0.2794)
						)
						(arc
							(start 0.1778 0.2794)
							(mid 0.249642 0.249642)
							(end 0.2794 0.1778)
						)
						(arc
							(start 0.2794 -0.1778)
							(mid 0.249642 -0.249642)
							(end 0.1778 -0.2794)
						)
					)
					(width 0)
					(fill yes)
				)
			)
		)
		(pad "2" smd custom
			(at 0 0.4445 180)
			(size 0.1397 0.1397)
			(layers "F.Cu" "F.Mask" "F.Paste")
			(net "FANTACH_A_OE")
			(options
				(clearance outline)
				(anchor circle)
			)
			(primitives
				(gr_poly
					(pts
						(arc
							(start -0.1778 -0.2794)
							(mid -0.249642 -0.249642)
							(end -0.2794 -0.1778)
						)
						(arc
							(start -0.2794 0.1778)
							(mid -0.249642 0.249642)
							(end -0.1778 0.2794)
						)
						(arc
							(start 0.1778 0.2794)
							(mid 0.249642 0.249642)
							(end 0.2794 0.1778)
						)
						(arc
							(start 0.2794 -0.1778)
							(mid 0.249642 -0.249642)
							(end 0.1778 -0.2794)
						)
					)
					(width 0)
					(fill yes)
				)
			)
		)
	)
	(footprint ""
		(layer "F.Cu")
		(at 323.545962 -99.717098 180)
		(property "Reference" "Q237"
			(at 0 0 180)
			(layer "F.SilkS")
			(hide yes)
			(effects
				(font
					(size 1.27 1.27)
				)
			)
		)
		(property "Value" "2N7002K-2-GP"
			(at 0.127 -8.9662 180)
			(unlocked yes)
			(layer "F.Fab")
			(hide yes)
			(effects
				(font
					(size 1.016 1.016)
					(thickness 0.1524)
				)
			)
		)
		(property "Device Type" "SOT23DGS2D4H44"
			(at 0.127 -10.4902 180)
			(unlocked yes)
			(layer "F.Fab")
			(hide yes)
			(effects
				(font
					(size 1.016 1.016)
					(thickness 0.1524)
				)
			)
		)
		(duplicate_pad_numbers_are_jumpers no)
		(fp_line
			(start 1.651 1.778)
			(end 1.651 -1.778)
			(stroke
				(width 0.1524)
				(type default)
			)
			(layer "F.SilkS")
		)
		(fp_line
			(start 1.651 -1.778)
			(end -1.651 -1.778)
			(stroke
				(width 0.1524)
				(type default)
			)
			(layer "F.SilkS")
		)
		(fp_line
			(start -1.651 1.778)
			(end 1.651 1.778)
			(stroke
				(width 0.1524)
				(type default)
			)
			(layer "F.SilkS")
		)
		(fp_line
			(start -1.651 -1.778)
			(end -1.651 1.778)
			(stroke
				(width 0.1524)
				(type default)
			)
			(layer "F.SilkS")
		)
		(fp_poly
			(pts
				(xy -1.778 1.8796) (xy -1.778 -1.8796) (xy 1.778 -1.8796) (xy 1.778 1.8796)
			)
			(stroke
				(width 0)
				(type default)
			)
			(fill no)
			(layer "F.CrtYd")
		)
		(fp_poly
			(pts
				(xy -1.778 1.8796) (xy -1.778 -1.8796) (xy 1.778 -1.8796) (xy 1.778 1.8796)
			)
			(stroke
				(width 0)
				(type default)
			)
			(fill no)
			(layer "F.Fab")
		)
		(pad "D" smd custom
			(at 0 -0.9525 180)
			(size 0.1905 0.1905)
			(layers "F.Cu" "F.Mask" "F.Paste")
			(net "FLT_HDD18_N")
			(options
				(clearance outline)
				(anchor circle)
			)
			(primitives
				(gr_poly
					(pts
						(arc
							(start -0.1778 0.5715)
							(mid -0.321484 0.511984)
							(end -0.381 0.3683)
						)
						(arc
							(start -0.381 -0.3683)
							(mid -0.321484 -0.511984)
							(end -0.1778 -0.5715)
						)
						(arc
							(start 0.1778 -0.5715)
							(mid 0.321484 -0.511984)
							(end 0.381 -0.3683)
						)
						(arc
							(start 0.381 0.3683)
							(mid 0.321484 0.511984)
							(end 0.1778 0.5715)
						)
					)
					(width 0)
					(fill yes)
				)
			)
		)
		(pad "G" smd custom
			(at -0.98425 0.9525 180)
			(size 0.1905 0.1905)
			(layers "F.Cu" "F.Mask" "F.Paste")
			(net "DRIVE_B_18_FLT_LED")
			(options
				(clearance outline)
				(anchor circle)
			)
			(primitives
				(gr_poly
					(pts
						(arc
							(start -0.1778 0.5715)
							(mid -0.321484 0.511984)
							(end -0.381 0.3683)
						)
						(arc
							(start -0.381 -0.3683)
							(mid -0.321484 -0.511984)
							(end -0.1778 -0.5715)
						)
						(arc
							(start 0.1778 -0.5715)
							(mid 0.321484 -0.511984)
							(end 0.381 -0.3683)
						)
						(arc
							(start 0.381 0.3683)
							(mid 0.321484 0.511984)
							(end 0.1778 0.5715)
						)
					)
					(width 0)
					(fill yes)
				)
			)
		)
		(pad "S" smd custom
			(at 0.98425 0.9525 180)
			(size 0.1905 0.1905)
			(layers "F.Cu" "F.Mask" "F.Paste")
			(net "GND")
			(options
				(clearance outline)
				(anchor circle)
			)
			(primitives
				(gr_poly
					(pts
						(arc
							(start -0.1778 0.5715)
							(mid -0.321484 0.511984)
							(end -0.381 0.3683)
						)
						(arc
							(start -0.381 -0.3683)
							(mid -0.321484 -0.511984)
							(end -0.1778 -0.5715)
						)
						(arc
							(start 0.1778 -0.5715)
							(mid 0.321484 -0.511984)
							(end 0.381 -0.3683)
						)
						(arc
							(start 0.381 0.3683)
							(mid 0.321484 0.511984)
							(end 0.1778 0.5715)
						)
					)
					(width 0)
					(fill yes)
				)
			)
		)
	)
	(footprint ""
		(layer "F.Cu")
		(at 210.93938 -247.88622 180)
		(property "Reference" "R37"
			(at 0 0 180)
			(layer "F.SilkS")
			(hide yes)
			(effects
				(font
					(size 1.27 1.27)
				)
			)
		)
		(property "Value" "4K7R2F-GP"
			(at 0.064008 -3.993896 180)
			(unlocked yes)
			(layer "F.Fab")
			(hide yes)
			(effects
				(font
					(size 1.016 1.016)
					(thickness 0.1524)
				)
			)
		)
		(property "Device Type" "R402H16"
			(at 0.064008 -5.517896 180)
			(unlocked yes)
			(layer "F.Fab")
			(hide yes)
			(effects
				(font
					(size 1.016 1.016)
					(thickness 0.1524)
				)
			)
		)
		(duplicate_pad_numbers_are_jumpers no)
		(fp_line
			(start 0.508 -0.9398)
			(end -0.508 -0.9398)
			(stroke
				(width 0.1524)
				(type default)
			)
			(layer "F.SilkS")
		)
		(fp_line
			(start -0.508 -0.9398)
			(end -0.508 0.9398)
			(stroke
				(width 0.1524)
				(type default)
			)
			(layer "F.SilkS")
		)
		(fp_rect
			(start -0.508 0.9398)
			(end 0.508 -0.9398)
			(stroke
				(width 0)
				(type default)
			)
			(fill no)
			(layer "F.CrtYd")
		)
		(fp_rect
			(start -0.508 0.9398)
			(end 0.508 -0.9398)
			(stroke
				(width 0)
				(type default)
			)
			(fill no)
			(layer "F.Fab")
		)
		(pad "1" smd custom
			(at 0 -0.4445 180)
			(size 0.1397 0.1397)
			(layers "F.Cu" "F.Mask" "F.Paste")
			(net "IO_EXP4_A1")
			(options
				(clearance outline)
				(anchor circle)
			)
			(primitives
				(gr_poly
					(pts
						(arc
							(start -0.1778 -0.2794)
							(mid -0.249642 -0.249642)
							(end -0.2794 -0.1778)
						)
						(arc
							(start -0.2794 0.1778)
							(mid -0.249642 0.249642)
							(end -0.1778 0.2794)
						)
						(arc
							(start 0.1778 0.2794)
							(mid 0.249642 0.249642)
							(end 0.2794 0.1778)
						)
						(arc
							(start 0.2794 -0.1778)
							(mid 0.249642 -0.249642)
							(end 0.1778 -0.2794)
						)
					)
					(width 0)
					(fill yes)
				)
			)
		)
		(pad "2" smd custom
			(at 0 0.4445 180)
			(size 0.1397 0.1397)
			(layers "F.Cu" "F.Mask" "F.Paste")
			(net "GND")
			(options
				(clearance outline)
				(anchor circle)
			)
			(primitives
				(gr_poly
					(pts
						(arc
							(start -0.1778 -0.2794)
							(mid -0.249642 -0.249642)
							(end -0.2794 -0.1778)
						)
						(arc
							(start -0.2794 0.1778)
							(mid -0.249642 0.249642)
							(end -0.1778 0.2794)
						)
						(arc
							(start 0.1778 0.2794)
							(mid 0.249642 0.249642)
							(end 0.2794 0.1778)
						)
						(arc
							(start 0.2794 -0.1778)
							(mid 0.249642 -0.249642)
							(end 0.1778 -0.2794)
						)
					)
					(width 0)
					(fill yes)
				)
			)
		)
	)
	(footprint ""
		(layer "F.Cu")
		(at 160.485582 -129.99085 90)
		(property "Reference" "VIA33"
			(at 0 0 90)
			(layer "F.SilkS")
			(hide yes)
			(effects
				(font
					(size 1.27 1.27)
				)
			)
		)
		(property "Value" "100OHM-8L-2D36MM-L18-GP"
			(at 3.8989 0.5715 90)
			(unlocked yes)
			(layer "F.Fab")
			(hide yes)
			(effects
				(font
					(size 1.016 1.016)
					(thickness 0.1524)
				)
			)
		)
		(property "Device Type" "VIA-PCIE-4P-414097"
			(at 3.8989 -0.9525 90)
			(unlocked yes)
			(layer "F.Fab")
			(hide yes)
			(effects
				(font
					(size 1.016 1.016)
					(thickness 0.1524)
				)
			)
		)
		(duplicate_pad_numbers_are_jumpers no)
		(fp_rect
			(start -2.0701 0.4826)
			(end 2.0701 -0.4826)
			(stroke
				(width 0)
				(type default)
			)
			(fill no)
			(layer "F.CrtYd")
		)
		(fp_rect
			(start -2.0701 0.4826)
			(end 2.0701 -0.4826)
			(stroke
				(width 0)
				(type default)
			)
			(fill no)
			(layer "F.Fab")
		)
		(pad "1" thru_hole circle
			(at -1.5875 0 90)
			(size 0.508 0.508)
			(drill 0.254)
			(layers "*.Cu" "*.Mask")
			(remove_unused_layers no)
			(net "GND")
			(clearance 0.2286)
			(thermal_gap 0.2286)
		)
		(pad "2" thru_hole circle
			(at -0.5715 0 90)
			(size 0.508 0.508)
			(drill 0.254)
			(layers "*.Cu" "*.Mask")
			(remove_unused_layers no)
			(net "PHY_SCC_B_TO_DRV_B_16_DP")
			(clearance 0.2286)
			(thermal_gap 0.2286)
		)
		(pad "3" thru_hole circle
			(at 0.5715 0 90)
			(size 0.508 0.508)
			(drill 0.254)
			(layers "*.Cu" "*.Mask")
			(remove_unused_layers no)
			(net "PHY_SCC_B_TO_DRV_B_16_DN")
			(clearance 0.2286)
			(thermal_gap 0.2286)
		)
		(pad "4" thru_hole circle
			(at 1.5875 0 90)
			(size 0.508 0.508)
			(drill 0.254)
			(layers "*.Cu" "*.Mask")
			(remove_unused_layers no)
			(net "GND")
			(clearance 0.2286)
			(thermal_gap 0.2286)
		)
	)
	(footprint ""
		(layer "F.Cu")
		(at 375.004076 -99.756976 180)
		(property "Reference" "Q239"
			(at 0 0 180)
			(layer "F.SilkS")
			(hide yes)
			(effects
				(font
					(size 1.27 1.27)
				)
			)
		)
		(property "Value" "2N7002K-2-GP"
			(at 0.127 -8.9662 180)
			(unlocked yes)
			(layer "F.Fab")
			(hide yes)
			(effects
				(font
					(size 1.016 1.016)
					(thickness 0.1524)
				)
			)
		)
		(property "Device Type" "SOT23DGS2D4H44"
			(at 0.127 -10.4902 180)
			(unlocked yes)
			(layer "F.Fab")
			(hide yes)
			(effects
				(font
					(size 1.016 1.016)
					(thickness 0.1524)
				)
			)
		)
		(duplicate_pad_numbers_are_jumpers no)
		(fp_line
			(start 1.651 1.778)
			(end 1.651 -1.778)
			(stroke
				(width 0.1524)
				(type default)
			)
			(layer "F.SilkS")
		)
		(fp_line
			(start 1.651 -1.778)
			(end -1.651 -1.778)
			(stroke
				(width 0.1524)
				(type default)
			)
			(layer "F.SilkS")
		)
		(fp_line
			(start -1.651 1.778)
			(end 1.651 1.778)
			(stroke
				(width 0.1524)
				(type default)
			)
			(layer "F.SilkS")
		)
		(fp_line
			(start -1.651 -1.778)
			(end -1.651 1.778)
			(stroke
				(width 0.1524)
				(type default)
			)
			(layer "F.SilkS")
		)
		(fp_poly
			(pts
				(xy -1.778 1.8796) (xy -1.778 -1.8796) (xy 1.778 -1.8796) (xy 1.778 1.8796)
			)
			(stroke
				(width 0)
				(type default)
			)
			(fill no)
			(layer "F.CrtYd")
		)
		(fp_poly
			(pts
				(xy -1.778 1.8796) (xy -1.778 -1.8796) (xy 1.778 -1.8796) (xy 1.778 1.8796)
			)
			(stroke
				(width 0)
				(type default)
			)
			(fill no)
			(layer "F.Fab")
		)
		(pad "D" smd custom
			(at 0 -0.9525 180)
			(size 0.1905 0.1905)
			(layers "F.Cu" "F.Mask" "F.Paste")
			(net "FLT_HDD20_N")
			(options
				(clearance outline)
				(anchor circle)
			)
			(primitives
				(gr_poly
					(pts
						(arc
							(start -0.1778 0.5715)
							(mid -0.321484 0.511984)
							(end -0.381 0.3683)
						)
						(arc
							(start -0.381 -0.3683)
							(mid -0.321484 -0.511984)
							(end -0.1778 -0.5715)
						)
						(arc
							(start 0.1778 -0.5715)
							(mid 0.321484 -0.511984)
							(end 0.381 -0.3683)
						)
						(arc
							(start 0.381 0.3683)
							(mid 0.321484 0.511984)
							(end 0.1778 0.5715)
						)
					)
					(width 0)
					(fill yes)
				)
			)
		)
		(pad "G" smd custom
			(at -0.98425 0.9525 180)
			(size 0.1905 0.1905)
			(layers "F.Cu" "F.Mask" "F.Paste")
			(net "DRIVE_B_20_FLT_LED")
			(options
				(clearance outline)
				(anchor circle)
			)
			(primitives
				(gr_poly
					(pts
						(arc
							(start -0.1778 0.5715)
							(mid -0.321484 0.511984)
							(end -0.381 0.3683)
						)
						(arc
							(start -0.381 -0.3683)
							(mid -0.321484 -0.511984)
							(end -0.1778 -0.5715)
						)
						(arc
							(start 0.1778 -0.5715)
							(mid 0.321484 -0.511984)
							(end 0.381 -0.3683)
						)
						(arc
							(start 0.381 0.3683)
							(mid 0.321484 0.511984)
							(end 0.1778 0.5715)
						)
					)
					(width 0)
					(fill yes)
				)
			)
		)
		(pad "S" smd custom
			(at 0.98425 0.9525 180)
			(size 0.1905 0.1905)
			(layers "F.Cu" "F.Mask" "F.Paste")
			(net "GND")
			(options
				(clearance outline)
				(anchor circle)
			)
			(primitives
				(gr_poly
					(pts
						(arc
							(start -0.1778 0.5715)
							(mid -0.321484 0.511984)
							(end -0.381 0.3683)
						)
						(arc
							(start -0.381 -0.3683)
							(mid -0.321484 -0.511984)
							(end -0.1778 -0.5715)
						)
						(arc
							(start 0.1778 -0.5715)
							(mid 0.321484 -0.511984)
							(end 0.381 -0.3683)
						)
						(arc
							(start 0.381 0.3683)
							(mid 0.321484 0.511984)
							(end 0.1778 0.5715)
						)
					)
					(width 0)
					(fill yes)
				)
			)
		)
	)
	(footprint ""
		(layer "F.Cu")
		(at 394.589 -160.02 180)
		(property "Reference" "C294"
			(at 0 0 180)
			(layer "F.SilkS")
			(hide yes)
			(effects
				(font
					(size 1.27 1.27)
				)
			)
		)
		(property "Value" "SC4D7U25V5KX-1-GP"
			(at -0.0762 -6.1214 180)
			(unlocked yes)
			(layer "F.Fab")
			(hide yes)
			(effects
				(font
					(size 1.016 1.016)
					(thickness 0.1524)
				)
			)
		)
		(property "Device Type" "C805H58"
			(at -0.0762 -8.1534 180)
			(unlocked yes)
			(layer "F.Fab")
			(hide yes)
			(effects
				(font
					(size 1.016 1.016)
					(thickness 0.1524)
				)
			)
		)
		(duplicate_pad_numbers_are_jumpers no)
		(fp_line
			(start 0.635 0)
			(end -0.635 0)
			(stroke
				(width 0.508)
				(type default)
			)
			(layer "F.SilkS")
		)
		(fp_rect
			(start -0.9652 1.778)
			(end 0.9652 -1.778)
			(stroke
				(width 0)
				(type default)
			)
			(fill no)
			(layer "F.CrtYd")
		)
		(fp_poly
			(pts
				(xy -0.9652 -1.778) (xy 0.9652 -1.778) (xy 0.9652 1.778) (xy -0.9652 1.778)
			)
			(stroke
				(width 0)
				(type default)
			)
			(fill no)
			(layer "F.Fab")
		)
		(pad "1" smd rect
			(at 0 -0.9652 180)
			(size 1.397 1.143)
			(layers "F.Cu" "F.Mask" "F.Paste")
			(net "P12V_HDD20")
		)
		(pad "2" smd rect
			(at 0 0.9652 180)
			(size 1.397 1.143)
			(layers "F.Cu" "F.Mask" "F.Paste")
			(net "GND")
		)
	)
	(footprint ""
		(layer "F.Cu")
		(at 46.355 -145.796)
		(property "Reference" "Q54"
			(at 0 0 0)
			(layer "F.SilkS")
			(hide yes)
			(effects
				(font
					(size 1.27 1.27)
				)
			)
		)
		(property "Value" "AO4407AL-GP"
			(at -3.707384 -1.5367 0)
			(unlocked yes)
			(layer "F.Fab")
			(hide yes)
			(effects
				(font
					(size 1.016 1.016)
					(thickness 0.1524)
				)
			)
		)
		(property "Device Type" "SOIC8H69"
			(at -3.707384 -3.0607 0)
			(unlocked yes)
			(layer "F.Fab")
			(hide yes)
			(effects
				(font
					(size 1.016 1.016)
					(thickness 0.1524)
				)
			)
		)
		(duplicate_pad_numbers_are_jumpers no)
		(fp_line
			(start -2.7432 -1.4224)
			(end -2.7432 1.4224)
			(stroke
				(width 0.1524)
				(type default)
			)
			(layer "F.SilkS")
		)
		(fp_line
			(start -2.7432 1.4224)
			(end -2.6416 1.4224)
			(stroke
				(width 0.1524)
				(type default)
			)
			(layer "F.SilkS")
		)
		(fp_line
			(start -2.7432 1.4224)
			(end 2.1336 1.4224)
			(stroke
				(width 0.1524)
				(type default)
			)
			(layer "F.SilkS")
		)
		(fp_line
			(start -2.7178 -0.508)
			(end -2.1844 -0.0508)
			(stroke
				(width 0.1524)
				(type default)
			)
			(layer "F.SilkS")
		)
		(fp_line
			(start -2.6289 3.4417)
			(end -2.6289 1.4732)
			(stroke
				(width 0.381)
				(type default)
			)
			(layer "F.SilkS")
		)
		(fp_line
			(start -2.1844 -0.0508)
			(end -2.7178 0.508)
			(stroke
				(width 0.1524)
				(type default)
			)
			(layer "F.SilkS")
		)
		(fp_line
			(start 2.1336 -1.4224)
			(end -2.7432 -1.4224)
			(stroke
				(width 0.1524)
				(type default)
			)
			(layer "F.SilkS")
		)
		(fp_line
			(start 2.1336 1.4224)
			(end 2.1336 -1.4224)
			(stroke
				(width 0.1524)
				(type default)
			)
			(layer "F.SilkS")
		)
		(fp_poly
			(pts
				(xy -2.2098 -1.4224) (xy -2.2098 1.4224) (xy 2.2098 1.4224) (xy 2.2098 -1.4224)
			)
			(stroke
				(width 0)
				(type default)
			)
			(fill yes)
			(layer "F.SilkS")
		)
		(fp_rect
			(start -2.450084 2.999994)
			(end 2.450084 -2.999994)
			(stroke
				(width 0)
				(type default)
			)
			(fill no)
			(layer "F.CrtYd")
		)
		(fp_poly
			(pts
				(xy -2.8194 3.6322) (xy -2.8194 -3.6322) (xy 2.8194 -3.6322) (xy 2.8194 1.18364) (xy 2.450084 1.18364)
				(xy 2.450084 -2.999994) (xy -2.450084 -2.999994) (xy -2.450084 2.999994) (xy 2.450084 2.999994)
				(xy 2.450084 1.18618) (xy 2.8194 1.18618) (xy 2.8194 3.6322)
			)
			(stroke
				(width 0)
				(type default)
			)
			(fill no)
			(layer "F.CrtYd")
		)
		(fp_rect
			(start -2.8194 3.6322)
			(end 2.8194 -3.6322)
			(stroke
				(width 0)
				(type default)
			)
			(fill no)
			(layer "F.Fab")
		)
		(pad "1" smd rect
			(at -1.905 2.54)
			(size 0.635 1.651)
			(layers "F.Cu" "F.Mask" "F.Paste")
			(net "P12V_B")
		)
		(pad "2" smd rect
			(at -0.635 2.54)
			(size 0.635 1.651)
			(layers "F.Cu" "F.Mask" "F.Paste")
			(net "P12V_B")
		)
		(pad "3" smd rect
			(at 0.635 2.54)
			(size 0.635 1.651)
			(layers "F.Cu" "F.Mask" "F.Paste")
			(net "P12V_B")
		)
		(pad "4" smd rect
			(at 1.905 2.54)
			(size 0.635 1.651)
			(layers "F.Cu" "F.Mask" "F.Paste")
			(net "SW_HDD_N13")
		)
		(pad "5" smd rect
			(at 1.905 -2.54)
			(size 0.635 1.651)
			(layers "F.Cu" "F.Mask" "F.Paste")
			(net "P12V_HDD13")
		)
		(pad "6" smd rect
			(at 0.635 -2.54)
			(size 0.635 1.651)
			(layers "F.Cu" "F.Mask" "F.Paste")
			(net "P12V_HDD13")
		)
		(pad "7" smd rect
			(at -0.635 -2.54)
			(size 0.635 1.651)
			(layers "F.Cu" "F.Mask" "F.Paste")
			(net "P12V_HDD13")
		)
		(pad "8" smd rect
			(at -1.905 -2.54)
			(size 0.635 1.651)
			(layers "F.Cu" "F.Mask" "F.Paste")
			(net "P12V_HDD13")
		)
	)
	(footprint ""
		(layer "F.Cu")
		(at 461.80375 -102.503986 -90)
		(property "Reference" "R487"
			(at 0 0 270)
			(layer "F.SilkS")
			(hide yes)
			(effects
				(font
					(size 1.27 1.27)
				)
			)
		)
		(property "Value" "4K7R2F-GP"
			(at 0.064008 -3.993896 270)
			(unlocked yes)
			(layer "F.Fab")
			(hide yes)
			(effects
				(font
					(size 1.016 1.016)
					(thickness 0.1524)
				)
			)
		)
		(property "Device Type" "R402H16"
			(at 0.064008 -5.517896 270)
			(unlocked yes)
			(layer "F.Fab")
			(hide yes)
			(effects
				(font
					(size 1.016 1.016)
					(thickness 0.1524)
				)
			)
		)
		(duplicate_pad_numbers_are_jumpers no)
		(fp_line
			(start -0.508 -0.9398)
			(end -0.508 0.9398)
			(stroke
				(width 0.1524)
				(type default)
			)
			(layer "F.SilkS")
		)
		(fp_line
			(start 0.508 -0.9398)
			(end -0.508 -0.9398)
			(stroke
				(width 0.1524)
				(type default)
			)
			(layer "F.SilkS")
		)
		(fp_rect
			(start -0.508 0.9398)
			(end 0.508 -0.9398)
			(stroke
				(width 0)
				(type default)
			)
			(fill no)
			(layer "F.CrtYd")
		)
		(fp_rect
			(start -0.508 0.9398)
			(end 0.508 -0.9398)
			(stroke
				(width 0)
				(type default)
			)
			(fill no)
			(layer "F.Fab")
		)
		(pad "1" smd custom
			(at 0 -0.4445 270)
			(size 0.1397 0.1397)
			(layers "F.Cu" "F.Mask" "F.Paste")
			(net "DRIVE_B_23_FLT_LED")
			(options
				(clearance outline)
				(anchor circle)
			)
			(primitives
				(gr_poly
					(pts
						(arc
							(start -0.1778 -0.2794)
							(mid -0.249642 -0.249642)
							(end -0.2794 -0.1778)
						)
						(arc
							(start -0.2794 0.1778)
							(mid -0.249642 0.249642)
							(end -0.1778 0.2794)
						)
						(arc
							(start 0.1778 0.2794)
							(mid 0.249642 0.249642)
							(end 0.2794 0.1778)
						)
						(arc
							(start 0.2794 -0.1778)
							(mid 0.249642 -0.249642)
							(end 0.1778 -0.2794)
						)
					)
					(width 0)
					(fill yes)
				)
			)
		)
		(pad "2" smd custom
			(at 0 0.4445 270)
			(size 0.1397 0.1397)
			(layers "F.Cu" "F.Mask" "F.Paste")
			(net "GND")
			(options
				(clearance outline)
				(anchor circle)
			)
			(primitives
				(gr_poly
					(pts
						(arc
							(start -0.1778 -0.2794)
							(mid -0.249642 -0.249642)
							(end -0.2794 -0.1778)
						)
						(arc
							(start -0.2794 0.1778)
							(mid -0.249642 0.249642)
							(end -0.1778 0.2794)
						)
						(arc
							(start 0.1778 0.2794)
							(mid 0.249642 0.249642)
							(end 0.2794 0.1778)
						)
						(arc
							(start 0.2794 -0.1778)
							(mid 0.249642 -0.249642)
							(end 0.1778 -0.2794)
						)
					)
					(width 0)
					(fill yes)
				)
			)
		)
	)
	(footprint ""
		(layer "F.Cu")
		(at 136.457436 -362.795566 180)
		(property "Reference" "C525"
			(at 0 0 180)
			(layer "F.SilkS")
			(hide yes)
			(effects
				(font
					(size 1.27 1.27)
				)
			)
		)
		(property "Value" "SC22U25V0MX-2-GP"
			(at -0.00254 -4.78536 180)
			(unlocked yes)
			(layer "F.Fab")
			(hide yes)
			(effects
				(font
					(size 1.016 1.016)
					(thickness 0.1524)
				)
			)
		)
		(property "Device Type" "C1210H111"
			(at -0.00254 -6.38048 180)
			(unlocked yes)
			(layer "F.Fab")
			(hide yes)
			(effects
				(font
					(size 1.016 1.016)
					(thickness 0.1524)
				)
			)
		)
		(duplicate_pad_numbers_are_jumpers no)
		(fp_line
			(start 1.5748 2.3368)
			(end 1.5748 0.762)
			(stroke
				(width 0.1524)
				(type default)
			)
			(layer "F.SilkS")
		)
		(fp_line
			(start 1.5748 -0.762)
			(end 1.5748 -2.3368)
			(stroke
				(width 0.1524)
				(type default)
			)
			(layer "F.SilkS")
		)
		(fp_line
			(start 1.5748 -2.3368)
			(end -1.5748 -2.3368)
			(stroke
				(width 0.1524)
				(type default)
			)
			(layer "F.SilkS")
		)
		(fp_line
			(start -1.5748 2.3368)
			(end 1.5748 2.3368)
			(stroke
				(width 0.1524)
				(type default)
			)
			(layer "F.SilkS")
		)
		(fp_line
			(start -1.5748 0.762)
			(end -1.5748 2.3368)
			(stroke
				(width 0.1524)
				(type default)
			)
			(layer "F.SilkS")
		)
		(fp_line
			(start -1.5748 -2.3368)
			(end -1.5748 -0.762)
			(stroke
				(width 0.1524)
				(type default)
			)
			(layer "F.SilkS")
		)
		(fp_rect
			(start -1.651 2.413)
			(end 1.651 -2.413)
			(stroke
				(width 0)
				(type default)
			)
			(fill no)
			(layer "F.CrtYd")
		)
		(fp_poly
			(pts
				(xy 1.651 2.413) (xy 1.651 -2.413) (xy -1.651 -2.413) (xy -1.651 2.413)
			)
			(stroke
				(width 0)
				(type default)
			)
			(fill no)
			(layer "F.Fab")
		)
		(pad "1" smd rect
			(at 0 -1.4732 180)
			(size 2.794 1.397)
			(layers "F.Cu" "F.Mask" "F.Paste")
			(net "P12V_FAN1")
		)
		(pad "2" smd rect
			(at 0 1.4732 180)
			(size 2.794 1.397)
			(layers "F.Cu" "F.Mask" "F.Paste")
			(net "GND")
		)
	)
	(footprint ""
		(layer "F.Cu")
		(at 14.467586 -97.416112 -90)
		(property "Reference" "R341"
			(at 0 0 270)
			(layer "F.SilkS")
			(hide yes)
			(effects
				(font
					(size 1.27 1.27)
				)
			)
		)
		(property "Value" "4K7R2F-GP"
			(at 0.064008 -3.993896 270)
			(unlocked yes)
			(layer "F.Fab")
			(hide yes)
			(effects
				(font
					(size 1.016 1.016)
					(thickness 0.1524)
				)
			)
		)
		(property "Device Type" "R402H16"
			(at 0.064008 -5.517896 270)
			(unlocked yes)
			(layer "F.Fab")
			(hide yes)
			(effects
				(font
					(size 1.016 1.016)
					(thickness 0.1524)
				)
			)
		)
		(duplicate_pad_numbers_are_jumpers no)
		(fp_line
			(start -0.508 -0.9398)
			(end -0.508 0.9398)
			(stroke
				(width 0.1524)
				(type default)
			)
			(layer "F.SilkS")
		)
		(fp_line
			(start 0.508 -0.9398)
			(end -0.508 -0.9398)
			(stroke
				(width 0.1524)
				(type default)
			)
			(layer "F.SilkS")
		)
		(fp_rect
			(start -0.508 0.9398)
			(end 0.508 -0.9398)
			(stroke
				(width 0)
				(type default)
			)
			(fill no)
			(layer "F.CrtYd")
		)
		(fp_rect
			(start -0.508 0.9398)
			(end 0.508 -0.9398)
			(stroke
				(width 0)
				(type default)
			)
			(fill no)
			(layer "F.Fab")
		)
		(pad "1" smd custom
			(at 0 -0.4445 270)
			(size 0.1397 0.1397)
			(layers "F.Cu" "F.Mask" "F.Paste")
			(net "DRIVE_B_12_ACT")
			(options
				(clearance outline)
				(anchor circle)
			)
			(primitives
				(gr_poly
					(pts
						(arc
							(start -0.1778 -0.2794)
							(mid -0.249642 -0.249642)
							(end -0.2794 -0.1778)
						)
						(arc
							(start -0.2794 0.1778)
							(mid -0.249642 0.249642)
							(end -0.1778 0.2794)
						)
						(arc
							(start 0.1778 0.2794)
							(mid 0.249642 0.249642)
							(end 0.2794 0.1778)
						)
						(arc
							(start 0.2794 -0.1778)
							(mid 0.249642 -0.249642)
							(end 0.1778 -0.2794)
						)
					)
					(width 0)
					(fill yes)
				)
			)
		)
		(pad "2" smd custom
			(at 0 0.4445 270)
			(size 0.1397 0.1397)
			(layers "F.Cu" "F.Mask" "F.Paste")
			(net "GND")
			(options
				(clearance outline)
				(anchor circle)
			)
			(primitives
				(gr_poly
					(pts
						(arc
							(start -0.1778 -0.2794)
							(mid -0.249642 -0.249642)
							(end -0.2794 -0.1778)
						)
						(arc
							(start -0.2794 0.1778)
							(mid -0.249642 0.249642)
							(end -0.1778 0.2794)
						)
						(arc
							(start 0.1778 0.2794)
							(mid 0.249642 0.249642)
							(end 0.2794 0.1778)
						)
						(arc
							(start 0.2794 -0.1778)
							(mid 0.249642 -0.249642)
							(end 0.1778 -0.2794)
						)
					)
					(width 0)
					(fill yes)
				)
			)
		)
	)
	(footprint ""
		(layer "F.Cu")
		(at 244.348 -215.265)
		(property "Reference" "R86"
			(at 0 0 0)
			(layer "F.SilkS")
			(hide yes)
			(effects
				(font
					(size 1.27 1.27)
				)
			)
		)
		(property "Value" "4K7R2F-GP"
			(at 0.064008 -3.993896 0)
			(unlocked yes)
			(layer "F.Fab")
			(hide yes)
			(effects
				(font
					(size 1.016 1.016)
					(thickness 0.1524)
				)
			)
		)
		(property "Device Type" "R402H16"
			(at 0.064008 -5.517896 0)
			(unlocked yes)
			(layer "F.Fab")
			(hide yes)
			(effects
				(font
					(size 1.016 1.016)
					(thickness 0.1524)
				)
			)
		)
		(duplicate_pad_numbers_are_jumpers no)
		(fp_line
			(start -0.508 -0.9398)
			(end -0.508 0.9398)
			(stroke
				(width 0.1524)
				(type default)
			)
			(layer "F.SilkS")
		)
		(fp_line
			(start 0.508 -0.9398)
			(end -0.508 -0.9398)
			(stroke
				(width 0.1524)
				(type default)
			)
			(layer "F.SilkS")
		)
		(fp_rect
			(start -0.508 0.9398)
			(end 0.508 -0.9398)
			(stroke
				(width 0)
				(type default)
			)
			(fill no)
			(layer "F.CrtYd")
		)
		(fp_rect
			(start -0.508 0.9398)
			(end 0.508 -0.9398)
			(stroke
				(width 0)
				(type default)
			)
			(fill no)
			(layer "F.Fab")
		)
		(pad "1" smd custom
			(at 0 -0.4445)
			(size 0.1397 0.1397)
			(layers "F.Cu" "F.Mask" "F.Paste")
			(net "IO_EXP3_A2")
			(options
				(clearance outline)
				(anchor circle)
			)
			(primitives
				(gr_poly
					(pts
						(arc
							(start -0.1778 -0.2794)
							(mid -0.249642 -0.249642)
							(end -0.2794 -0.1778)
						)
						(arc
							(start -0.2794 0.1778)
							(mid -0.249642 0.249642)
							(end -0.1778 0.2794)
						)
						(arc
							(start 0.1778 0.2794)
							(mid 0.249642 0.249642)
							(end 0.2794 0.1778)
						)
						(arc
							(start 0.2794 -0.1778)
							(mid 0.249642 -0.249642)
							(end 0.1778 -0.2794)
						)
					)
					(width 0)
					(fill yes)
				)
			)
		)
		(pad "2" smd custom
			(at 0 0.4445)
			(size 0.1397 0.1397)
			(layers "F.Cu" "F.Mask" "F.Paste")
			(net "GND")
			(options
				(clearance outline)
				(anchor circle)
			)
			(primitives
				(gr_poly
					(pts
						(arc
							(start -0.1778 -0.2794)
							(mid -0.249642 -0.249642)
							(end -0.2794 -0.1778)
						)
						(arc
							(start -0.2794 0.1778)
							(mid -0.249642 0.249642)
							(end -0.1778 0.2794)
						)
						(arc
							(start 0.1778 0.2794)
							(mid 0.249642 0.249642)
							(end 0.2794 0.1778)
						)
						(arc
							(start 0.2794 -0.1778)
							(mid 0.249642 -0.249642)
							(end 0.1778 -0.2794)
						)
					)
					(width 0)
					(fill yes)
				)
			)
		)
	)
	(footprint ""
		(layer "F.Cu")
		(at 321.634612 -244.660674 -90)
		(property "Reference" "C107"
			(at 0 0 270)
			(layer "F.SilkS")
			(hide yes)
			(effects
				(font
					(size 1.27 1.27)
				)
			)
		)
		(property "Value" "SCD01U16V1KX-GP"
			(at -2.8321 -1.7399 270)
			(unlocked yes)
			(layer "F.Fab")
			(hide yes)
			(effects
				(font
					(size 1.016 1.016)
					(thickness 0.1524)
				)
			)
		)
		(property "Device Type" "C0201H13"
			(at -2.8321 -3.2639 270)
			(unlocked yes)
			(layer "F.Fab")
			(hide yes)
			(effects
				(font
					(size 1.016 1.016)
					(thickness 0.1524)
				)
			)
		)
		(duplicate_pad_numbers_are_jumpers no)
		(fp_rect
			(start -0.2794 0.6477)
			(end 0.2794 -0.6477)
			(stroke
				(width 0)
				(type default)
			)
			(fill no)
			(layer "F.CrtYd")
		)
		(fp_rect
			(start -0.2794 0.6477)
			(end 0.2794 -0.6477)
			(stroke
				(width 0)
				(type default)
			)
			(fill no)
			(layer "F.Fab")
		)
		(pad "1" smd custom
			(at 0 -0.2794 270)
			(size 0.0762 0.0762)
			(layers "F.Cu" "F.Mask" "F.Paste")
			(net "SAS_HDD_RX_P6")
			(options
				(clearance outline)
				(anchor circle)
			)
			(primitives
				(gr_poly
					(pts
						(arc
							(start 0.1524 -0.127)
							(mid 0.137521 -0.162921)
							(end 0.1016 -0.1778)
						)
						(arc
							(start -0.1016 -0.1778)
							(mid -0.137521 -0.162921)
							(end -0.1524 -0.127)
						)
						(arc
							(start -0.1524 0.127)
							(mid -0.137521 0.162921)
							(end -0.1016 0.1778)
						)
						(arc
							(start 0.1016 0.1778)
							(mid 0.137521 0.162921)
							(end 0.1524 0.127)
						)
					)
					(width 0)
					(fill yes)
				)
			)
		)
		(pad "2" smd custom
			(at 0 0.2794 270)
			(size 0.0762 0.0762)
			(layers "F.Cu" "F.Mask" "F.Paste")
			(net "PHY_SCC_B_TO_DRV_B_6_DP")
			(options
				(clearance outline)
				(anchor circle)
			)
			(primitives
				(gr_poly
					(pts
						(arc
							(start 0.1524 -0.127)
							(mid 0.137521 -0.162921)
							(end 0.1016 -0.1778)
						)
						(arc
							(start -0.1016 -0.1778)
							(mid -0.137521 -0.162921)
							(end -0.1524 -0.127)
						)
						(arc
							(start -0.1524 0.127)
							(mid -0.137521 0.162921)
							(end -0.1016 0.1778)
						)
						(arc
							(start 0.1016 0.1778)
							(mid 0.137521 0.162921)
							(end 0.1524 0.127)
						)
					)
					(width 0)
					(fill yes)
				)
			)
		)
	)
	(footprint ""
		(layer "F.Cu")
		(at 143.256 -214.249)
		(property "Reference" "R268"
			(at 0 0 0)
			(layer "F.SilkS")
			(hide yes)
			(effects
				(font
					(size 1.27 1.27)
				)
			)
		)
		(property "Value" "130R3F-GP"
			(at -0.0254 -2.5146 0)
			(unlocked yes)
			(layer "F.Fab")
			(hide yes)
			(effects
				(font
					(size 1.016 1.016)
					(thickness 0.1524)
				)
			)
		)
		(property "Device Type" "R603H22"
			(at -0.0254 -4.0386 0)
			(unlocked yes)
			(layer "F.Fab")
			(hide yes)
			(effects
				(font
					(size 1.016 1.016)
					(thickness 0.1524)
				)
			)
		)
		(duplicate_pad_numbers_are_jumpers no)
		(fp_line
			(start -0.4826 0)
			(end -0.2032 0)
			(stroke
				(width 0.2032)
				(type default)
			)
			(layer "F.SilkS")
		)
		(fp_line
			(start 0.2032 0)
			(end 0.4826 0)
			(stroke
				(width 0.2032)
				(type default)
			)
			(layer "F.SilkS")
		)
		(fp_rect
			(start -0.5842 1.3335)
			(end 0.5842 -1.3335)
			(stroke
				(width 0)
				(type default)
			)
			(fill no)
			(layer "F.CrtYd")
		)
		(fp_rect
			(start -0.5842 1.3335)
			(end 0.5842 -1.3335)
			(stroke
				(width 0)
				(type default)
			)
			(fill no)
			(layer "F.Fab")
		)
		(pad "1" smd custom
			(at 0 -0.762)
			(size 0.2159 0.2159)
			(layers "F.Cu" "F.Mask" "F.Paste")
			(net "P5V_B_1")
			(options
				(clearance outline)
				(anchor circle)
			)
			(primitives
				(gr_poly
					(pts
						(arc
							(start -0.3302 -0.4318)
							(mid -0.402042 -0.402042)
							(end -0.4318 -0.3302)
						)
						(arc
							(start -0.4318 0.3302)
							(mid -0.402042 0.402042)
							(end -0.3302 0.4318)
						)
						(arc
							(start 0.3302 0.4318)
							(mid 0.402042 0.402042)
							(end 0.4318 0.3302)
						)
						(arc
							(start 0.4318 -0.3302)
							(mid 0.402042 -0.402042)
							(end 0.3302 -0.4318)
						)
					)
					(width 0)
					(fill yes)
				)
			)
		)
		(pad "2" smd custom
			(at 0 0.762)
			(size 0.2159 0.2159)
			(layers "F.Cu" "F.Mask" "F.Paste")
			(net "FLT_HDD4")
			(options
				(clearance outline)
				(anchor circle)
			)
			(primitives
				(gr_poly
					(pts
						(arc
							(start -0.3302 -0.4318)
							(mid -0.402042 -0.402042)
							(end -0.4318 -0.3302)
						)
						(arc
							(start -0.4318 0.3302)
							(mid -0.402042 0.402042)
							(end -0.3302 0.4318)
						)
						(arc
							(start 0.3302 0.4318)
							(mid 0.402042 0.402042)
							(end 0.4318 0.3302)
						)
						(arc
							(start 0.4318 -0.3302)
							(mid 0.402042 -0.402042)
							(end 0.3302 -0.4318)
						)
					)
					(width 0)
					(fill yes)
				)
			)
		)
	)
	(footprint ""
		(layer "F.Cu")
		(at 115.2398 -11.303 -90)
		(property "Reference" "R707"
			(at 0 0 270)
			(layer "F.SilkS")
			(hide yes)
			(effects
				(font
					(size 1.27 1.27)
				)
			)
		)
		(property "Value" "200KR2F-L-GP"
			(at 0.064008 -3.993896 270)
			(unlocked yes)
			(layer "F.Fab")
			(hide yes)
			(effects
				(font
					(size 1.016 1.016)
					(thickness 0.1524)
				)
			)
		)
		(property "Device Type" "R402H16"
			(at 0.064008 -5.517896 270)
			(unlocked yes)
			(layer "F.Fab")
			(hide yes)
			(effects
				(font
					(size 1.016 1.016)
					(thickness 0.1524)
				)
			)
		)
		(duplicate_pad_numbers_are_jumpers no)
		(fp_line
			(start -0.508 -0.9398)
			(end -0.508 0.9398)
			(stroke
				(width 0.1524)
				(type default)
			)
			(layer "F.SilkS")
		)
		(fp_line
			(start 0.508 -0.9398)
			(end -0.508 -0.9398)
			(stroke
				(width 0.1524)
				(type default)
			)
			(layer "F.SilkS")
		)
		(fp_rect
			(start -0.508 0.9398)
			(end 0.508 -0.9398)
			(stroke
				(width 0)
				(type default)
			)
			(fill no)
			(layer "F.CrtYd")
		)
		(fp_rect
			(start -0.508 0.9398)
			(end 0.508 -0.9398)
			(stroke
				(width 0)
				(type default)
			)
			(fill no)
			(layer "F.Fab")
		)
		(pad "1" smd custom
			(at 0 -0.4445 270)
			(size 0.1397 0.1397)
			(layers "F.Cu" "F.Mask" "F.Paste")
			(net "SW_HDD_R27")
			(options
				(clearance outline)
				(anchor circle)
			)
			(primitives
				(gr_poly
					(pts
						(arc
							(start -0.1778 -0.2794)
							(mid -0.249642 -0.249642)
							(end -0.2794 -0.1778)
						)
						(arc
							(start -0.2794 0.1778)
							(mid -0.249642 0.249642)
							(end -0.1778 0.2794)
						)
						(arc
							(start 0.1778 0.2794)
							(mid 0.249642 0.249642)
							(end 0.2794 0.1778)
						)
						(arc
							(start 0.2794 -0.1778)
							(mid 0.249642 -0.249642)
							(end 0.1778 -0.2794)
						)
					)
					(width 0)
					(fill yes)
				)
			)
		)
		(pad "2" smd custom
			(at 0 0.4445 270)
			(size 0.1397 0.1397)
			(layers "F.Cu" "F.Mask" "F.Paste")
			(net "SW_HDD_N27")
			(options
				(clearance outline)
				(anchor circle)
			)
			(primitives
				(gr_poly
					(pts
						(arc
							(start -0.1778 -0.2794)
							(mid -0.249642 -0.249642)
							(end -0.2794 -0.1778)
						)
						(arc
							(start -0.2794 0.1778)
							(mid -0.249642 0.249642)
							(end -0.1778 0.2794)
						)
						(arc
							(start 0.1778 0.2794)
							(mid 0.249642 0.249642)
							(end 0.2794 0.1778)
						)
						(arc
							(start 0.2794 -0.1778)
							(mid 0.249642 -0.249642)
							(end 0.1778 -0.2794)
						)
					)
					(width 0)
					(fill yes)
				)
			)
		)
	)
	(footprint ""
		(layer "F.Cu")
		(at 256.921 -215.011 -90)
		(property "Reference" "C25"
			(at 0 0 270)
			(layer "F.SilkS")
			(hide yes)
			(effects
				(font
					(size 1.27 1.27)
				)
			)
		)
		(property "Value" "SCD1U16V2KX-3GP"
			(at 1.1811 -2.7051 270)
			(unlocked yes)
			(layer "F.Fab")
			(hide yes)
			(effects
				(font
					(size 1.016 1.016)
					(thickness 0.1524)
				)
			)
		)
		(property "Device Type" "C402H22"
			(at 1.1811 -4.2291 270)
			(unlocked yes)
			(layer "F.Fab")
			(hide yes)
			(effects
				(font
					(size 1.016 1.016)
					(thickness 0.1524)
				)
			)
		)
		(duplicate_pad_numbers_are_jumpers no)
		(fp_rect
			(start -0.4318 0.9525)
			(end 0.4318 -0.9525)
			(stroke
				(width 0)
				(type default)
			)
			(fill no)
			(layer "F.CrtYd")
		)
		(fp_rect
			(start -0.4318 0.9525)
			(end 0.4318 -0.9525)
			(stroke
				(width 0)
				(type default)
			)
			(fill no)
			(layer "F.Fab")
		)
		(pad "1" smd custom
			(at 0 -0.4445 270)
			(size 0.1524 0.1524)
			(layers "F.Cu" "F.Mask" "F.Paste")
			(net "P3V3_STBY_B")
			(options
				(clearance outline)
				(anchor circle)
			)
			(primitives
				(gr_poly
					(pts
						(arc
							(start 0.3048 -0.2032)
							(mid 0.275042 -0.275042)
							(end 0.2032 -0.3048)
						)
						(arc
							(start -0.2032 -0.3048)
							(mid -0.275042 -0.275042)
							(end -0.3048 -0.2032)
						)
						(arc
							(start -0.3048 0.2032)
							(mid -0.275042 0.275042)
							(end -0.2032 0.3048)
						)
						(arc
							(start 0.2032 0.3048)
							(mid 0.275042 0.275042)
							(end 0.3048 0.2032)
						)
					)
					(width 0)
					(fill yes)
				)
			)
		)
		(pad "2" smd custom
			(at 0 0.4445 270)
			(size 0.1524 0.1524)
			(layers "F.Cu" "F.Mask" "F.Paste")
			(net "GND")
			(options
				(clearance outline)
				(anchor circle)
			)
			(primitives
				(gr_poly
					(pts
						(arc
							(start 0.3048 -0.2032)
							(mid 0.275042 -0.275042)
							(end 0.2032 -0.3048)
						)
						(arc
							(start -0.2032 -0.3048)
							(mid -0.275042 -0.275042)
							(end -0.3048 -0.2032)
						)
						(arc
							(start -0.3048 0.2032)
							(mid -0.275042 0.275042)
							(end -0.2032 0.3048)
						)
						(arc
							(start 0.2032 0.3048)
							(mid 0.275042 0.275042)
							(end 0.3048 0.2032)
						)
					)
					(width 0)
					(fill yes)
				)
			)
		)
	)
	(footprint ""
		(layer "F.Cu")
		(at 259.272278 -236.1565 -90)
		(property "Reference" "Q25"
			(at 0 0 270)
			(layer "F.SilkS")
			(hide yes)
			(effects
				(font
					(size 1.27 1.27)
				)
			)
		)
		(property "Value" "2N7002K-1-GP"
			(at 0.127 -8.9662 270)
			(unlocked yes)
			(layer "F.Fab")
			(hide yes)
			(effects
				(font
					(size 1.016 1.016)
					(thickness 0.1524)
				)
			)
		)
		(property "Device Type" "SOT23DGS2D4H44"
			(at 0.127 -10.4902 270)
			(unlocked yes)
			(layer "F.Fab")
			(hide yes)
			(effects
				(font
					(size 1.016 1.016)
					(thickness 0.1524)
				)
			)
		)
		(duplicate_pad_numbers_are_jumpers no)
		(fp_line
			(start -1.651 1.778)
			(end 1.651 1.778)
			(stroke
				(width 0.1524)
				(type default)
			)
			(layer "F.SilkS")
		)
		(fp_line
			(start 1.651 1.778)
			(end 1.651 -1.778)
			(stroke
				(width 0.1524)
				(type default)
			)
			(layer "F.SilkS")
		)
		(fp_line
			(start -1.651 -1.778)
			(end -1.651 1.778)
			(stroke
				(width 0.1524)
				(type default)
			)
			(layer "F.SilkS")
		)
		(fp_line
			(start 1.651 -1.778)
			(end -1.651 -1.778)
			(stroke
				(width 0.1524)
				(type default)
			)
			(layer "F.SilkS")
		)
		(fp_poly
			(pts
				(xy -1.778 1.8796) (xy -1.778 -1.8796) (xy 1.778 -1.8796) (xy 1.778 1.8796)
			)
			(stroke
				(width 0)
				(type default)
			)
			(fill no)
			(layer "F.CrtYd")
		)
		(fp_poly
			(pts
				(xy -1.778 1.8796) (xy -1.778 -1.8796) (xy 1.778 -1.8796) (xy 1.778 1.8796)
			)
			(stroke
				(width 0)
				(type default)
			)
			(fill no)
			(layer "F.Fab")
		)
		(pad "D" smd custom
			(at 0 -0.9525 270)
			(size 0.1905 0.1905)
			(layers "F.Cu" "F.Mask" "F.Paste")
			(net "SCC_B_FULL_PWR_EN_12V")
			(options
				(clearance outline)
				(anchor circle)
			)
			(primitives
				(gr_poly
					(pts
						(arc
							(start -0.1778 0.5715)
							(mid -0.321484 0.511984)
							(end -0.381 0.3683)
						)
						(arc
							(start -0.381 -0.3683)
							(mid -0.321484 -0.511984)
							(end -0.1778 -0.5715)
						)
						(arc
							(start 0.1778 -0.5715)
							(mid 0.321484 -0.511984)
							(end 0.381 -0.3683)
						)
						(arc
							(start 0.381 0.3683)
							(mid 0.321484 0.511984)
							(end 0.1778 0.5715)
						)
					)
					(width 0)
					(fill yes)
				)
			)
		)
		(pad "G" smd custom
			(at -0.98425 0.9525 270)
			(size 0.1905 0.1905)
			(layers "F.Cu" "F.Mask" "F.Paste")
			(net "SCC_B_FULL_PWR_EN")
			(options
				(clearance outline)
				(anchor circle)
			)
			(primitives
				(gr_poly
					(pts
						(arc
							(start -0.1778 0.5715)
							(mid -0.321484 0.511984)
							(end -0.381 0.3683)
						)
						(arc
							(start -0.381 -0.3683)
							(mid -0.321484 -0.511984)
							(end -0.1778 -0.5715)
						)
						(arc
							(start 0.1778 -0.5715)
							(mid 0.321484 -0.511984)
							(end 0.381 -0.3683)
						)
						(arc
							(start 0.381 0.3683)
							(mid 0.321484 0.511984)
							(end 0.1778 0.5715)
						)
					)
					(width 0)
					(fill yes)
				)
			)
		)
		(pad "S" smd custom
			(at 0.98425 0.9525 270)
			(size 0.1905 0.1905)
			(layers "F.Cu" "F.Mask" "F.Paste")
			(net "GND")
			(options
				(clearance outline)
				(anchor circle)
			)
			(primitives
				(gr_poly
					(pts
						(arc
							(start -0.1778 0.5715)
							(mid -0.321484 0.511984)
							(end -0.381 0.3683)
						)
						(arc
							(start -0.381 -0.3683)
							(mid -0.321484 -0.511984)
							(end -0.1778 -0.5715)
						)
						(arc
							(start 0.1778 -0.5715)
							(mid 0.321484 -0.511984)
							(end 0.381 -0.3683)
						)
						(arc
							(start 0.381 0.3683)
							(mid 0.321484 0.511984)
							(end 0.1778 0.5715)
						)
					)
					(width 0)
					(fill yes)
				)
			)
		)
	)
	(footprint ""
		(layer "F.Cu")
		(at 81.407 -99.314)
		(property "Reference" "R405"
			(at 0 0 0)
			(layer "F.SilkS")
			(hide yes)
			(effects
				(font
					(size 1.27 1.27)
				)
			)
		)
		(property "Value" "91R3F-1-GP"
			(at -0.0254 -2.5146 0)
			(unlocked yes)
			(layer "F.Fab")
			(hide yes)
			(effects
				(font
					(size 1.016 1.016)
					(thickness 0.1524)
				)
			)
		)
		(property "Device Type" "R603H22"
			(at -0.0254 -4.0386 0)
			(unlocked yes)
			(layer "F.Fab")
			(hide yes)
			(effects
				(font
					(size 1.016 1.016)
					(thickness 0.1524)
				)
			)
		)
		(duplicate_pad_numbers_are_jumpers no)
		(fp_line
			(start -0.4826 0)
			(end -0.2032 0)
			(stroke
				(width 0.2032)
				(type default)
			)
			(layer "F.SilkS")
		)
		(fp_line
			(start 0.2032 0)
			(end 0.4826 0)
			(stroke
				(width 0.2032)
				(type default)
			)
			(layer "F.SilkS")
		)
		(fp_rect
			(start -0.5842 1.3335)
			(end 0.5842 -1.3335)
			(stroke
				(width 0)
				(type default)
			)
			(fill no)
			(layer "F.CrtYd")
		)
		(fp_rect
			(start -0.5842 1.3335)
			(end 0.5842 -1.3335)
			(stroke
				(width 0)
				(type default)
			)
			(fill no)
			(layer "F.Fab")
		)
		(pad "1" smd custom
			(at 0 -0.762)
			(size 0.2159 0.2159)
			(layers "F.Cu" "F.Mask" "F.Paste")
			(net "P5V_B_1")
			(options
				(clearance outline)
				(anchor circle)
			)
			(primitives
				(gr_poly
					(pts
						(arc
							(start -0.3302 -0.4318)
							(mid -0.402042 -0.402042)
							(end -0.4318 -0.3302)
						)
						(arc
							(start -0.4318 0.3302)
							(mid -0.402042 0.402042)
							(end -0.3302 0.4318)
						)
						(arc
							(start 0.3302 0.4318)
							(mid 0.402042 0.402042)
							(end 0.4318 0.3302)
						)
						(arc
							(start 0.4318 -0.3302)
							(mid 0.402042 -0.402042)
							(end 0.3302 -0.4318)
						)
					)
					(width 0)
					(fill yes)
				)
			)
		)
		(pad "2" smd custom
			(at 0 0.762)
			(size 0.2159 0.2159)
			(layers "F.Cu" "F.Mask" "F.Paste")
			(net "DRV_ACT_14")
			(options
				(clearance outline)
				(anchor circle)
			)
			(primitives
				(gr_poly
					(pts
						(arc
							(start -0.3302 -0.4318)
							(mid -0.402042 -0.402042)
							(end -0.4318 -0.3302)
						)
						(arc
							(start -0.4318 0.3302)
							(mid -0.402042 0.402042)
							(end -0.3302 0.4318)
						)
						(arc
							(start 0.3302 0.4318)
							(mid 0.402042 0.402042)
							(end 0.4318 0.3302)
						)
						(arc
							(start 0.4318 -0.3302)
							(mid 0.402042 -0.402042)
							(end 0.3302 -0.4318)
						)
					)
					(width 0)
					(fill yes)
				)
			)
		)
	)
	(footprint ""
		(layer "F.Cu")
		(at 476.4532 -250.571 180)
		(property "Reference" "R335"
			(at 0 0 180)
			(layer "F.SilkS")
			(hide yes)
			(effects
				(font
					(size 1.27 1.27)
				)
			)
		)
		(property "Value" "10KR2F-2-GP"
			(at 0.064008 -3.993896 180)
			(unlocked yes)
			(layer "F.Fab")
			(hide yes)
			(effects
				(font
					(size 1.016 1.016)
					(thickness 0.1524)
				)
			)
		)
		(property "Device Type" "R402H16"
			(at 0.064008 -5.517896 180)
			(unlocked yes)
			(layer "F.Fab")
			(hide yes)
			(effects
				(font
					(size 1.016 1.016)
					(thickness 0.1524)
				)
			)
		)
		(duplicate_pad_numbers_are_jumpers no)
		(fp_line
			(start 0.508 -0.9398)
			(end -0.508 -0.9398)
			(stroke
				(width 0.1524)
				(type default)
			)
			(layer "F.SilkS")
		)
		(fp_line
			(start -0.508 -0.9398)
			(end -0.508 0.9398)
			(stroke
				(width 0.1524)
				(type default)
			)
			(layer "F.SilkS")
		)
		(fp_rect
			(start -0.508 0.9398)
			(end 0.508 -0.9398)
			(stroke
				(width 0)
				(type default)
			)
			(fill no)
			(layer "F.CrtYd")
		)
		(fp_rect
			(start -0.508 0.9398)
			(end 0.508 -0.9398)
			(stroke
				(width 0)
				(type default)
			)
			(fill no)
			(layer "F.Fab")
		)
		(pad "1" smd custom
			(at 0 -0.4445 180)
			(size 0.1397 0.1397)
			(layers "F.Cu" "F.Mask" "F.Paste")
			(net "P3V3_STBY_B")
			(options
				(clearance outline)
				(anchor circle)
			)
			(primitives
				(gr_poly
					(pts
						(arc
							(start -0.1778 -0.2794)
							(mid -0.249642 -0.249642)
							(end -0.2794 -0.1778)
						)
						(arc
							(start -0.2794 0.1778)
							(mid -0.249642 0.249642)
							(end -0.1778 0.2794)
						)
						(arc
							(start 0.1778 0.2794)
							(mid 0.249642 0.249642)
							(end 0.2794 0.1778)
						)
						(arc
							(start 0.2794 -0.1778)
							(mid 0.249642 -0.249642)
							(end 0.1778 -0.2794)
						)
					)
					(width 0)
					(fill yes)
				)
			)
		)
		(pad "2" smd custom
			(at 0 0.4445 180)
			(size 0.1397 0.1397)
			(layers "F.Cu" "F.Mask" "F.Paste")
			(net "HDD_PRSNT_11")
			(options
				(clearance outline)
				(anchor circle)
			)
			(primitives
				(gr_poly
					(pts
						(arc
							(start -0.1778 -0.2794)
							(mid -0.249642 -0.249642)
							(end -0.2794 -0.1778)
						)
						(arc
							(start -0.2794 0.1778)
							(mid -0.249642 0.249642)
							(end -0.1778 0.2794)
						)
						(arc
							(start 0.1778 0.2794)
							(mid 0.249642 0.249642)
							(end 0.2794 0.1778)
						)
						(arc
							(start 0.2794 -0.1778)
							(mid 0.249642 -0.249642)
							(end 0.1778 -0.2794)
						)
					)
					(width 0)
					(fill yes)
				)
			)
		)
	)
	(footprint ""
		(layer "F.Cu")
		(at 248.270522 -360.349546 -90)
		(property "Reference" "R1041"
			(at 0 0 270)
			(layer "F.SilkS")
			(hide yes)
			(effects
				(font
					(size 1.27 1.27)
				)
			)
		)
		(property "Value" "100KR2F-L1-GP"
			(at 0.064008 -3.993896 270)
			(unlocked yes)
			(layer "F.Fab")
			(hide yes)
			(effects
				(font
					(size 1.016 1.016)
					(thickness 0.1524)
				)
			)
		)
		(property "Device Type" "R402H16"
			(at 0.064008 -5.517896 270)
			(unlocked yes)
			(layer "F.Fab")
			(hide yes)
			(effects
				(font
					(size 1.016 1.016)
					(thickness 0.1524)
				)
			)
		)
		(duplicate_pad_numbers_are_jumpers no)
		(fp_line
			(start -0.508 -0.9398)
			(end -0.508 0.9398)
			(stroke
				(width 0.1524)
				(type default)
			)
			(layer "F.SilkS")
		)
		(fp_line
			(start 0.508 -0.9398)
			(end -0.508 -0.9398)
			(stroke
				(width 0.1524)
				(type default)
			)
			(layer "F.SilkS")
		)
		(fp_rect
			(start -0.508 0.9398)
			(end 0.508 -0.9398)
			(stroke
				(width 0)
				(type default)
			)
			(fill no)
			(layer "F.CrtYd")
		)
		(fp_rect
			(start -0.508 0.9398)
			(end 0.508 -0.9398)
			(stroke
				(width 0)
				(type default)
			)
			(fill no)
			(layer "F.Fab")
		)
		(pad "1" smd custom
			(at 0 -0.4445 270)
			(size 0.1397 0.1397)
			(layers "F.Cu" "F.Mask" "F.Paste")
			(net "MB3_VCAP_R")
			(options
				(clearance outline)
				(anchor circle)
			)
			(primitives
				(gr_poly
					(pts
						(arc
							(start -0.1778 -0.2794)
							(mid -0.249642 -0.249642)
							(end -0.2794 -0.1778)
						)
						(arc
							(start -0.2794 0.1778)
							(mid -0.249642 0.249642)
							(end -0.1778 0.2794)
						)
						(arc
							(start 0.1778 0.2794)
							(mid 0.249642 0.249642)
							(end 0.2794 0.1778)
						)
						(arc
							(start 0.2794 -0.1778)
							(mid 0.249642 -0.249642)
							(end 0.1778 -0.2794)
						)
					)
					(width 0)
					(fill yes)
				)
			)
		)
		(pad "2" smd custom
			(at 0 0.4445 270)
			(size 0.1397 0.1397)
			(layers "F.Cu" "F.Mask" "F.Paste")
			(net "MB3_PSET_R")
			(options
				(clearance outline)
				(anchor circle)
			)
			(primitives
				(gr_poly
					(pts
						(arc
							(start -0.1778 -0.2794)
							(mid -0.249642 -0.249642)
							(end -0.2794 -0.1778)
						)
						(arc
							(start -0.2794 0.1778)
							(mid -0.249642 0.249642)
							(end -0.1778 0.2794)
						)
						(arc
							(start 0.1778 0.2794)
							(mid 0.249642 0.249642)
							(end 0.2794 0.1778)
						)
						(arc
							(start 0.2794 -0.1778)
							(mid 0.249642 -0.249642)
							(end 0.1778 -0.2794)
						)
					)
					(width 0)
					(fill yes)
				)
			)
		)
	)
	(footprint ""
		(layer "F.Cu")
		(at 211.95538 -238.48822 180)
		(property "Reference" "C8"
			(at 0 0 180)
			(layer "F.SilkS")
			(hide yes)
			(effects
				(font
					(size 1.27 1.27)
				)
			)
		)
		(property "Value" "SCD1U16V2KX-3GP"
			(at 1.1811 -2.7051 180)
			(unlocked yes)
			(layer "F.Fab")
			(hide yes)
			(effects
				(font
					(size 1.016 1.016)
					(thickness 0.1524)
				)
			)
		)
		(property "Device Type" "C402H22"
			(at 1.1811 -4.2291 180)
			(unlocked yes)
			(layer "F.Fab")
			(hide yes)
			(effects
				(font
					(size 1.016 1.016)
					(thickness 0.1524)
				)
			)
		)
		(duplicate_pad_numbers_are_jumpers no)
		(fp_rect
			(start -0.4318 0.9525)
			(end 0.4318 -0.9525)
			(stroke
				(width 0)
				(type default)
			)
			(fill no)
			(layer "F.CrtYd")
		)
		(fp_rect
			(start -0.4318 0.9525)
			(end 0.4318 -0.9525)
			(stroke
				(width 0)
				(type default)
			)
			(fill no)
			(layer "F.Fab")
		)
		(pad "1" smd custom
			(at 0 -0.4445 180)
			(size 0.1524 0.1524)
			(layers "F.Cu" "F.Mask" "F.Paste")
			(net "P3V3_STBY_B")
			(options
				(clearance outline)
				(anchor circle)
			)
			(primitives
				(gr_poly
					(pts
						(arc
							(start 0.3048 -0.2032)
							(mid 0.275042 -0.275042)
							(end 0.2032 -0.3048)
						)
						(arc
							(start -0.2032 -0.3048)
							(mid -0.275042 -0.275042)
							(end -0.3048 -0.2032)
						)
						(arc
							(start -0.3048 0.2032)
							(mid -0.275042 0.275042)
							(end -0.2032 0.3048)
						)
						(arc
							(start 0.2032 0.3048)
							(mid 0.275042 0.275042)
							(end 0.3048 0.2032)
						)
					)
					(width 0)
					(fill yes)
				)
			)
		)
		(pad "2" smd custom
			(at 0 0.4445 180)
			(size 0.1524 0.1524)
			(layers "F.Cu" "F.Mask" "F.Paste")
			(net "GND")
			(options
				(clearance outline)
				(anchor circle)
			)
			(primitives
				(gr_poly
					(pts
						(arc
							(start 0.3048 -0.2032)
							(mid 0.275042 -0.275042)
							(end 0.2032 -0.3048)
						)
						(arc
							(start -0.2032 -0.3048)
							(mid -0.275042 -0.275042)
							(end -0.3048 -0.2032)
						)
						(arc
							(start -0.3048 0.2032)
							(mid -0.275042 0.275042)
							(end -0.2032 0.3048)
						)
						(arc
							(start 0.2032 0.3048)
							(mid 0.275042 0.275042)
							(end 0.3048 0.2032)
						)
					)
					(width 0)
					(fill yes)
				)
			)
		)
	)
	(footprint ""
		(layer "F.Cu")
		(at 248.285 -309.118 90)
		(property "Reference" "R1091"
			(at 0 0 90)
			(layer "F.SilkS")
			(hide yes)
			(effects
				(font
					(size 1.27 1.27)
				)
			)
		)
		(property "Value" "0R2J-2-GP"
			(at 0.064008 -3.993896 90)
			(unlocked yes)
			(layer "F.Fab")
			(hide yes)
			(effects
				(font
					(size 1.016 1.016)
					(thickness 0.1524)
				)
			)
		)
		(property "Device Type" "R402H16"
			(at 0.064008 -5.517896 90)
			(unlocked yes)
			(layer "F.Fab")
			(hide yes)
			(effects
				(font
					(size 1.016 1.016)
					(thickness 0.1524)
				)
			)
		)
		(duplicate_pad_numbers_are_jumpers no)
		(fp_line
			(start 0.508 -0.9398)
			(end -0.508 -0.9398)
			(stroke
				(width 0.1524)
				(type default)
			)
			(layer "F.SilkS")
		)
		(fp_line
			(start -0.508 -0.9398)
			(end -0.508 0.9398)
			(stroke
				(width 0.1524)
				(type default)
			)
			(layer "F.SilkS")
		)
		(fp_rect
			(start -0.508 0.9398)
			(end 0.508 -0.9398)
			(stroke
				(width 0)
				(type default)
			)
			(fill no)
			(layer "F.CrtYd")
		)
		(fp_rect
			(start -0.508 0.9398)
			(end 0.508 -0.9398)
			(stroke
				(width 0)
				(type default)
			)
			(fill no)
			(layer "F.Fab")
		)
		(pad "1" smd custom
			(at 0 -0.4445 90)
			(size 0.1397 0.1397)
			(layers "F.Cu" "F.Mask" "F.Paste")
			(net "MAX31790_A_PWM_ST1")
			(options
				(clearance outline)
				(anchor circle)
			)
			(primitives
				(gr_poly
					(pts
						(arc
							(start -0.1778 -0.2794)
							(mid -0.249642 -0.249642)
							(end -0.2794 -0.1778)
						)
						(arc
							(start -0.2794 0.1778)
							(mid -0.249642 0.249642)
							(end -0.1778 0.2794)
						)
						(arc
							(start 0.1778 0.2794)
							(mid 0.249642 0.249642)
							(end 0.2794 0.1778)
						)
						(arc
							(start 0.2794 -0.1778)
							(mid 0.249642 -0.249642)
							(end 0.1778 -0.2794)
						)
					)
					(width 0)
					(fill yes)
				)
			)
		)
		(pad "2" smd custom
			(at 0 0.4445 90)
			(size 0.1397 0.1397)
			(layers "F.Cu" "F.Mask" "F.Paste")
			(net "GND")
			(options
				(clearance outline)
				(anchor circle)
			)
			(primitives
				(gr_poly
					(pts
						(arc
							(start -0.1778 -0.2794)
							(mid -0.249642 -0.249642)
							(end -0.2794 -0.1778)
						)
						(arc
							(start -0.2794 0.1778)
							(mid -0.249642 0.249642)
							(end -0.1778 0.2794)
						)
						(arc
							(start 0.1778 0.2794)
							(mid 0.249642 0.249642)
							(end 0.2794 0.1778)
						)
						(arc
							(start 0.2794 -0.1778)
							(mid 0.249642 -0.249642)
							(end 0.1778 -0.2794)
						)
					)
					(width 0)
					(fill yes)
				)
			)
		)
	)
	(footprint ""
		(layer "F.Cu")
		(at 280.444448 -350.335342 -90)
		(property "Reference" "R1080"
			(at 0 0 270)
			(layer "F.SilkS")
			(hide yes)
			(effects
				(font
					(size 1.27 1.27)
				)
			)
		)
		(property "Value" "0R2J-2-GP"
			(at 0.064008 -3.993896 270)
			(unlocked yes)
			(layer "F.Fab")
			(hide yes)
			(effects
				(font
					(size 1.016 1.016)
					(thickness 0.1524)
				)
			)
		)
		(property "Device Type" "R402H16"
			(at 0.064008 -5.517896 270)
			(unlocked yes)
			(layer "F.Fab")
			(hide yes)
			(effects
				(font
					(size 1.016 1.016)
					(thickness 0.1524)
				)
			)
		)
		(duplicate_pad_numbers_are_jumpers no)
		(fp_line
			(start -0.508 -0.9398)
			(end -0.508 0.9398)
			(stroke
				(width 0.1524)
				(type default)
			)
			(layer "F.SilkS")
		)
		(fp_line
			(start 0.508 -0.9398)
			(end -0.508 -0.9398)
			(stroke
				(width 0.1524)
				(type default)
			)
			(layer "F.SilkS")
		)
		(fp_rect
			(start -0.508 0.9398)
			(end 0.508 -0.9398)
			(stroke
				(width 0)
				(type default)
			)
			(fill no)
			(layer "F.CrtYd")
		)
		(fp_rect
			(start -0.508 0.9398)
			(end 0.508 -0.9398)
			(stroke
				(width 0)
				(type default)
			)
			(fill no)
			(layer "F.Fab")
		)
		(pad "1" smd custom
			(at 0 -0.4445 270)
			(size 0.1397 0.1397)
			(layers "F.Cu" "F.Mask" "F.Paste")
			(net "MAX31790_B_PWM_ST1")
			(options
				(clearance outline)
				(anchor circle)
			)
			(primitives
				(gr_poly
					(pts
						(arc
							(start -0.1778 -0.2794)
							(mid -0.249642 -0.249642)
							(end -0.2794 -0.1778)
						)
						(arc
							(start -0.2794 0.1778)
							(mid -0.249642 0.249642)
							(end -0.1778 0.2794)
						)
						(arc
							(start 0.1778 0.2794)
							(mid 0.249642 0.249642)
							(end 0.2794 0.1778)
						)
						(arc
							(start 0.2794 -0.1778)
							(mid 0.249642 -0.249642)
							(end 0.1778 -0.2794)
						)
					)
					(width 0)
					(fill yes)
				)
			)
		)
		(pad "2" smd custom
			(at 0 0.4445 270)
			(size 0.1397 0.1397)
			(layers "F.Cu" "F.Mask" "F.Paste")
			(net "GND")
			(options
				(clearance outline)
				(anchor circle)
			)
			(primitives
				(gr_poly
					(pts
						(arc
							(start -0.1778 -0.2794)
							(mid -0.249642 -0.249642)
							(end -0.2794 -0.1778)
						)
						(arc
							(start -0.2794 0.1778)
							(mid -0.249642 0.249642)
							(end -0.1778 0.2794)
						)
						(arc
							(start 0.1778 0.2794)
							(mid 0.249642 0.249642)
							(end 0.2794 0.1778)
						)
						(arc
							(start 0.2794 -0.1778)
							(mid 0.249642 -0.249642)
							(end 0.1778 -0.2794)
						)
					)
					(width 0)
					(fill yes)
				)
			)
		)
	)
	(footprint ""
		(layer "F.Cu")
		(at 23.749 -33.274)
		(property "Reference" "R621"
			(at 0 0 0)
			(layer "F.SilkS")
			(hide yes)
			(effects
				(font
					(size 1.27 1.27)
				)
			)
		)
		(property "Value" "2R6F-GP"
			(at -0.0508 -4.8514 0)
			(unlocked yes)
			(layer "F.Fab")
			(hide yes)
			(effects
				(font
					(size 1.016 1.016)
					(thickness 0.1524)
				)
			)
		)
		(property "Device Type" "R1206H26"
			(at 0 -6.3754 0)
			(unlocked yes)
			(layer "F.Fab")
			(hide yes)
			(effects
				(font
					(size 1.016 1.016)
					(thickness 0.1524)
				)
			)
		)
		(duplicate_pad_numbers_are_jumpers no)
		(fp_line
			(start -1.016 -2.2352)
			(end 1.016 -2.2352)
			(stroke
				(width 0.1524)
				(type default)
			)
			(layer "F.SilkS")
		)
		(fp_line
			(start -1.016 2.2352)
			(end -1.016 -2.2352)
			(stroke
				(width 0.1524)
				(type default)
			)
			(layer "F.SilkS")
		)
		(fp_line
			(start 1.016 -2.2352)
			(end 1.016 2.2352)
			(stroke
				(width 0.1524)
				(type default)
			)
			(layer "F.SilkS")
		)
		(fp_line
			(start 1.016 2.2352)
			(end -1.016 2.2352)
			(stroke
				(width 0.1524)
				(type default)
			)
			(layer "F.SilkS")
		)
		(fp_rect
			(start -1.0922 2.3114)
			(end 1.0922 -2.3114)
			(stroke
				(width 0)
				(type default)
			)
			(fill no)
			(layer "F.CrtYd")
		)
		(fp_poly
			(pts
				(xy -1.0922 -2.3114) (xy 1.0922 -2.3114) (xy 1.0922 2.3114) (xy -1.0922 2.3114)
			)
			(stroke
				(width 0)
				(type default)
			)
			(fill no)
			(layer "F.Fab")
		)
		(pad "1" smd rect
			(at 0 -1.397)
			(size 1.651 1.27)
			(layers "F.Cu" "F.Mask" "F.Paste")
			(net "P5V_HDD24")
		)
		(pad "2" smd rect
			(at 0 1.397)
			(size 1.651 1.27)
			(layers "F.Cu" "F.Mask" "F.Paste")
			(net "5V_PRE_24")
		)
	)
	(footprint ""
		(layer "F.Cu")
		(at 441.416186 -119.178578 -90)
		(property "Reference" "C677"
			(at 0 0 270)
			(layer "F.SilkS")
			(hide yes)
			(effects
				(font
					(size 1.27 1.27)
				)
			)
		)
		(property "Value" "SC1U16V3KX-5GP"
			(at 0 -2.8194 270)
			(unlocked yes)
			(layer "F.Fab")
			(hide yes)
			(effects
				(font
					(size 1.016 1.016)
					(thickness 0.1524)
				)
			)
		)
		(property "Device Type" "C603H36"
			(at 0 -4.3434 270)
			(unlocked yes)
			(layer "F.Fab")
			(hide yes)
			(effects
				(font
					(size 1.016 1.016)
					(thickness 0.1524)
				)
			)
		)
		(duplicate_pad_numbers_are_jumpers no)
		(fp_line
			(start 0.508 0)
			(end -0.508 0)
			(stroke
				(width 0.2032)
				(type default)
			)
			(layer "F.SilkS")
		)
		(fp_rect
			(start -0.5842 1.3335)
			(end 0.5842 -1.3335)
			(stroke
				(width 0)
				(type default)
			)
			(fill no)
			(layer "F.CrtYd")
		)
		(fp_rect
			(start -0.5842 1.3335)
			(end 0.5842 -1.3335)
			(stroke
				(width 0)
				(type default)
			)
			(fill no)
			(layer "F.Fab")
		)
		(pad "1" smd custom
			(at 0 -0.762 270)
			(size 0.2159 0.2159)
			(layers "F.Cu" "F.Mask" "F.Paste")
			(net "P5V_B_4_EN_R")
			(options
				(clearance outline)
				(anchor circle)
			)
			(primitives
				(gr_poly
					(pts
						(arc
							(start -0.3302 -0.4318)
							(mid -0.402042 -0.402042)
							(end -0.4318 -0.3302)
						)
						(arc
							(start -0.4318 0.3302)
							(mid -0.402042 0.402042)
							(end -0.3302 0.4318)
						)
						(arc
							(start 0.3302 0.4318)
							(mid 0.402042 0.402042)
							(end 0.4318 0.3302)
						)
						(arc
							(start 0.4318 -0.3302)
							(mid 0.402042 -0.402042)
							(end 0.3302 -0.4318)
						)
					)
					(width 0)
					(fill yes)
				)
			)
		)
		(pad "2" smd custom
			(at 0 0.762 270)
			(size 0.2159 0.2159)
			(layers "F.Cu" "F.Mask" "F.Paste")
			(net "GND")
			(options
				(clearance outline)
				(anchor circle)
			)
			(primitives
				(gr_poly
					(pts
						(arc
							(start -0.3302 -0.4318)
							(mid -0.402042 -0.402042)
							(end -0.4318 -0.3302)
						)
						(arc
							(start -0.4318 0.3302)
							(mid -0.402042 0.402042)
							(end -0.3302 0.4318)
						)
						(arc
							(start 0.3302 0.4318)
							(mid 0.402042 0.402042)
							(end 0.4318 0.3302)
						)
						(arc
							(start 0.4318 -0.3302)
							(mid 0.402042 -0.402042)
							(end 0.3302 -0.4318)
						)
					)
					(width 0)
					(fill yes)
				)
			)
		)
	)
	(footprint ""
		(layer "F.Cu")
		(at 309.1434 -340.812882 180)
		(property "Reference" "R161"
			(at 0 0 180)
			(layer "F.SilkS")
			(hide yes)
			(effects
				(font
					(size 1.27 1.27)
				)
			)
		)
		(property "Value" "100KR2F-L1-GP"
			(at 0.064008 -3.993896 180)
			(unlocked yes)
			(layer "F.Fab")
			(hide yes)
			(effects
				(font
					(size 1.016 1.016)
					(thickness 0.1524)
				)
			)
		)
		(property "Device Type" "R402H16"
			(at 0.064008 -5.517896 180)
			(unlocked yes)
			(layer "F.Fab")
			(hide yes)
			(effects
				(font
					(size 1.016 1.016)
					(thickness 0.1524)
				)
			)
		)
		(duplicate_pad_numbers_are_jumpers no)
		(fp_line
			(start 0.508 -0.9398)
			(end -0.508 -0.9398)
			(stroke
				(width 0.1524)
				(type default)
			)
			(layer "F.SilkS")
		)
		(fp_line
			(start -0.508 -0.9398)
			(end -0.508 0.9398)
			(stroke
				(width 0.1524)
				(type default)
			)
			(layer "F.SilkS")
		)
		(fp_rect
			(start -0.508 0.9398)
			(end 0.508 -0.9398)
			(stroke
				(width 0)
				(type default)
			)
			(fill no)
			(layer "F.CrtYd")
		)
		(fp_rect
			(start -0.508 0.9398)
			(end 0.508 -0.9398)
			(stroke
				(width 0)
				(type default)
			)
			(fill no)
			(layer "F.Fab")
		)
		(pad "1" smd custom
			(at 0 -0.4445 180)
			(size 0.1397 0.1397)
			(layers "F.Cu" "F.Mask" "F.Paste")
			(net "PWM_SCC_B_ZONE_D")
			(options
				(clearance outline)
				(anchor circle)
			)
			(primitives
				(gr_poly
					(pts
						(arc
							(start -0.1778 -0.2794)
							(mid -0.249642 -0.249642)
							(end -0.2794 -0.1778)
						)
						(arc
							(start -0.2794 0.1778)
							(mid -0.249642 0.249642)
							(end -0.1778 0.2794)
						)
						(arc
							(start 0.1778 0.2794)
							(mid 0.249642 0.249642)
							(end 0.2794 0.1778)
						)
						(arc
							(start 0.2794 -0.1778)
							(mid 0.249642 -0.249642)
							(end 0.1778 -0.2794)
						)
					)
					(width 0)
					(fill yes)
				)
			)
		)
		(pad "2" smd custom
			(at 0 0.4445 180)
			(size 0.1397 0.1397)
			(layers "F.Cu" "F.Mask" "F.Paste")
			(net "GND")
			(options
				(clearance outline)
				(anchor circle)
			)
			(primitives
				(gr_poly
					(pts
						(arc
							(start -0.1778 -0.2794)
							(mid -0.249642 -0.249642)
							(end -0.2794 -0.1778)
						)
						(arc
							(start -0.2794 0.1778)
							(mid -0.249642 0.249642)
							(end -0.1778 0.2794)
						)
						(arc
							(start 0.1778 0.2794)
							(mid 0.249642 0.249642)
							(end 0.2794 0.1778)
						)
						(arc
							(start 0.2794 -0.1778)
							(mid 0.249642 -0.249642)
							(end 0.1778 -0.2794)
						)
					)
					(width 0)
					(fill yes)
				)
			)
		)
	)
	(footprint ""
		(layer "F.Cu")
		(at 86.106 -19.558 90)
		(property "Reference" "R680"
			(at 0 0 90)
			(layer "F.SilkS")
			(hide yes)
			(effects
				(font
					(size 1.27 1.27)
				)
			)
		)
		(property "Value" "4K7R2F-GP"
			(at 0.064008 -3.993896 90)
			(unlocked yes)
			(layer "F.Fab")
			(hide yes)
			(effects
				(font
					(size 1.016 1.016)
					(thickness 0.1524)
				)
			)
		)
		(property "Device Type" "R402H16"
			(at 0.064008 -5.517896 90)
			(unlocked yes)
			(layer "F.Fab")
			(hide yes)
			(effects
				(font
					(size 1.016 1.016)
					(thickness 0.1524)
				)
			)
		)
		(duplicate_pad_numbers_are_jumpers no)
		(fp_line
			(start 0.508 -0.9398)
			(end -0.508 -0.9398)
			(stroke
				(width 0.1524)
				(type default)
			)
			(layer "F.SilkS")
		)
		(fp_line
			(start -0.508 -0.9398)
			(end -0.508 0.9398)
			(stroke
				(width 0.1524)
				(type default)
			)
			(layer "F.SilkS")
		)
		(fp_rect
			(start -0.508 0.9398)
			(end 0.508 -0.9398)
			(stroke
				(width 0)
				(type default)
			)
			(fill no)
			(layer "F.CrtYd")
		)
		(fp_rect
			(start -0.508 0.9398)
			(end 0.508 -0.9398)
			(stroke
				(width 0)
				(type default)
			)
			(fill no)
			(layer "F.Fab")
		)
		(pad "1" smd custom
			(at 0 -0.4445 90)
			(size 0.1397 0.1397)
			(layers "F.Cu" "F.Mask" "F.Paste")
			(net "SW_PWR_R_HDD26")
			(options
				(clearance outline)
				(anchor circle)
			)
			(primitives
				(gr_poly
					(pts
						(arc
							(start -0.1778 -0.2794)
							(mid -0.249642 -0.249642)
							(end -0.2794 -0.1778)
						)
						(arc
							(start -0.2794 0.1778)
							(mid -0.249642 0.249642)
							(end -0.1778 0.2794)
						)
						(arc
							(start 0.1778 0.2794)
							(mid 0.249642 0.249642)
							(end 0.2794 0.1778)
						)
						(arc
							(start 0.2794 -0.1778)
							(mid 0.249642 -0.249642)
							(end 0.1778 -0.2794)
						)
					)
					(width 0)
					(fill yes)
				)
			)
		)
		(pad "2" smd custom
			(at 0 0.4445 90)
			(size 0.1397 0.1397)
			(layers "F.Cu" "F.Mask" "F.Paste")
			(net "GND")
			(options
				(clearance outline)
				(anchor circle)
			)
			(primitives
				(gr_poly
					(pts
						(arc
							(start -0.1778 -0.2794)
							(mid -0.249642 -0.249642)
							(end -0.2794 -0.1778)
						)
						(arc
							(start -0.2794 0.1778)
							(mid -0.249642 0.249642)
							(end -0.1778 0.2794)
						)
						(arc
							(start 0.1778 0.2794)
							(mid 0.249642 0.249642)
							(end 0.2794 0.1778)
						)
						(arc
							(start 0.2794 -0.1778)
							(mid 0.249642 -0.249642)
							(end 0.1778 -0.2794)
						)
					)
					(width 0)
					(fill yes)
				)
			)
		)
	)
	(footprint ""
		(layer "F.Cu")
		(at 456.9714 -19.5072)
		(property "Reference" "R859"
			(at 0 0 0)
			(layer "F.SilkS")
			(hide yes)
			(effects
				(font
					(size 1.27 1.27)
				)
			)
		)
		(property "Value" "4K7R2J-2-GP"
			(at 0.064008 -3.993896 0)
			(unlocked yes)
			(layer "F.Fab")
			(hide yes)
			(effects
				(font
					(size 1.016 1.016)
					(thickness 0.1524)
				)
			)
		)
		(property "Device Type" "R402H16"
			(at 0.064008 -5.517896 0)
			(unlocked yes)
			(layer "F.Fab")
			(hide yes)
			(effects
				(font
					(size 1.016 1.016)
					(thickness 0.1524)
				)
			)
		)
		(duplicate_pad_numbers_are_jumpers no)
		(fp_line
			(start -0.508 -0.9398)
			(end -0.508 0.9398)
			(stroke
				(width 0.1524)
				(type default)
			)
			(layer "F.SilkS")
		)
		(fp_line
			(start 0.508 -0.9398)
			(end -0.508 -0.9398)
			(stroke
				(width 0.1524)
				(type default)
			)
			(layer "F.SilkS")
		)
		(fp_rect
			(start -0.508 0.9398)
			(end 0.508 -0.9398)
			(stroke
				(width 0)
				(type default)
			)
			(fill no)
			(layer "F.CrtYd")
		)
		(fp_rect
			(start -0.508 0.9398)
			(end 0.508 -0.9398)
			(stroke
				(width 0)
				(type default)
			)
			(fill no)
			(layer "F.Fab")
		)
		(pad "1" smd custom
			(at 0 -0.4445)
			(size 0.1397 0.1397)
			(layers "F.Cu" "F.Mask" "F.Paste")
			(net "P12V_B")
			(options
				(clearance outline)
				(anchor circle)
			)
			(primitives
				(gr_poly
					(pts
						(arc
							(start -0.1778 -0.2794)
							(mid -0.249642 -0.249642)
							(end -0.2794 -0.1778)
						)
						(arc
							(start -0.2794 0.1778)
							(mid -0.249642 0.249642)
							(end -0.1778 0.2794)
						)
						(arc
							(start 0.1778 0.2794)
							(mid 0.249642 0.249642)
							(end 0.2794 0.1778)
						)
						(arc
							(start 0.2794 -0.1778)
							(mid 0.249642 -0.249642)
							(end 0.1778 -0.2794)
						)
					)
					(width 0)
					(fill yes)
				)
			)
		)
		(pad "2" smd custom
			(at 0 0.4445)
			(size 0.1397 0.1397)
			(layers "F.Cu" "F.Mask" "F.Paste")
			(net "SW_HDD_P34")
			(options
				(clearance outline)
				(anchor circle)
			)
			(primitives
				(gr_poly
					(pts
						(arc
							(start -0.1778 -0.2794)
							(mid -0.249642 -0.249642)
							(end -0.2794 -0.1778)
						)
						(arc
							(start -0.2794 0.1778)
							(mid -0.249642 0.249642)
							(end -0.1778 0.2794)
						)
						(arc
							(start 0.1778 0.2794)
							(mid 0.249642 0.249642)
							(end 0.2794 0.1778)
						)
						(arc
							(start 0.2794 -0.1778)
							(mid 0.249642 -0.249642)
							(end 0.1778 -0.2794)
						)
					)
					(width 0)
					(fill yes)
				)
			)
		)
	)
	(footprint ""
		(layer "F.Cu")
		(at 13.959586 -99.886262 90)
		(property "Reference" "Q255"
			(at 0 0 90)
			(layer "F.SilkS")
			(hide yes)
			(effects
				(font
					(size 1.27 1.27)
				)
			)
		)
		(property "Value" "SSM3K324R-GP"
			(at 0.127 -8.9662 90)
			(unlocked yes)
			(layer "F.Fab")
			(hide yes)
			(effects
				(font
					(size 1.016 1.016)
					(thickness 0.1524)
				)
			)
		)
		(property "Device Type" "SOT23DGS2D4H35"
			(at 0.127 -10.4902 90)
			(unlocked yes)
			(layer "F.Fab")
			(hide yes)
			(effects
				(font
					(size 1.016 1.016)
					(thickness 0.1524)
				)
			)
		)
		(duplicate_pad_numbers_are_jumpers no)
		(fp_line
			(start 1.651 -1.778)
			(end -1.651 -1.778)
			(stroke
				(width 0.1524)
				(type default)
			)
			(layer "F.SilkS")
		)
		(fp_line
			(start -1.651 -1.778)
			(end -1.651 1.778)
			(stroke
				(width 0.1524)
				(type default)
			)
			(layer "F.SilkS")
		)
		(fp_line
			(start 1.651 1.778)
			(end 1.651 -1.778)
			(stroke
				(width 0.1524)
				(type default)
			)
			(layer "F.SilkS")
		)
		(fp_line
			(start -1.651 1.778)
			(end 1.651 1.778)
			(stroke
				(width 0.1524)
				(type default)
			)
			(layer "F.SilkS")
		)
		(fp_poly
			(pts
				(xy -1.778 1.8796) (xy -1.778 -1.8796) (xy 1.778 -1.8796) (xy 1.778 1.8796)
			)
			(stroke
				(width 0)
				(type default)
			)
			(fill no)
			(layer "F.CrtYd")
		)
		(fp_poly
			(pts
				(xy -1.778 1.8796) (xy -1.778 -1.8796) (xy 1.778 -1.8796) (xy 1.778 1.8796)
			)
			(stroke
				(width 0)
				(type default)
			)
			(fill no)
			(layer "F.Fab")
		)
		(pad "D" smd custom
			(at 0 -0.9525 90)
			(size 0.1905 0.1905)
			(layers "F.Cu" "F.Mask" "F.Paste")
			(net "DRV_ACT_12_N")
			(options
				(clearance outline)
				(anchor circle)
			)
			(primitives
				(gr_poly
					(pts
						(arc
							(start -0.1778 0.5715)
							(mid -0.321484 0.511984)
							(end -0.381 0.3683)
						)
						(arc
							(start -0.381 -0.3683)
							(mid -0.321484 -0.511984)
							(end -0.1778 -0.5715)
						)
						(arc
							(start 0.1778 -0.5715)
							(mid 0.321484 -0.511984)
							(end 0.381 -0.3683)
						)
						(arc
							(start 0.381 0.3683)
							(mid 0.321484 0.511984)
							(end 0.1778 0.5715)
						)
					)
					(width 0)
					(fill yes)
				)
			)
		)
		(pad "G" smd custom
			(at -0.98425 0.9525 90)
			(size 0.1905 0.1905)
			(layers "F.Cu" "F.Mask" "F.Paste")
			(net "DRIVE_B_12_ACT")
			(options
				(clearance outline)
				(anchor circle)
			)
			(primitives
				(gr_poly
					(pts
						(arc
							(start -0.1778 0.5715)
							(mid -0.321484 0.511984)
							(end -0.381 0.3683)
						)
						(arc
							(start -0.381 -0.3683)
							(mid -0.321484 -0.511984)
							(end -0.1778 -0.5715)
						)
						(arc
							(start 0.1778 -0.5715)
							(mid 0.321484 -0.511984)
							(end 0.381 -0.3683)
						)
						(arc
							(start 0.381 0.3683)
							(mid 0.321484 0.511984)
							(end 0.1778 0.5715)
						)
					)
					(width 0)
					(fill yes)
				)
			)
		)
		(pad "S" smd custom
			(at 0.98425 0.9525 90)
			(size 0.1905 0.1905)
			(layers "F.Cu" "F.Mask" "F.Paste")
			(net "GND")
			(options
				(clearance outline)
				(anchor circle)
			)
			(primitives
				(gr_poly
					(pts
						(arc
							(start -0.1778 0.5715)
							(mid -0.321484 0.511984)
							(end -0.381 0.3683)
						)
						(arc
							(start -0.381 -0.3683)
							(mid -0.321484 -0.511984)
							(end -0.1778 -0.5715)
						)
						(arc
							(start 0.1778 -0.5715)
							(mid 0.321484 -0.511984)
							(end 0.381 -0.3683)
						)
						(arc
							(start 0.381 0.3683)
							(mid 0.321484 0.511984)
							(end 0.1778 0.5715)
						)
					)
					(width 0)
					(fill yes)
				)
			)
		)
	)
	(footprint ""
		(layer "F.Cu")
		(at 451.749922 -258.910074 -90)
		(property "Reference" "HDDSAS10"
			(at 0 0 270)
			(layer "F.SilkS")
			(hide yes)
			(effects
				(font
					(size 1.27 1.27)
				)
			)
		)
		(property "Value" "SKT-SAS15P-14P-45-GP"
			(at -20.7645 -8.9789 270)
			(unlocked yes)
			(layer "F.Fab")
			(hide yes)
			(effects
				(font
					(size 1.016 1.016)
					(thickness 0.1524)
				)
			)
		)
		(property "Device Type" "10120818-001C-TRLF"
			(at -20.7645 -10.5029 270)
			(unlocked yes)
			(layer "F.Fab")
			(hide yes)
			(effects
				(font
					(size 1.016 1.016)
					(thickness 0.1524)
				)
			)
		)
		(duplicate_pad_numbers_are_jumpers no)
		(fp_line
			(start 1.651 4.2926)
			(end 1.651 3.0099)
			(stroke
				(width 0.1524)
				(type default)
			)
			(layer "F.SilkS")
		)
		(fp_line
			(start 8.509 4.2926)
			(end 1.651 4.2926)
			(stroke
				(width 0.1524)
				(type default)
			)
			(layer "F.SilkS")
		)
		(fp_line
			(start -23.4188 3.0099)
			(end -23.4188 -3.2512)
			(stroke
				(width 0.1524)
				(type default)
			)
			(layer "F.SilkS")
		)
		(fp_line
			(start 1.651 3.0099)
			(end -23.4188 3.0099)
			(stroke
				(width 0.1524)
				(type default)
			)
			(layer "F.SilkS")
		)
		(fp_line
			(start 8.509 3.0099)
			(end 8.509 4.2926)
			(stroke
				(width 0.1524)
				(type default)
			)
			(layer "F.SilkS")
		)
		(fp_line
			(start 23.4188 3.0099)
			(end 8.509 3.0099)
			(stroke
				(width 0.1524)
				(type default)
			)
			(layer "F.SilkS")
		)
		(fp_line
			(start -23.4188 -3.2512)
			(end 23.4188 -3.2512)
			(stroke
				(width 0.1524)
				(type default)
			)
			(layer "F.SilkS")
		)
		(fp_line
			(start 23.4188 -3.2512)
			(end 23.4188 3.0099)
			(stroke
				(width 0.1524)
				(type default)
			)
			(layer "F.SilkS")
		)
		(fp_line
			(start 15.5067 -3.3401)
			(end 16.2687 -3.3401)
			(stroke
				(width 0.3302)
				(type default)
			)
			(layer "F.SilkS")
		)
		(fp_poly
			(pts
				(xy 15.868904 -3.230372) (xy 16.503904 -3.865372) (xy 15.233904 -3.865372)
			)
			(stroke
				(width 0)
				(type default)
			)
			(fill yes)
			(layer "F.SilkS")
		)
		(fp_poly
			(pts
				(xy -22.8727 -2.7559) (xy 22.8727 -2.7559) (xy 22.8727 2.7559) (xy 8.255 2.7559) (xy 8.255 3.5179)
				(xy 1.905 3.5179) (xy 1.905 2.7559) (xy -22.8727 2.7559)
			)
			(stroke
				(width 0)
				(type default)
			)
			(fill no)
			(layer "F.CrtYd")
		)
		(fp_poly
			(pts
				(xy 1.397 4.5466) (xy 1.397 3.2639) (xy -23.6728 3.2639) (xy -23.6728 -3.5052) (xy 23.6728 -3.5052)
				(xy 23.6728 -0.00635) (xy 22.8727 -0.00635) (xy 22.8727 -2.7559) (xy -22.8727 -2.7559) (xy -22.8727 2.7559)
				(xy 1.905 2.7559) (xy 1.905 3.5179) (xy 8.255 3.5179) (xy 8.255 2.7559) (xy 22.8727 2.7559) (xy 22.8727 0.00635)
				(xy 23.6728 0.00635) (xy 23.6728 3.2639) (xy 8.763 3.2639) (xy 8.763 4.5466)
			)
			(stroke
				(width 0)
				(type default)
			)
			(fill no)
			(layer "F.CrtYd")
		)
		(fp_poly
			(pts
				(xy 1.397 4.5466) (xy 1.397 3.2639) (xy -23.6728 3.2639) (xy -23.6728 -3.5052) (xy 23.6728 -3.5052)
				(xy 23.6728 3.2639) (xy 8.763 3.2639) (xy 8.763 4.5466)
			)
			(stroke
				(width 0)
				(type default)
			)
			(fill no)
			(layer "F.Fab")
		)
		(pad "" np_thru_hole circle
			(at -18.874994 0 270)
			(size 0.254 0.254)
			(drill 1.3462)
			(layers "*.Cu" "*.Mask")
			(clearance 0.9017)
			(thermal_gap 0.9017)
		)
		(pad "" np_thru_hole circle
			(at 18.874994 0 270)
			(size 0.254 0.254)
			(drill 0.9398)
			(layers "*.Cu" "*.Mask")
			(clearance 0.6985)
			(thermal_gap 0.6985)
		)
		(pad "G1" smd rect
			(at 21.874988 0 270)
			(size 2.5908 2.5908)
			(layers "F.Cu" "F.Mask" "F.Paste")
			(net "GND")
		)
		(pad "G2" smd rect
			(at -21.874988 0 270)
			(size 2.5908 2.5908)
			(layers "F.Cu" "F.Mask" "F.Paste")
			(net "GND")
		)
		(pad "P1" smd rect
			(at 1.905 -1.82499 270)
			(size 0.6096 2.3622)
			(layers "F.Cu" "F.Mask" "F.Paste")
			(net "Net_1754")
		)
		(pad "P2" smd rect
			(at 0.635 -1.82499 270)
			(size 0.6096 2.3622)
			(layers "F.Cu" "F.Mask" "F.Paste")
			(net "Net_1755")
		)
		(pad "P3" smd rect
			(at -0.635 -1.82499 270)
			(size 0.6096 2.3622)
			(layers "F.Cu" "F.Mask" "F.Paste")
			(net "Net_1756")
		)
		(pad "P4" smd rect
			(at -1.905 -1.82499 270)
			(size 0.6096 2.3622)
			(layers "F.Cu" "F.Mask" "F.Paste")
			(net "GND")
		)
		(pad "P5" smd rect
			(at -3.175 -1.82499 270)
			(size 0.6096 2.3622)
			(layers "F.Cu" "F.Mask" "F.Paste")
			(net "HDD_PRSNT_10")
		)
		(pad "P6" smd rect
			(at -4.445 -1.82499 270)
			(size 0.6096 2.3622)
			(layers "F.Cu" "F.Mask" "F.Paste")
			(net "GND")
		)
		(pad "P7" smd rect
			(at -5.715 -1.82499 270)
			(size 0.6096 2.3622)
			(layers "F.Cu" "F.Mask" "F.Paste")
			(net "5V_PRE_10")
		)
		(pad "P8" smd rect
			(at -6.985 -1.82499 270)
			(size 0.6096 2.3622)
			(layers "F.Cu" "F.Mask" "F.Paste")
			(net "P5V_HDD10")
		)
		(pad "P9" smd rect
			(at -8.255 -1.82499 270)
			(size 0.6096 2.3622)
			(layers "F.Cu" "F.Mask" "F.Paste")
			(net "P5V_HDD10")
		)
		(pad "P10" smd rect
			(at -9.525 -1.82499 270)
			(size 0.6096 2.3622)
			(layers "F.Cu" "F.Mask" "F.Paste")
			(net "GND")
		)
		(pad "P11" smd rect
			(at -10.795 -1.82499 270)
			(size 0.6096 2.3622)
			(layers "F.Cu" "F.Mask" "F.Paste")
			(net "ACT_HDD_10")
		)
		(pad "P12" smd rect
			(at -12.065 -1.82499 270)
			(size 0.6096 2.3622)
			(layers "F.Cu" "F.Mask" "F.Paste")
			(net "GND")
		)
		(pad "P13" smd rect
			(at -13.335 -1.82499 270)
			(size 0.6096 2.3622)
			(layers "F.Cu" "F.Mask" "F.Paste")
			(net "12V_PRE_10")
		)
		(pad "P14" smd rect
			(at -14.605 -1.82499 270)
			(size 0.6096 2.3622)
			(layers "F.Cu" "F.Mask" "F.Paste")
			(net "P12V_HDD10")
		)
		(pad "P15" smd rect
			(at -15.875 -1.82499 270)
			(size 0.6096 2.3622)
			(layers "F.Cu" "F.Mask" "F.Paste")
			(net "P12V_HDD10")
		)
		(pad "S1" smd rect
			(at 15.875 -1.82499 270)
			(size 0.6096 2.3622)
			(layers "F.Cu" "F.Mask" "F.Paste")
			(net "GND")
		)
		(pad "S2" smd rect
			(at 14.605 -1.82499 270)
			(size 0.6096 2.3622)
			(layers "F.Cu" "F.Mask" "F.Paste")
			(net "SAS_HDD_RX_P10")
		)
		(pad "S3" smd rect
			(at 13.335 -1.82499 270)
			(size 0.6096 2.3622)
			(layers "F.Cu" "F.Mask" "F.Paste")
			(net "SAS_HDD_RX_N10")
		)
		(pad "S4" smd rect
			(at 12.065 -1.82499 270)
			(size 0.6096 2.3622)
			(layers "F.Cu" "F.Mask" "F.Paste")
			(net "GND")
		)
		(pad "S5" smd rect
			(at 10.795 -1.82499 270)
			(size 0.6096 2.3622)
			(layers "F.Cu" "F.Mask" "F.Paste")
			(net "PHY_DRV_B_TO_SCC_B_10_DN")
		)
		(pad "S6" smd rect
			(at 9.525 -1.82499 270)
			(size 0.6096 2.3622)
			(layers "F.Cu" "F.Mask" "F.Paste")
			(net "PHY_DRV_B_TO_SCC_B_10_DP")
		)
		(pad "S7" smd rect
			(at 8.255 -1.82499 270)
			(size 0.6096 2.3622)
			(layers "F.Cu" "F.Mask" "F.Paste")
			(net "GND")
		)
		(pad "S8" smd rect
			(at 7.480046 2.845054 270)
			(size 0.508 2.3622)
			(layers "F.Cu" "F.Mask" "F.Paste")
			(net "GND")
		)
		(pad "S9" smd rect
			(at 6.679946 2.845054 270)
			(size 0.508 2.3622)
			(layers "F.Cu" "F.Mask" "F.Paste")
			(net "Net_433")
		)
		(pad "S10" smd rect
			(at 5.8801 2.845054 270)
			(size 0.508 2.3622)
			(layers "F.Cu" "F.Mask" "F.Paste")
			(net "Net_325")
		)
		(pad "S11" smd rect
			(at 5.08 2.845054 270)
			(size 0.508 2.3622)
			(layers "F.Cu" "F.Mask" "F.Paste")
			(net "GND")
		)
		(pad "S12" smd rect
			(at 4.2799 2.845054 270)
			(size 0.508 2.3622)
			(layers "F.Cu" "F.Mask" "F.Paste")
			(net "Net_361")
		)
		(pad "S13" smd rect
			(at 3.480054 2.845054 270)
			(size 0.508 2.3622)
			(layers "F.Cu" "F.Mask" "F.Paste")
			(net "Net_397")
		)
		(pad "S14" smd rect
			(at 2.679954 2.845054 270)
			(size 0.508 2.3622)
			(layers "F.Cu" "F.Mask" "F.Paste")
			(net "GND")
		)
		(zone
			(layer "F.Cu")
			(hatch none 0.5)
			(connect_pads
				(clearance 0)
			)
			(min_thickness 0.25)
			(keepout
				(tracks not_allowed)
				(vias allowed)
				(pads allowed)
				(copperpour not_allowed)
				(footprints allowed)
			)
			(placement
				(enabled no)
				(sheetname "")
			)
			(fill
				(thermal_gap 0.5)
				(thermal_bridge_width 0.5)
				(island_removal_mode 0)
			)
			(polygon
				(pts
					(xy 455.407522 -275.648674) (xy 448.333622 -275.648674) (xy 448.333622 -282.582874) (xy 449.438522 -282.582874)
					(xy 449.438522 -278.468074) (xy 454.061322 -278.468074) (xy 454.061322 -282.582874) (xy 455.407522 -282.582874)
				)
			)
		)
		(zone
			(layer "F.Cu")
			(hatch none 0.5)
			(connect_pads
				(clearance 0)
			)
			(min_thickness 0.25)
			(keepout
				(tracks allowed)
				(vias not_allowed)
				(pads allowed)
				(copperpour not_allowed)
				(footprints allowed)
			)
			(placement
				(enabled no)
				(sheetname "")
			)
			(fill
				(thermal_gap 0.5)
				(thermal_bridge_width 0.5)
				(island_removal_mode 0)
			)
			(polygon
				(pts
					(xy 455.407522 -275.648674) (xy 448.333622 -275.648674) (xy 448.333622 -282.582874) (xy 449.438522 -282.582874)
					(xy 449.438522 -278.468074) (xy 454.061322 -278.468074) (xy 454.061322 -282.582874) (xy 455.407522 -282.582874)
				)
			)
		)
		(zone
			(layer "F.Cu")
			(hatch none 0.5)
			(connect_pads
				(clearance 0)
			)
			(min_thickness 0.25)
			(keepout
				(tracks not_allowed)
				(vias allowed)
				(pads allowed)
				(copperpour not_allowed)
				(footprints allowed)
			)
			(placement
				(enabled no)
				(sheetname "")
			)
			(fill
				(thermal_gap 0.5)
				(thermal_bridge_width 0.5)
				(island_removal_mode 0)
			)
			(polygon
				(pts
					(xy 455.407522 -242.171474) (xy 448.333622 -242.171474) (xy 448.333622 -235.237274) (xy 449.438522 -235.237274)
					(xy 449.438522 -239.352074) (xy 454.061322 -239.352074) (xy 454.061322 -235.237274) (xy 455.407522 -235.237274)
				)
			)
		)
		(zone
			(layer "F.Cu")
			(hatch none 0.5)
			(connect_pads
				(clearance 0)
			)
			(min_thickness 0.25)
			(keepout
				(tracks allowed)
				(vias not_allowed)
				(pads allowed)
				(copperpour not_allowed)
				(footprints allowed)
			)
			(placement
				(enabled no)
				(sheetname "")
			)
			(fill
				(thermal_gap 0.5)
				(thermal_bridge_width 0.5)
				(island_removal_mode 0)
			)
			(polygon
				(pts
					(xy 455.407522 -242.171474) (xy 448.333622 -242.171474) (xy 448.333622 -235.237274) (xy 449.438522 -235.237274)
					(xy 449.438522 -239.352074) (xy 454.061322 -239.352074) (xy 454.061322 -235.237274) (xy 455.407522 -235.237274)
				)
			)
		)
		(zone
			(layers "F.Cu" "B.Cu" "In1.Cu" "In2.Cu" "In3.Cu" "In4.Cu" "In5.Cu" "In6.Cu")
			(hatch none 0.5)
			(connect_pads
				(clearance 0)
			)
			(min_thickness 0.25)
			(keepout
				(tracks not_allowed)
				(vias allowed)
				(pads allowed)
				(copperpour not_allowed)
				(footprints allowed)
			)
			(placement
				(enabled no)
				(sheetname "")
			)
			(fill
				(thermal_gap 0.5)
				(thermal_bridge_width 0.5)
				(island_removal_mode 0)
			)
			(polygon
				(pts
					(arc
						(start 452.524622 -240.03508)
						(mid 450.975222 -240.03508)
						(end 452.524622 -240.03508)
					)
				)
			)
		)
		(zone
			(layers "F.Cu" "B.Cu" "In1.Cu" "In2.Cu" "In3.Cu" "In4.Cu" "In5.Cu" "In6.Cu")
			(hatch none 0.5)
			(connect_pads
				(clearance 0)
			)
			(min_thickness 0.25)
			(keepout
				(tracks not_allowed)
				(vias allowed)
				(pads allowed)
				(copperpour not_allowed)
				(footprints allowed)
			)
			(placement
				(enabled no)
				(sheetname "")
			)
			(fill
				(thermal_gap 0.5)
				(thermal_bridge_width 0.5)
				(island_removal_mode 0)
			)
			(polygon
				(pts
					(arc
						(start 452.727822 -277.785068)
						(mid 450.772022 -277.785068)
						(end 452.727822 -277.785068)
					)
				)
			)
		)
	)
	(footprint ""
		(layer "F.Cu")
		(at 250.327668 -222.9612)
		(property "Reference" "R107"
			(at 0 0 0)
			(layer "F.SilkS")
			(hide yes)
			(effects
				(font
					(size 1.27 1.27)
				)
			)
		)
		(property "Value" "4K7R2F-GP"
			(at 0.064008 -3.993896 0)
			(unlocked yes)
			(layer "F.Fab")
			(hide yes)
			(effects
				(font
					(size 1.016 1.016)
					(thickness 0.1524)
				)
			)
		)
		(property "Device Type" "R402H16"
			(at 0.064008 -5.517896 0)
			(unlocked yes)
			(layer "F.Fab")
			(hide yes)
			(effects
				(font
					(size 1.016 1.016)
					(thickness 0.1524)
				)
			)
		)
		(duplicate_pad_numbers_are_jumpers no)
		(fp_line
			(start -0.508 -0.9398)
			(end -0.508 0.9398)
			(stroke
				(width 0.1524)
				(type default)
			)
			(layer "F.SilkS")
		)
		(fp_line
			(start 0.508 -0.9398)
			(end -0.508 -0.9398)
			(stroke
				(width 0.1524)
				(type default)
			)
			(layer "F.SilkS")
		)
		(fp_rect
			(start -0.508 0.9398)
			(end 0.508 -0.9398)
			(stroke
				(width 0)
				(type default)
			)
			(fill no)
			(layer "F.CrtYd")
		)
		(fp_rect
			(start -0.508 0.9398)
			(end 0.508 -0.9398)
			(stroke
				(width 0)
				(type default)
			)
			(fill no)
			(layer "F.Fab")
		)
		(pad "1" smd custom
			(at 0 -0.4445)
			(size 0.1397 0.1397)
			(layers "F.Cu" "F.Mask" "F.Paste")
			(net "P3V3_STBY_B")
			(options
				(clearance outline)
				(anchor circle)
			)
			(primitives
				(gr_poly
					(pts
						(arc
							(start -0.1778 -0.2794)
							(mid -0.249642 -0.249642)
							(end -0.2794 -0.1778)
						)
						(arc
							(start -0.2794 0.1778)
							(mid -0.249642 0.249642)
							(end -0.1778 0.2794)
						)
						(arc
							(start 0.1778 0.2794)
							(mid 0.249642 0.249642)
							(end 0.2794 0.1778)
						)
						(arc
							(start 0.2794 -0.1778)
							(mid 0.249642 -0.249642)
							(end 0.1778 -0.2794)
						)
					)
					(width 0)
					(fill yes)
				)
			)
		)
		(pad "2" smd custom
			(at 0 0.4445)
			(size 0.1397 0.1397)
			(layers "F.Cu" "F.Mask" "F.Paste")
			(net "EEPROM_A1")
			(options
				(clearance outline)
				(anchor circle)
			)
			(primitives
				(gr_poly
					(pts
						(arc
							(start -0.1778 -0.2794)
							(mid -0.249642 -0.249642)
							(end -0.2794 -0.1778)
						)
						(arc
							(start -0.2794 0.1778)
							(mid -0.249642 0.249642)
							(end -0.1778 0.2794)
						)
						(arc
							(start 0.1778 0.2794)
							(mid 0.249642 0.249642)
							(end 0.2794 0.1778)
						)
						(arc
							(start 0.2794 -0.1778)
							(mid 0.249642 -0.249642)
							(end 0.1778 -0.2794)
						)
					)
					(width 0)
					(fill yes)
				)
			)
		)
	)
	(footprint ""
		(layer "F.Cu")
		(at 112.450118 -180.399944)
		(property "Reference" "LED4"
			(at 0 0 0)
			(layer "F.SilkS")
			(hide yes)
			(effects
				(font
					(size 1.27 1.27)
				)
			)
		)
		(property "Value" "LED-BY-19-GP"
			(at -2.132076 1.414018 0)
			(unlocked yes)
			(layer "F.Fab")
			(hide yes)
			(effects
				(font
					(size 1.016 1.016)
					(thickness 0.1524)
				)
			)
		)
		(property "Device Type" "LED-1615-4PH26"
			(at -2.132076 -0.109982 0)
			(unlocked yes)
			(layer "F.Fab")
			(hide yes)
			(effects
				(font
					(size 1.016 1.016)
					(thickness 0.1524)
				)
			)
		)
		(duplicate_pad_numbers_are_jumpers no)
		(fp_line
			(start -1.2954 0.254)
			(end -1.2954 1.6002)
			(stroke
				(width 0.508)
				(type default)
			)
			(layer "F.SilkS")
		)
		(fp_line
			(start -1.2954 1.6002)
			(end 1.2954 1.6002)
			(stroke
				(width 0.508)
				(type default)
			)
			(layer "F.SilkS")
		)
		(fp_line
			(start -1.1176 -1.4224)
			(end 1.1176 -1.4224)
			(stroke
				(width 0.1524)
				(type default)
			)
			(layer "F.SilkS")
		)
		(fp_line
			(start -1.1176 1.4224)
			(end -1.1176 -1.4224)
			(stroke
				(width 0.1524)
				(type default)
			)
			(layer "F.SilkS")
		)
		(fp_line
			(start 1.1176 -1.4224)
			(end 1.1176 1.4224)
			(stroke
				(width 0.1524)
				(type default)
			)
			(layer "F.SilkS")
		)
		(fp_line
			(start 1.1176 1.4224)
			(end -1.1176 1.4224)
			(stroke
				(width 0.1524)
				(type default)
			)
			(layer "F.SilkS")
		)
		(fp_line
			(start 1.2954 1.6002)
			(end 1.2954 0.254)
			(stroke
				(width 0.508)
				(type default)
			)
			(layer "F.SilkS")
		)
		(fp_rect
			(start -0.7493 0.8001)
			(end 0.7493 -0.8001)
			(stroke
				(width 0)
				(type default)
			)
			(fill no)
			(layer "F.CrtYd")
		)
		(fp_poly
			(pts
				(xy -1.3716 1.6764) (xy -1.3716 -1.6764) (xy 1.3716 -1.6764) (xy 1.3716 0.0635) (xy 0.7493 0.0635)
				(xy 0.7493 -0.8001) (xy -0.7493 -0.8001) (xy -0.7493 0.8001) (xy 0.7493 0.8001) (xy 0.7493 0.0762)
				(xy 1.3716 0.0762) (xy 1.3716 1.6764)
			)
			(stroke
				(width 0)
				(type default)
			)
			(fill no)
			(layer "F.CrtYd")
		)
		(fp_rect
			(start -1.3716 1.6764)
			(end 1.3716 -1.6764)
			(stroke
				(width 0)
				(type default)
			)
			(fill no)
			(layer "F.Fab")
		)
		(pad "1" smd rect
			(at 0.50038 -0.73025)
			(size 0.7112 0.8636)
			(layers "F.Cu" "F.Mask" "F.Paste")
			(net "DRV_ACT_3")
		)
		(pad "2" smd rect
			(at -0.50038 -0.73025)
			(size 0.7112 0.8636)
			(layers "F.Cu" "F.Mask" "F.Paste")
			(net "FLT_HDD3")
		)
		(pad "3" smd rect
			(at 0.50038 0.73025)
			(size 0.7112 0.8636)
			(layers "F.Cu" "F.Mask" "F.Paste")
			(net "DRV_ACT_3_N")
		)
		(pad "4" smd rect
			(at -0.50038 0.73025)
			(size 0.7112 0.8636)
			(layers "F.Cu" "F.Mask" "F.Paste")
			(net "FLT_HDD3_N")
		)
	)
	(footprint ""
		(layer "F.Cu")
		(at 35.687 -151.003 90)
		(property "Reference" "R353"
			(at 0 0 90)
			(layer "F.SilkS")
			(hide yes)
			(effects
				(font
					(size 1.27 1.27)
				)
			)
		)
		(property "Value" "220R3F-1-GP"
			(at -0.0254 -2.5146 90)
			(unlocked yes)
			(layer "F.Fab")
			(hide yes)
			(effects
				(font
					(size 1.016 1.016)
					(thickness 0.1524)
				)
			)
		)
		(property "Device Type" "R603H22"
			(at -0.0254 -4.0386 90)
			(unlocked yes)
			(layer "F.Fab")
			(hide yes)
			(effects
				(font
					(size 1.016 1.016)
					(thickness 0.1524)
				)
			)
		)
		(duplicate_pad_numbers_are_jumpers no)
		(fp_line
			(start 0.2032 0)
			(end 0.4826 0)
			(stroke
				(width 0.2032)
				(type default)
			)
			(layer "F.SilkS")
		)
		(fp_line
			(start -0.4826 0)
			(end -0.2032 0)
			(stroke
				(width 0.2032)
				(type default)
			)
			(layer "F.SilkS")
		)
		(fp_rect
			(start -0.5842 1.3335)
			(end 0.5842 -1.3335)
			(stroke
				(width 0)
				(type default)
			)
			(fill no)
			(layer "F.CrtYd")
		)
		(fp_rect
			(start -0.5842 1.3335)
			(end 0.5842 -1.3335)
			(stroke
				(width 0)
				(type default)
			)
			(fill no)
			(layer "F.Fab")
		)
		(pad "1" smd custom
			(at 0 -0.762 90)
			(size 0.2159 0.2159)
			(layers "F.Cu" "F.Mask" "F.Paste")
			(net "HDD_PRSNT_12")
			(options
				(clearance outline)
				(anchor circle)
			)
			(primitives
				(gr_poly
					(pts
						(arc
							(start -0.3302 -0.4318)
							(mid -0.402042 -0.402042)
							(end -0.4318 -0.3302)
						)
						(arc
							(start -0.4318 0.3302)
							(mid -0.402042 0.402042)
							(end -0.3302 0.4318)
						)
						(arc
							(start 0.3302 0.4318)
							(mid 0.402042 0.402042)
							(end 0.4318 0.3302)
						)
						(arc
							(start 0.4318 -0.3302)
							(mid 0.402042 -0.402042)
							(end 0.3302 -0.4318)
						)
					)
					(width 0)
					(fill yes)
				)
			)
		)
		(pad "2" smd custom
			(at 0 0.762 90)
			(size 0.2159 0.2159)
			(layers "F.Cu" "F.Mask" "F.Paste")
			(net "DRIVE_B_12_INS")
			(options
				(clearance outline)
				(anchor circle)
			)
			(primitives
				(gr_poly
					(pts
						(arc
							(start -0.3302 -0.4318)
							(mid -0.402042 -0.402042)
							(end -0.4318 -0.3302)
						)
						(arc
							(start -0.4318 0.3302)
							(mid -0.402042 0.402042)
							(end -0.3302 0.4318)
						)
						(arc
							(start 0.3302 0.4318)
							(mid 0.402042 0.402042)
							(end 0.4318 0.3302)
						)
						(arc
							(start 0.4318 -0.3302)
							(mid 0.402042 -0.402042)
							(end 0.3302 -0.4318)
						)
					)
					(width 0)
					(fill yes)
				)
			)
		)
	)
	(footprint ""
		(layer "F.Cu")
		(at 445.415924 -269.705074)
		(property "Reference" "TP71"
			(at 0 0 0)
			(layer "F.SilkS")
			(hide yes)
			(effects
				(font
					(size 1.27 1.27)
				)
			)
		)
		(property "Value" "*"
			(at -0.0508 -1.6764 0)
			(unlocked yes)
			(layer "F.Fab")
			(hide yes)
			(effects
				(font
					(size 1.016 1.016)
					(thickness 0.1524)
				)
			)
		)
		(property "Device Type" "TPAD32"
			(at -0.0508 -3.2004 0)
			(unlocked yes)
			(layer "F.Fab")
			(hide yes)
			(effects
				(font
					(size 1.016 1.016)
					(thickness 0.1524)
				)
			)
		)
		(duplicate_pad_numbers_are_jumpers no)
		(fp_poly
			(pts
				(arc
					(start 0.4064 0)
					(mid -0.4064 0)
					(end 0.4064 0)
				)
			)
			(stroke
				(width 0)
				(type default)
			)
			(fill no)
			(layer "F.CrtYd")
		)
		(fp_poly
			(pts
				(arc
					(start 0.7112 0)
					(mid -0.7112 0)
					(end 0.7112 0)
				)
			)
			(stroke
				(width 0)
				(type default)
			)
			(fill no)
			(layer "F.Fab")
		)
		(pad "1" smd circle
			(at 0 0)
			(size 0.8128 0.8128)
			(layers "F.Cu" "F.Mask" "F.Paste")
			(net "ACT_HDD_10")
		)
	)
	(footprint ""
		(layer "F.Cu")
		(at 168.529 -366.776 90)
		(property "Reference" "R984"
			(at 0 0 90)
			(layer "F.SilkS")
			(hide yes)
			(effects
				(font
					(size 1.27 1.27)
				)
			)
		)
		(property "Value" "10R2F-L-GP"
			(at 0.064008 -3.993896 90)
			(unlocked yes)
			(layer "F.Fab")
			(hide yes)
			(effects
				(font
					(size 1.016 1.016)
					(thickness 0.1524)
				)
			)
		)
		(property "Device Type" "R402H14"
			(at 0.064008 -5.517896 90)
			(unlocked yes)
			(layer "F.Fab")
			(hide yes)
			(effects
				(font
					(size 1.016 1.016)
					(thickness 0.1524)
				)
			)
		)
		(duplicate_pad_numbers_are_jumpers no)
		(fp_line
			(start 0.508 -0.9398)
			(end -0.508 -0.9398)
			(stroke
				(width 0.1524)
				(type default)
			)
			(layer "F.SilkS")
		)
		(fp_line
			(start -0.508 -0.9398)
			(end -0.508 0.9398)
			(stroke
				(width 0.1524)
				(type default)
			)
			(layer "F.SilkS")
		)
		(fp_rect
			(start -0.508 0.9398)
			(end 0.508 -0.9398)
			(stroke
				(width 0)
				(type default)
			)
			(fill no)
			(layer "F.CrtYd")
		)
		(fp_rect
			(start -0.508 0.9398)
			(end 0.508 -0.9398)
			(stroke
				(width 0)
				(type default)
			)
			(fill no)
			(layer "F.Fab")
		)
		(pad "1" smd custom
			(at 0 -0.4445 90)
			(size 0.1397 0.1397)
			(layers "F.Cu" "F.Mask" "F.Paste")
			(net "P12V_CLIP")
			(options
				(clearance outline)
				(anchor circle)
			)
			(primitives
				(gr_poly
					(pts
						(arc
							(start -0.1778 -0.2794)
							(mid -0.249642 -0.249642)
							(end -0.2794 -0.1778)
						)
						(arc
							(start -0.2794 0.1778)
							(mid -0.249642 0.249642)
							(end -0.1778 0.2794)
						)
						(arc
							(start 0.1778 0.2794)
							(mid 0.249642 0.249642)
							(end 0.2794 0.1778)
						)
						(arc
							(start 0.2794 -0.1778)
							(mid 0.249642 -0.249642)
							(end 0.1778 -0.2794)
						)
					)
					(width 0)
					(fill yes)
				)
			)
		)
		(pad "2" smd custom
			(at 0 0.4445 90)
			(size 0.1397 0.1397)
			(layers "F.Cu" "F.Mask" "F.Paste")
			(net "MB0_P12V_HS")
			(options
				(clearance outline)
				(anchor circle)
			)
			(primitives
				(gr_poly
					(pts
						(arc
							(start -0.1778 -0.2794)
							(mid -0.249642 -0.249642)
							(end -0.2794 -0.1778)
						)
						(arc
							(start -0.2794 0.1778)
							(mid -0.249642 0.249642)
							(end -0.1778 0.2794)
						)
						(arc
							(start 0.1778 0.2794)
							(mid 0.249642 0.249642)
							(end 0.2794 0.1778)
						)
						(arc
							(start 0.2794 -0.1778)
							(mid 0.249642 -0.249642)
							(end 0.1778 -0.2794)
						)
					)
					(width 0)
					(fill yes)
				)
			)
		)
	)
	(footprint ""
		(layer "F.Cu")
		(at 172.593 -145.796)
		(property "Reference" "Q78"
			(at 0 0 0)
			(layer "F.SilkS")
			(hide yes)
			(effects
				(font
					(size 1.27 1.27)
				)
			)
		)
		(property "Value" "AO4407AL-GP"
			(at -3.707384 -1.5367 0)
			(unlocked yes)
			(layer "F.Fab")
			(hide yes)
			(effects
				(font
					(size 1.016 1.016)
					(thickness 0.1524)
				)
			)
		)
		(property "Device Type" "SOIC8H69"
			(at -3.707384 -3.0607 0)
			(unlocked yes)
			(layer "F.Fab")
			(hide yes)
			(effects
				(font
					(size 1.016 1.016)
					(thickness 0.1524)
				)
			)
		)
		(duplicate_pad_numbers_are_jumpers no)
		(fp_line
			(start -2.7432 -1.4224)
			(end -2.7432 1.4224)
			(stroke
				(width 0.1524)
				(type default)
			)
			(layer "F.SilkS")
		)
		(fp_line
			(start -2.7432 1.4224)
			(end -2.6416 1.4224)
			(stroke
				(width 0.1524)
				(type default)
			)
			(layer "F.SilkS")
		)
		(fp_line
			(start -2.7432 1.4224)
			(end 2.1336 1.4224)
			(stroke
				(width 0.1524)
				(type default)
			)
			(layer "F.SilkS")
		)
		(fp_line
			(start -2.7178 -0.508)
			(end -2.1844 -0.0508)
			(stroke
				(width 0.1524)
				(type default)
			)
			(layer "F.SilkS")
		)
		(fp_line
			(start -2.6289 3.4417)
			(end -2.6289 1.4732)
			(stroke
				(width 0.381)
				(type default)
			)
			(layer "F.SilkS")
		)
		(fp_line
			(start -2.1844 -0.0508)
			(end -2.7178 0.508)
			(stroke
				(width 0.1524)
				(type default)
			)
			(layer "F.SilkS")
		)
		(fp_line
			(start 2.1336 -1.4224)
			(end -2.7432 -1.4224)
			(stroke
				(width 0.1524)
				(type default)
			)
			(layer "F.SilkS")
		)
		(fp_line
			(start 2.1336 1.4224)
			(end 2.1336 -1.4224)
			(stroke
				(width 0.1524)
				(type default)
			)
			(layer "F.SilkS")
		)
		(fp_poly
			(pts
				(xy -2.2098 -1.4224) (xy -2.2098 1.4224) (xy 2.2098 1.4224) (xy 2.2098 -1.4224)
			)
			(stroke
				(width 0)
				(type default)
			)
			(fill yes)
			(layer "F.SilkS")
		)
		(fp_rect
			(start -2.450084 2.999994)
			(end 2.450084 -2.999994)
			(stroke
				(width 0)
				(type default)
			)
			(fill no)
			(layer "F.CrtYd")
		)
		(fp_poly
			(pts
				(xy -2.8194 3.6322) (xy -2.8194 -3.6322) (xy 2.8194 -3.6322) (xy 2.8194 1.18364) (xy 2.450084 1.18364)
				(xy 2.450084 -2.999994) (xy -2.450084 -2.999994) (xy -2.450084 2.999994) (xy 2.450084 2.999994)
				(xy 2.450084 1.18618) (xy 2.8194 1.18618) (xy 2.8194 3.6322)
			)
			(stroke
				(width 0)
				(type default)
			)
			(fill no)
			(layer "F.CrtYd")
		)
		(fp_rect
			(start -2.8194 3.6322)
			(end 2.8194 -3.6322)
			(stroke
				(width 0)
				(type default)
			)
			(fill no)
			(layer "F.Fab")
		)
		(pad "1" smd rect
			(at -1.905 2.54)
			(size 0.635 1.651)
			(layers "F.Cu" "F.Mask" "F.Paste")
			(net "P12V_B")
		)
		(pad "2" smd rect
			(at -0.635 2.54)
			(size 0.635 1.651)
			(layers "F.Cu" "F.Mask" "F.Paste")
			(net "P12V_B")
		)
		(pad "3" smd rect
			(at 0.635 2.54)
			(size 0.635 1.651)
			(layers "F.Cu" "F.Mask" "F.Paste")
			(net "P12V_B")
		)
		(pad "4" smd rect
			(at 1.905 2.54)
			(size 0.635 1.651)
			(layers "F.Cu" "F.Mask" "F.Paste")
			(net "SW_HDD_N17")
		)
		(pad "5" smd rect
			(at 1.905 -2.54)
			(size 0.635 1.651)
			(layers "F.Cu" "F.Mask" "F.Paste")
			(net "P12V_HDD17")
		)
		(pad "6" smd rect
			(at 0.635 -2.54)
			(size 0.635 1.651)
			(layers "F.Cu" "F.Mask" "F.Paste")
			(net "P12V_HDD17")
		)
		(pad "7" smd rect
			(at -0.635 -2.54)
			(size 0.635 1.651)
			(layers "F.Cu" "F.Mask" "F.Paste")
			(net "P12V_HDD17")
		)
		(pad "8" smd rect
			(at -1.905 -2.54)
			(size 0.635 1.651)
			(layers "F.Cu" "F.Mask" "F.Paste")
			(net "P12V_HDD17")
		)
	)
	(footprint ""
		(layer "F.Cu")
		(at 462.915 -148.082)
		(property "Reference" "Q108"
			(at 0 0 0)
			(layer "F.SilkS")
			(hide yes)
			(effects
				(font
					(size 1.27 1.27)
				)
			)
		)
		(property "Value" "AO4407AL-GP"
			(at -3.707384 -1.5367 0)
			(unlocked yes)
			(layer "F.Fab")
			(hide yes)
			(effects
				(font
					(size 1.016 1.016)
					(thickness 0.1524)
				)
			)
		)
		(property "Device Type" "SOIC8H69"
			(at -3.707384 -3.0607 0)
			(unlocked yes)
			(layer "F.Fab")
			(hide yes)
			(effects
				(font
					(size 1.016 1.016)
					(thickness 0.1524)
				)
			)
		)
		(duplicate_pad_numbers_are_jumpers no)
		(fp_line
			(start -2.7432 -1.4224)
			(end -2.7432 1.4224)
			(stroke
				(width 0.1524)
				(type default)
			)
			(layer "F.SilkS")
		)
		(fp_line
			(start -2.7432 1.4224)
			(end -2.6416 1.4224)
			(stroke
				(width 0.1524)
				(type default)
			)
			(layer "F.SilkS")
		)
		(fp_line
			(start -2.7432 1.4224)
			(end 2.1336 1.4224)
			(stroke
				(width 0.1524)
				(type default)
			)
			(layer "F.SilkS")
		)
		(fp_line
			(start -2.7178 -0.508)
			(end -2.1844 -0.0508)
			(stroke
				(width 0.1524)
				(type default)
			)
			(layer "F.SilkS")
		)
		(fp_line
			(start -2.6289 3.4417)
			(end -2.6289 1.4732)
			(stroke
				(width 0.381)
				(type default)
			)
			(layer "F.SilkS")
		)
		(fp_line
			(start -2.1844 -0.0508)
			(end -2.7178 0.508)
			(stroke
				(width 0.1524)
				(type default)
			)
			(layer "F.SilkS")
		)
		(fp_line
			(start 2.1336 -1.4224)
			(end -2.7432 -1.4224)
			(stroke
				(width 0.1524)
				(type default)
			)
			(layer "F.SilkS")
		)
		(fp_line
			(start 2.1336 1.4224)
			(end 2.1336 -1.4224)
			(stroke
				(width 0.1524)
				(type default)
			)
			(layer "F.SilkS")
		)
		(fp_poly
			(pts
				(xy -2.2098 -1.4224) (xy -2.2098 1.4224) (xy 2.2098 1.4224) (xy 2.2098 -1.4224)
			)
			(stroke
				(width 0)
				(type default)
			)
			(fill yes)
			(layer "F.SilkS")
		)
		(fp_rect
			(start -2.450084 2.999994)
			(end 2.450084 -2.999994)
			(stroke
				(width 0)
				(type default)
			)
			(fill no)
			(layer "F.CrtYd")
		)
		(fp_poly
			(pts
				(xy -2.8194 3.6322) (xy -2.8194 -3.6322) (xy 2.8194 -3.6322) (xy 2.8194 1.18364) (xy 2.450084 1.18364)
				(xy 2.450084 -2.999994) (xy -2.450084 -2.999994) (xy -2.450084 2.999994) (xy 2.450084 2.999994)
				(xy 2.450084 1.18618) (xy 2.8194 1.18618) (xy 2.8194 3.6322)
			)
			(stroke
				(width 0)
				(type default)
			)
			(fill no)
			(layer "F.CrtYd")
		)
		(fp_rect
			(start -2.8194 3.6322)
			(end 2.8194 -3.6322)
			(stroke
				(width 0)
				(type default)
			)
			(fill no)
			(layer "F.Fab")
		)
		(pad "1" smd rect
			(at -1.905 2.54)
			(size 0.635 1.651)
			(layers "F.Cu" "F.Mask" "F.Paste")
			(net "P12V_B")
		)
		(pad "2" smd rect
			(at -0.635 2.54)
			(size 0.635 1.651)
			(layers "F.Cu" "F.Mask" "F.Paste")
			(net "P12V_B")
		)
		(pad "3" smd rect
			(at 0.635 2.54)
			(size 0.635 1.651)
			(layers "F.Cu" "F.Mask" "F.Paste")
			(net "P12V_B")
		)
		(pad "4" smd rect
			(at 1.905 2.54)
			(size 0.635 1.651)
			(layers "F.Cu" "F.Mask" "F.Paste")
			(net "SW_HDD_N22")
		)
		(pad "5" smd rect
			(at 1.905 -2.54)
			(size 0.635 1.651)
			(layers "F.Cu" "F.Mask" "F.Paste")
			(net "P12V_HDD22")
		)
		(pad "6" smd rect
			(at 0.635 -2.54)
			(size 0.635 1.651)
			(layers "F.Cu" "F.Mask" "F.Paste")
			(net "P12V_HDD22")
		)
		(pad "7" smd rect
			(at -0.635 -2.54)
			(size 0.635 1.651)
			(layers "F.Cu" "F.Mask" "F.Paste")
			(net "P12V_HDD22")
		)
		(pad "8" smd rect
			(at -1.905 -2.54)
			(size 0.635 1.651)
			(layers "F.Cu" "F.Mask" "F.Paste")
			(net "P12V_HDD22")
		)
	)
	(footprint ""
		(layer "F.Cu")
		(at 464.82 -143.891 90)
		(property "Reference" "C325"
			(at 0 0 90)
			(layer "F.SilkS")
			(hide yes)
			(effects
				(font
					(size 1.27 1.27)
				)
			)
		)
		(property "Value" "SCD033U25V2KX-GP"
			(at 1.1811 -2.7051 90)
			(unlocked yes)
			(layer "F.Fab")
			(hide yes)
			(effects
				(font
					(size 1.016 1.016)
					(thickness 0.1524)
				)
			)
		)
		(property "Device Type" "C402H22"
			(at 1.1811 -4.2291 90)
			(unlocked yes)
			(layer "F.Fab")
			(hide yes)
			(effects
				(font
					(size 1.016 1.016)
					(thickness 0.1524)
				)
			)
		)
		(duplicate_pad_numbers_are_jumpers no)
		(fp_rect
			(start -0.4318 0.9525)
			(end 0.4318 -0.9525)
			(stroke
				(width 0)
				(type default)
			)
			(fill no)
			(layer "F.CrtYd")
		)
		(fp_rect
			(start -0.4318 0.9525)
			(end 0.4318 -0.9525)
			(stroke
				(width 0)
				(type default)
			)
			(fill no)
			(layer "F.Fab")
		)
		(pad "1" smd custom
			(at 0 -0.4445 90)
			(size 0.1524 0.1524)
			(layers "F.Cu" "F.Mask" "F.Paste")
			(net "P12V_B")
			(options
				(clearance outline)
				(anchor circle)
			)
			(primitives
				(gr_poly
					(pts
						(arc
							(start 0.3048 -0.2032)
							(mid 0.275042 -0.275042)
							(end 0.2032 -0.3048)
						)
						(arc
							(start -0.2032 -0.3048)
							(mid -0.275042 -0.275042)
							(end -0.3048 -0.2032)
						)
						(arc
							(start -0.3048 0.2032)
							(mid -0.275042 0.275042)
							(end -0.2032 0.3048)
						)
						(arc
							(start 0.2032 0.3048)
							(mid 0.275042 0.275042)
							(end 0.3048 0.2032)
						)
					)
					(width 0)
					(fill yes)
				)
			)
		)
		(pad "2" smd custom
			(at 0 0.4445 90)
			(size 0.1524 0.1524)
			(layers "F.Cu" "F.Mask" "F.Paste")
			(net "SW_HDD_N22")
			(options
				(clearance outline)
				(anchor circle)
			)
			(primitives
				(gr_poly
					(pts
						(arc
							(start 0.3048 -0.2032)
							(mid 0.275042 -0.275042)
							(end 0.2032 -0.3048)
						)
						(arc
							(start -0.2032 -0.3048)
							(mid -0.275042 -0.275042)
							(end -0.3048 -0.2032)
						)
						(arc
							(start -0.3048 0.2032)
							(mid -0.275042 0.275042)
							(end -0.2032 0.3048)
						)
						(arc
							(start 0.2032 0.3048)
							(mid 0.275042 0.275042)
							(end 0.3048 0.2032)
						)
					)
					(width 0)
					(fill yes)
				)
			)
		)
	)
	(footprint ""
		(layer "F.Cu")
		(at 118.872 -160.401 180)
		(property "Reference" "C231"
			(at 0 0 180)
			(layer "F.SilkS")
			(hide yes)
			(effects
				(font
					(size 1.27 1.27)
				)
			)
		)
		(property "Value" "SC1U25V3KX-GP"
			(at 0 -2.8194 180)
			(unlocked yes)
			(layer "F.Fab")
			(hide yes)
			(effects
				(font
					(size 1.016 1.016)
					(thickness 0.1524)
				)
			)
		)
		(property "Device Type" "C603H36"
			(at 0 -4.3434 180)
			(unlocked yes)
			(layer "F.Fab")
			(hide yes)
			(effects
				(font
					(size 1.016 1.016)
					(thickness 0.1524)
				)
			)
		)
		(duplicate_pad_numbers_are_jumpers no)
		(fp_line
			(start 0.508 0)
			(end -0.508 0)
			(stroke
				(width 0.2032)
				(type default)
			)
			(layer "F.SilkS")
		)
		(fp_rect
			(start -0.5842 1.3335)
			(end 0.5842 -1.3335)
			(stroke
				(width 0)
				(type default)
			)
			(fill no)
			(layer "F.CrtYd")
		)
		(fp_rect
			(start -0.5842 1.3335)
			(end 0.5842 -1.3335)
			(stroke
				(width 0)
				(type default)
			)
			(fill no)
			(layer "F.Fab")
		)
		(pad "1" smd custom
			(at 0 -0.762 180)
			(size 0.2159 0.2159)
			(layers "F.Cu" "F.Mask" "F.Paste")
			(net "P12V_HDD15")
			(options
				(clearance outline)
				(anchor circle)
			)
			(primitives
				(gr_poly
					(pts
						(arc
							(start -0.3302 -0.4318)
							(mid -0.402042 -0.402042)
							(end -0.4318 -0.3302)
						)
						(arc
							(start -0.4318 0.3302)
							(mid -0.402042 0.402042)
							(end -0.3302 0.4318)
						)
						(arc
							(start 0.3302 0.4318)
							(mid 0.402042 0.402042)
							(end 0.4318 0.3302)
						)
						(arc
							(start 0.4318 -0.3302)
							(mid 0.402042 -0.402042)
							(end 0.3302 -0.4318)
						)
					)
					(width 0)
					(fill yes)
				)
			)
		)
		(pad "2" smd custom
			(at 0 0.762 180)
			(size 0.2159 0.2159)
			(layers "F.Cu" "F.Mask" "F.Paste")
			(net "GND")
			(options
				(clearance outline)
				(anchor circle)
			)
			(primitives
				(gr_poly
					(pts
						(arc
							(start -0.3302 -0.4318)
							(mid -0.402042 -0.402042)
							(end -0.4318 -0.3302)
						)
						(arc
							(start -0.4318 0.3302)
							(mid -0.402042 0.402042)
							(end -0.3302 0.4318)
						)
						(arc
							(start 0.3302 0.4318)
							(mid 0.402042 0.402042)
							(end 0.4318 0.3302)
						)
						(arc
							(start 0.4318 -0.3302)
							(mid 0.402042 -0.402042)
							(end 0.3302 -0.4318)
						)
					)
					(width 0)
					(fill yes)
				)
			)
		)
	)
	(footprint ""
		(layer "F.Cu")
		(at 423.577004 -364.236 -90)
		(property "Reference" "R961"
			(at 0 0 270)
			(layer "F.SilkS")
			(hide yes)
			(effects
				(font
					(size 1.27 1.27)
				)
			)
		)
		(property "Value" "10KR2F-2-GP"
			(at 0.064008 -3.993896 270)
			(unlocked yes)
			(layer "F.Fab")
			(hide yes)
			(effects
				(font
					(size 1.016 1.016)
					(thickness 0.1524)
				)
			)
		)
		(property "Device Type" "R402H16"
			(at 0.064008 -5.517896 270)
			(unlocked yes)
			(layer "F.Fab")
			(hide yes)
			(effects
				(font
					(size 1.016 1.016)
					(thickness 0.1524)
				)
			)
		)
		(duplicate_pad_numbers_are_jumpers no)
		(fp_line
			(start -0.508 -0.9398)
			(end -0.508 0.9398)
			(stroke
				(width 0.1524)
				(type default)
			)
			(layer "F.SilkS")
		)
		(fp_line
			(start 0.508 -0.9398)
			(end -0.508 -0.9398)
			(stroke
				(width 0.1524)
				(type default)
			)
			(layer "F.SilkS")
		)
		(fp_rect
			(start -0.508 0.9398)
			(end 0.508 -0.9398)
			(stroke
				(width 0)
				(type default)
			)
			(fill no)
			(layer "F.CrtYd")
		)
		(fp_rect
			(start -0.508 0.9398)
			(end 0.508 -0.9398)
			(stroke
				(width 0)
				(type default)
			)
			(fill no)
			(layer "F.Fab")
		)
		(pad "1" smd custom
			(at 0 -0.4445 270)
			(size 0.1397 0.1397)
			(layers "F.Cu" "F.Mask" "F.Paste")
			(net "GND")
			(options
				(clearance outline)
				(anchor circle)
			)
			(primitives
				(gr_poly
					(pts
						(arc
							(start -0.1778 -0.2794)
							(mid -0.249642 -0.249642)
							(end -0.2794 -0.1778)
						)
						(arc
							(start -0.2794 0.1778)
							(mid -0.249642 0.249642)
							(end -0.1778 0.2794)
						)
						(arc
							(start 0.1778 0.2794)
							(mid 0.249642 0.249642)
							(end 0.2794 0.1778)
						)
						(arc
							(start 0.2794 -0.1778)
							(mid 0.249642 -0.249642)
							(end 0.1778 -0.2794)
						)
					)
					(width 0)
					(fill yes)
				)
			)
		)
		(pad "2" smd custom
			(at 0 0.4445 270)
			(size 0.1397 0.1397)
			(layers "F.Cu" "F.Mask" "F.Paste")
			(net "FANTACH_F3")
			(options
				(clearance outline)
				(anchor circle)
			)
			(primitives
				(gr_poly
					(pts
						(arc
							(start -0.1778 -0.2794)
							(mid -0.249642 -0.249642)
							(end -0.2794 -0.1778)
						)
						(arc
							(start -0.2794 0.1778)
							(mid -0.249642 0.249642)
							(end -0.1778 0.2794)
						)
						(arc
							(start 0.1778 0.2794)
							(mid 0.249642 0.249642)
							(end 0.2794 0.1778)
						)
						(arc
							(start 0.2794 -0.1778)
							(mid 0.249642 -0.249642)
							(end 0.1778 -0.2794)
						)
					)
					(width 0)
					(fill yes)
				)
			)
		)
	)
	(footprint ""
		(layer "F.Cu")
		(at 320.287396 -379.3236 -90)
		(property "Reference" "Q206"
			(at 0 0 270)
			(layer "F.SilkS")
			(hide yes)
			(effects
				(font
					(size 1.27 1.27)
				)
			)
		)
		(property "Value" "SSM6P39TU-GP"
			(at 0.0508 -11.5824 270)
			(unlocked yes)
			(layer "F.Fab")
			(hide yes)
			(effects
				(font
					(size 1.016 1.016)
					(thickness 0.1524)
				)
			)
		)
		(property "Device Type" "UMT6H30"
			(at 0.0508 -13.1572 270)
			(unlocked yes)
			(layer "F.Fab")
			(hide yes)
			(effects
				(font
					(size 1.016 1.016)
					(thickness 0.1524)
				)
			)
		)
		(duplicate_pad_numbers_are_jumpers no)
		(fp_line
			(start 1.524 0.36449)
			(end -1.27 0.36449)
			(stroke
				(width 0.1524)
				(type default)
			)
			(layer "F.SilkS")
		)
		(fp_line
			(start 1.09347 0)
			(end 1.45796 0.36449)
			(stroke
				(width 0.1524)
				(type default)
			)
			(layer "F.SilkS")
		)
		(fp_line
			(start -1.27 -0.36449)
			(end -1.27 0.36449)
			(stroke
				(width 0.1524)
				(type default)
			)
			(layer "F.SilkS")
		)
		(fp_line
			(start -1.27 -0.36449)
			(end 1.524 -0.36449)
			(stroke
				(width 0.1524)
				(type default)
			)
			(layer "F.SilkS")
		)
		(fp_line
			(start 1.45796 -0.36449)
			(end 1.09347 0)
			(stroke
				(width 0.1524)
				(type default)
			)
			(layer "F.SilkS")
		)
		(fp_line
			(start 1.524 -0.36449)
			(end 1.524 0.36449)
			(stroke
				(width 0.1524)
				(type default)
			)
			(layer "F.SilkS")
		)
		(fp_line
			(start 1.524 -0.36449)
			(end 1.45796 -0.36449)
			(stroke
				(width 0.1524)
				(type default)
			)
			(layer "F.SilkS")
		)
		(fp_line
			(start 1.524 -0.36449)
			(end 1.524 -1.82245)
			(stroke
				(width 0.508)
				(type default)
			)
			(layer "F.SilkS")
		)
		(fp_poly
			(pts
				(xy -0.65024 0.36449) (xy -0.65024 -0.36449) (xy 0.65024 -0.36449) (xy 0.65024 0.36449)
			)
			(stroke
				(width 0)
				(type default)
			)
			(fill yes)
			(layer "F.SilkS")
		)
		(fp_poly
			(pts
				(xy 1.016 -1.0668) (xy 1.016 1.0668) (xy -1.016 1.0668) (xy -1.016 -1.0668)
			)
			(stroke
				(width 0)
				(type default)
			)
			(fill no)
			(layer "F.CrtYd")
		)
		(fp_poly
			(pts
				(xy -1.524 1.905) (xy 1.524 1.905) (xy 1.524 -1.06426) (xy 1.016 -1.06426) (xy 1.016 1.0668) (xy -1.016 1.0668)
				(xy -1.016 -1.0668) (xy 1.524 -1.0668) (xy 1.524 -1.905) (xy -1.524 -1.905)
			)
			(stroke
				(width 0)
				(type default)
			)
			(fill no)
			(layer "F.CrtYd")
		)
		(fp_poly
			(pts
				(xy -1.524 -1.905) (xy -1.524 1.905) (xy 1.524 1.905) (xy 1.524 -1.905)
			)
			(stroke
				(width 0)
				(type default)
			)
			(fill no)
			(layer "F.Fab")
		)
		(pad "1" smd rect
			(at 0.65024 -1.02489 270)
			(size 0.4064 0.8128)
			(layers "F.Cu" "F.Mask" "F.Paste")
			(net "P12V_IN")
		)
		(pad "2" smd rect
			(at 0 -1.02489 270)
			(size 0.4064 0.8128)
			(layers "F.Cu" "F.Mask" "F.Paste")
			(net "FAN_YELLOW_LED2")
		)
		(pad "3" smd rect
			(at -0.65024 -1.02489 270)
			(size 0.4064 0.8128)
			(layers "F.Cu" "F.Mask" "F.Paste")
			(net "FAN_BLUE2")
		)
		(pad "4" smd rect
			(at -0.65024 1.02489 270)
			(size 0.4064 0.8128)
			(layers "F.Cu" "F.Mask" "F.Paste")
			(net "P12V_IN")
		)
		(pad "5" smd rect
			(at 0 1.02489 270)
			(size 0.4064 0.8128)
			(layers "F.Cu" "F.Mask" "F.Paste")
			(net "FAN_BLUE_LED2")
		)
		(pad "6" smd rect
			(at 0.65024 1.02489 270)
			(size 0.4064 0.8128)
			(layers "F.Cu" "F.Mask" "F.Paste")
			(net "FAN_YELLOW_2")
		)
	)
	(footprint ""
		(layer "F.Cu")
		(at 336.296 -360.2355 180)
		(property "Reference" "C391"
			(at 0 0 180)
			(layer "F.SilkS")
			(hide yes)
			(effects
				(font
					(size 1.27 1.27)
				)
			)
		)
		(property "Value" "SCD033U25V2KX-GP"
			(at 1.1811 -2.7051 180)
			(unlocked yes)
			(layer "F.Fab")
			(hide yes)
			(effects
				(font
					(size 1.016 1.016)
					(thickness 0.1524)
				)
			)
		)
		(property "Device Type" "C402H22"
			(at 1.1811 -4.2291 180)
			(unlocked yes)
			(layer "F.Fab")
			(hide yes)
			(effects
				(font
					(size 1.016 1.016)
					(thickness 0.1524)
				)
			)
		)
		(duplicate_pad_numbers_are_jumpers no)
		(fp_rect
			(start -0.4318 0.9525)
			(end 0.4318 -0.9525)
			(stroke
				(width 0)
				(type default)
			)
			(fill no)
			(layer "F.CrtYd")
		)
		(fp_rect
			(start -0.4318 0.9525)
			(end 0.4318 -0.9525)
			(stroke
				(width 0)
				(type default)
			)
			(fill no)
			(layer "F.Fab")
		)
		(pad "1" smd custom
			(at 0 -0.4445 180)
			(size 0.1524 0.1524)
			(layers "F.Cu" "F.Mask" "F.Paste")
			(net "GATE_FAN2_R")
			(options
				(clearance outline)
				(anchor circle)
			)
			(primitives
				(gr_poly
					(pts
						(arc
							(start 0.3048 -0.2032)
							(mid 0.275042 -0.275042)
							(end 0.2032 -0.3048)
						)
						(arc
							(start -0.2032 -0.3048)
							(mid -0.275042 -0.275042)
							(end -0.3048 -0.2032)
						)
						(arc
							(start -0.3048 0.2032)
							(mid -0.275042 0.275042)
							(end -0.2032 0.3048)
						)
						(arc
							(start 0.2032 0.3048)
							(mid 0.275042 0.275042)
							(end 0.3048 0.2032)
						)
					)
					(width 0)
					(fill yes)
				)
			)
		)
		(pad "2" smd custom
			(at 0 0.4445 180)
			(size 0.1524 0.1524)
			(layers "F.Cu" "F.Mask" "F.Paste")
			(net "P12V_IN")
			(options
				(clearance outline)
				(anchor circle)
			)
			(primitives
				(gr_poly
					(pts
						(arc
							(start 0.3048 -0.2032)
							(mid 0.275042 -0.275042)
							(end 0.2032 -0.3048)
						)
						(arc
							(start -0.2032 -0.3048)
							(mid -0.275042 -0.275042)
							(end -0.3048 -0.2032)
						)
						(arc
							(start -0.3048 0.2032)
							(mid -0.275042 0.275042)
							(end -0.2032 0.3048)
						)
						(arc
							(start 0.2032 0.3048)
							(mid 0.275042 0.275042)
							(end 0.3048 0.2032)
						)
					)
					(width 0)
					(fill yes)
				)
			)
		)
	)
	(footprint ""
		(layer "F.Cu")
		(at 63.7286 -31.6484)
		(property "Reference" "C362"
			(at 0 0 0)
			(layer "F.SilkS")
			(hide yes)
			(effects
				(font
					(size 1.27 1.27)
				)
			)
		)
		(property "Value" "SCD01U50V2KX-1GP"
			(at 1.1811 -2.7051 0)
			(unlocked yes)
			(layer "F.Fab")
			(hide yes)
			(effects
				(font
					(size 1.016 1.016)
					(thickness 0.1524)
				)
			)
		)
		(property "Device Type" "C402H22"
			(at 1.1811 -4.2291 0)
			(unlocked yes)
			(layer "F.Fab")
			(hide yes)
			(effects
				(font
					(size 1.016 1.016)
					(thickness 0.1524)
				)
			)
		)
		(duplicate_pad_numbers_are_jumpers no)
		(fp_rect
			(start -0.4318 0.9525)
			(end 0.4318 -0.9525)
			(stroke
				(width 0)
				(type default)
			)
			(fill no)
			(layer "F.CrtYd")
		)
		(fp_rect
			(start -0.4318 0.9525)
			(end 0.4318 -0.9525)
			(stroke
				(width 0)
				(type default)
			)
			(fill no)
			(layer "F.Fab")
		)
		(pad "1" smd custom
			(at 0 -0.4445)
			(size 0.1524 0.1524)
			(layers "F.Cu" "F.Mask" "F.Paste")
			(net "HDD_PRSNT_25")
			(options
				(clearance outline)
				(anchor circle)
			)
			(primitives
				(gr_poly
					(pts
						(arc
							(start 0.3048 -0.2032)
							(mid 0.275042 -0.275042)
							(end 0.2032 -0.3048)
						)
						(arc
							(start -0.2032 -0.3048)
							(mid -0.275042 -0.275042)
							(end -0.3048 -0.2032)
						)
						(arc
							(start -0.3048 0.2032)
							(mid -0.275042 0.275042)
							(end -0.2032 0.3048)
						)
						(arc
							(start 0.2032 0.3048)
							(mid 0.275042 0.275042)
							(end 0.3048 0.2032)
						)
					)
					(width 0)
					(fill yes)
				)
			)
		)
		(pad "2" smd custom
			(at 0 0.4445)
			(size 0.1524 0.1524)
			(layers "F.Cu" "F.Mask" "F.Paste")
			(net "GND")
			(options
				(clearance outline)
				(anchor circle)
			)
			(primitives
				(gr_poly
					(pts
						(arc
							(start 0.3048 -0.2032)
							(mid 0.275042 -0.275042)
							(end 0.2032 -0.3048)
						)
						(arc
							(start -0.2032 -0.3048)
							(mid -0.275042 -0.275042)
							(end -0.3048 -0.2032)
						)
						(arc
							(start -0.3048 0.2032)
							(mid -0.275042 0.275042)
							(end -0.2032 0.3048)
						)
						(arc
							(start 0.2032 0.3048)
							(mid 0.275042 0.275042)
							(end 0.3048 0.2032)
						)
					)
					(width 0)
					(fill yes)
				)
			)
		)
	)
	(footprint ""
		(layer "F.Cu")
		(at 471.805 -253.111 90)
		(property "Reference" "R339"
			(at 0 0 90)
			(layer "F.SilkS")
			(hide yes)
			(effects
				(font
					(size 1.27 1.27)
				)
			)
		)
		(property "Value" "4K7R2J-2-GP"
			(at 0.064008 -3.993896 90)
			(unlocked yes)
			(layer "F.Fab")
			(hide yes)
			(effects
				(font
					(size 1.016 1.016)
					(thickness 0.1524)
				)
			)
		)
		(property "Device Type" "R402H16"
			(at 0.064008 -5.517896 90)
			(unlocked yes)
			(layer "F.Fab")
			(hide yes)
			(effects
				(font
					(size 1.016 1.016)
					(thickness 0.1524)
				)
			)
		)
		(duplicate_pad_numbers_are_jumpers no)
		(fp_line
			(start 0.508 -0.9398)
			(end -0.508 -0.9398)
			(stroke
				(width 0.1524)
				(type default)
			)
			(layer "F.SilkS")
		)
		(fp_line
			(start -0.508 -0.9398)
			(end -0.508 0.9398)
			(stroke
				(width 0.1524)
				(type default)
			)
			(layer "F.SilkS")
		)
		(fp_rect
			(start -0.508 0.9398)
			(end 0.508 -0.9398)
			(stroke
				(width 0)
				(type default)
			)
			(fill no)
			(layer "F.CrtYd")
		)
		(fp_rect
			(start -0.508 0.9398)
			(end 0.508 -0.9398)
			(stroke
				(width 0)
				(type default)
			)
			(fill no)
			(layer "F.Fab")
		)
		(pad "1" smd custom
			(at 0 -0.4445 90)
			(size 0.1397 0.1397)
			(layers "F.Cu" "F.Mask" "F.Paste")
			(net "P12V_B")
			(options
				(clearance outline)
				(anchor circle)
			)
			(primitives
				(gr_poly
					(pts
						(arc
							(start -0.1778 -0.2794)
							(mid -0.249642 -0.249642)
							(end -0.2794 -0.1778)
						)
						(arc
							(start -0.2794 0.1778)
							(mid -0.249642 0.249642)
							(end -0.1778 0.2794)
						)
						(arc
							(start 0.1778 0.2794)
							(mid 0.249642 0.249642)
							(end 0.2794 0.1778)
						)
						(arc
							(start 0.2794 -0.1778)
							(mid 0.249642 -0.249642)
							(end 0.1778 -0.2794)
						)
					)
					(width 0)
					(fill yes)
				)
			)
		)
		(pad "2" smd custom
			(at 0 0.4445 90)
			(size 0.1397 0.1397)
			(layers "F.Cu" "F.Mask" "F.Paste")
			(net "SW_HDD_P11")
			(options
				(clearance outline)
				(anchor circle)
			)
			(primitives
				(gr_poly
					(pts
						(arc
							(start -0.1778 -0.2794)
							(mid -0.249642 -0.249642)
							(end -0.2794 -0.1778)
						)
						(arc
							(start -0.2794 0.1778)
							(mid -0.249642 0.249642)
							(end -0.1778 0.2794)
						)
						(arc
							(start 0.1778 0.2794)
							(mid 0.249642 0.249642)
							(end 0.2794 0.1778)
						)
						(arc
							(start 0.2794 -0.1778)
							(mid 0.249642 -0.249642)
							(end 0.1778 -0.2794)
						)
					)
					(width 0)
					(fill yes)
				)
			)
		)
	)
	(footprint ""
		(layer "F.Cu")
		(at 220.6752 -196.723 90)
		(property "Reference" "C6"
			(at 0 0 90)
			(layer "F.SilkS")
			(hide yes)
			(effects
				(font
					(size 1.27 1.27)
				)
			)
		)
		(property "Value" "SCD1U16V2KX-3GP"
			(at 1.1811 -2.7051 90)
			(unlocked yes)
			(layer "F.Fab")
			(hide yes)
			(effects
				(font
					(size 1.016 1.016)
					(thickness 0.1524)
				)
			)
		)
		(property "Device Type" "C402H22"
			(at 1.1811 -4.2291 90)
			(unlocked yes)
			(layer "F.Fab")
			(hide yes)
			(effects
				(font
					(size 1.016 1.016)
					(thickness 0.1524)
				)
			)
		)
		(duplicate_pad_numbers_are_jumpers no)
		(fp_rect
			(start -0.4318 0.9525)
			(end 0.4318 -0.9525)
			(stroke
				(width 0)
				(type default)
			)
			(fill no)
			(layer "F.CrtYd")
		)
		(fp_rect
			(start -0.4318 0.9525)
			(end 0.4318 -0.9525)
			(stroke
				(width 0)
				(type default)
			)
			(fill no)
			(layer "F.Fab")
		)
		(pad "1" smd custom
			(at 0 -0.4445 90)
			(size 0.1524 0.1524)
			(layers "F.Cu" "F.Mask" "F.Paste")
			(net "P3V3_STBY_B")
			(options
				(clearance outline)
				(anchor circle)
			)
			(primitives
				(gr_poly
					(pts
						(arc
							(start 0.3048 -0.2032)
							(mid 0.275042 -0.275042)
							(end 0.2032 -0.3048)
						)
						(arc
							(start -0.2032 -0.3048)
							(mid -0.275042 -0.275042)
							(end -0.3048 -0.2032)
						)
						(arc
							(start -0.3048 0.2032)
							(mid -0.275042 0.275042)
							(end -0.2032 0.3048)
						)
						(arc
							(start 0.2032 0.3048)
							(mid 0.275042 0.275042)
							(end 0.3048 0.2032)
						)
					)
					(width 0)
					(fill yes)
				)
			)
		)
		(pad "2" smd custom
			(at 0 0.4445 90)
			(size 0.1524 0.1524)
			(layers "F.Cu" "F.Mask" "F.Paste")
			(net "GND")
			(options
				(clearance outline)
				(anchor circle)
			)
			(primitives
				(gr_poly
					(pts
						(arc
							(start 0.3048 -0.2032)
							(mid 0.275042 -0.275042)
							(end 0.2032 -0.3048)
						)
						(arc
							(start -0.2032 -0.3048)
							(mid -0.275042 -0.275042)
							(end -0.3048 -0.2032)
						)
						(arc
							(start -0.3048 0.2032)
							(mid -0.275042 0.275042)
							(end -0.2032 0.3048)
						)
						(arc
							(start 0.2032 0.3048)
							(mid 0.275042 0.275042)
							(end 0.3048 0.2032)
						)
					)
					(width 0)
					(fill yes)
				)
			)
		)
	)
	(footprint ""
		(layer "F.Cu")
		(at 172.974 -361.696)
		(property "Reference" "R1006"
			(at 0 0 0)
			(layer "F.SilkS")
			(hide yes)
			(effects
				(font
					(size 1.27 1.27)
				)
			)
		)
		(property "Value" "86K6R2F-2-GP"
			(at 0.064008 -3.993896 0)
			(unlocked yes)
			(layer "F.Fab")
			(hide yes)
			(effects
				(font
					(size 1.016 1.016)
					(thickness 0.1524)
				)
			)
		)
		(property "Device Type" "R402H16"
			(at 0.064008 -5.517896 0)
			(unlocked yes)
			(layer "F.Fab")
			(hide yes)
			(effects
				(font
					(size 1.016 1.016)
					(thickness 0.1524)
				)
			)
		)
		(duplicate_pad_numbers_are_jumpers no)
		(fp_line
			(start -0.508 -0.9398)
			(end -0.508 0.9398)
			(stroke
				(width 0.1524)
				(type default)
			)
			(layer "F.SilkS")
		)
		(fp_line
			(start 0.508 -0.9398)
			(end -0.508 -0.9398)
			(stroke
				(width 0.1524)
				(type default)
			)
			(layer "F.SilkS")
		)
		(fp_rect
			(start -0.508 0.9398)
			(end 0.508 -0.9398)
			(stroke
				(width 0)
				(type default)
			)
			(fill no)
			(layer "F.CrtYd")
		)
		(fp_rect
			(start -0.508 0.9398)
			(end 0.508 -0.9398)
			(stroke
				(width 0)
				(type default)
			)
			(fill no)
			(layer "F.Fab")
		)
		(pad "1" smd custom
			(at 0 -0.4445)
			(size 0.1397 0.1397)
			(layers "F.Cu" "F.Mask" "F.Paste")
			(net "MB0_ISET_R")
			(options
				(clearance outline)
				(anchor circle)
			)
			(primitives
				(gr_poly
					(pts
						(arc
							(start -0.1778 -0.2794)
							(mid -0.249642 -0.249642)
							(end -0.2794 -0.1778)
						)
						(arc
							(start -0.2794 0.1778)
							(mid -0.249642 0.249642)
							(end -0.1778 0.2794)
						)
						(arc
							(start 0.1778 0.2794)
							(mid 0.249642 0.249642)
							(end 0.2794 0.1778)
						)
						(arc
							(start 0.2794 -0.1778)
							(mid 0.249642 -0.249642)
							(end 0.1778 -0.2794)
						)
					)
					(width 0)
					(fill yes)
				)
			)
		)
		(pad "2" smd custom
			(at 0 0.4445)
			(size 0.1397 0.1397)
			(layers "F.Cu" "F.Mask" "F.Paste")
			(net "AGND_CURRENT_MON")
			(options
				(clearance outline)
				(anchor circle)
			)
			(primitives
				(gr_poly
					(pts
						(arc
							(start -0.1778 -0.2794)
							(mid -0.249642 -0.249642)
							(end -0.2794 -0.1778)
						)
						(arc
							(start -0.2794 0.1778)
							(mid -0.249642 0.249642)
							(end -0.1778 0.2794)
						)
						(arc
							(start 0.1778 0.2794)
							(mid 0.249642 0.249642)
							(end 0.2794 0.1778)
						)
						(arc
							(start 0.2794 -0.1778)
							(mid 0.249642 -0.249642)
							(end 0.1778 -0.2794)
						)
					)
					(width 0)
					(fill yes)
				)
			)
		)
	)
	(footprint ""
		(layer "F.Cu")
		(at 85.5218 -16.1798 -90)
		(property "Reference" "R679"
			(at 0 0 270)
			(layer "F.SilkS")
			(hide yes)
			(effects
				(font
					(size 1.27 1.27)
				)
			)
		)
		(property "Value" "0R2J-2-GP"
			(at 0.064008 -3.993896 270)
			(unlocked yes)
			(layer "F.Fab")
			(hide yes)
			(effects
				(font
					(size 1.016 1.016)
					(thickness 0.1524)
				)
			)
		)
		(property "Device Type" "R402H16"
			(at 0.064008 -5.517896 270)
			(unlocked yes)
			(layer "F.Fab")
			(hide yes)
			(effects
				(font
					(size 1.016 1.016)
					(thickness 0.1524)
				)
			)
		)
		(duplicate_pad_numbers_are_jumpers no)
		(fp_line
			(start -0.508 -0.9398)
			(end -0.508 0.9398)
			(stroke
				(width 0.1524)
				(type default)
			)
			(layer "F.SilkS")
		)
		(fp_line
			(start 0.508 -0.9398)
			(end -0.508 -0.9398)
			(stroke
				(width 0.1524)
				(type default)
			)
			(layer "F.SilkS")
		)
		(fp_rect
			(start -0.508 0.9398)
			(end 0.508 -0.9398)
			(stroke
				(width 0)
				(type default)
			)
			(fill no)
			(layer "F.CrtYd")
		)
		(fp_rect
			(start -0.508 0.9398)
			(end 0.508 -0.9398)
			(stroke
				(width 0)
				(type default)
			)
			(fill no)
			(layer "F.Fab")
		)
		(pad "1" smd custom
			(at 0 -0.4445 270)
			(size 0.1397 0.1397)
			(layers "F.Cu" "F.Mask" "F.Paste")
			(net "DRIVE_B_26_PWR")
			(options
				(clearance outline)
				(anchor circle)
			)
			(primitives
				(gr_poly
					(pts
						(arc
							(start -0.1778 -0.2794)
							(mid -0.249642 -0.249642)
							(end -0.2794 -0.1778)
						)
						(arc
							(start -0.2794 0.1778)
							(mid -0.249642 0.249642)
							(end -0.1778 0.2794)
						)
						(arc
							(start 0.1778 0.2794)
							(mid 0.249642 0.249642)
							(end 0.2794 0.1778)
						)
						(arc
							(start 0.2794 -0.1778)
							(mid 0.249642 -0.249642)
							(end 0.1778 -0.2794)
						)
					)
					(width 0)
					(fill yes)
				)
			)
		)
		(pad "2" smd custom
			(at 0 0.4445 270)
			(size 0.1397 0.1397)
			(layers "F.Cu" "F.Mask" "F.Paste")
			(net "SW_PWR_R_HDD26")
			(options
				(clearance outline)
				(anchor circle)
			)
			(primitives
				(gr_poly
					(pts
						(arc
							(start -0.1778 -0.2794)
							(mid -0.249642 -0.249642)
							(end -0.2794 -0.1778)
						)
						(arc
							(start -0.2794 0.1778)
							(mid -0.249642 0.249642)
							(end -0.1778 0.2794)
						)
						(arc
							(start 0.1778 0.2794)
							(mid 0.249642 0.249642)
							(end 0.2794 0.1778)
						)
						(arc
							(start 0.2794 -0.1778)
							(mid 0.249642 -0.249642)
							(end 0.1778 -0.2794)
						)
					)
					(width 0)
					(fill yes)
				)
			)
		)
	)
	(footprint ""
		(layer "F.Cu")
		(at 285.90621 -333.51978 180)
		(property "Reference" "C19"
			(at 0 0 180)
			(layer "F.SilkS")
			(hide yes)
			(effects
				(font
					(size 1.27 1.27)
				)
			)
		)
		(property "Value" "SCD1U16V2KX-3GP"
			(at 1.1811 -2.7051 180)
			(unlocked yes)
			(layer "F.Fab")
			(hide yes)
			(effects
				(font
					(size 1.016 1.016)
					(thickness 0.1524)
				)
			)
		)
		(property "Device Type" "C402H22"
			(at 1.1811 -4.2291 180)
			(unlocked yes)
			(layer "F.Fab")
			(hide yes)
			(effects
				(font
					(size 1.016 1.016)
					(thickness 0.1524)
				)
			)
		)
		(duplicate_pad_numbers_are_jumpers no)
		(fp_rect
			(start -0.4318 0.9525)
			(end 0.4318 -0.9525)
			(stroke
				(width 0)
				(type default)
			)
			(fill no)
			(layer "F.CrtYd")
		)
		(fp_rect
			(start -0.4318 0.9525)
			(end 0.4318 -0.9525)
			(stroke
				(width 0)
				(type default)
			)
			(fill no)
			(layer "F.Fab")
		)
		(pad "1" smd custom
			(at 0 -0.4445 180)
			(size 0.1524 0.1524)
			(layers "F.Cu" "F.Mask" "F.Paste")
			(net "P3V3_IN")
			(options
				(clearance outline)
				(anchor circle)
			)
			(primitives
				(gr_poly
					(pts
						(arc
							(start 0.3048 -0.2032)
							(mid 0.275042 -0.275042)
							(end 0.2032 -0.3048)
						)
						(arc
							(start -0.2032 -0.3048)
							(mid -0.275042 -0.275042)
							(end -0.3048 -0.2032)
						)
						(arc
							(start -0.3048 0.2032)
							(mid -0.275042 0.275042)
							(end -0.2032 0.3048)
						)
						(arc
							(start 0.2032 0.3048)
							(mid 0.275042 0.275042)
							(end 0.3048 0.2032)
						)
					)
					(width 0)
					(fill yes)
				)
			)
		)
		(pad "2" smd custom
			(at 0 0.4445 180)
			(size 0.1524 0.1524)
			(layers "F.Cu" "F.Mask" "F.Paste")
			(net "GND")
			(options
				(clearance outline)
				(anchor circle)
			)
			(primitives
				(gr_poly
					(pts
						(arc
							(start 0.3048 -0.2032)
							(mid 0.275042 -0.275042)
							(end 0.2032 -0.3048)
						)
						(arc
							(start -0.2032 -0.3048)
							(mid -0.275042 -0.275042)
							(end -0.3048 -0.2032)
						)
						(arc
							(start -0.3048 0.2032)
							(mid -0.275042 0.275042)
							(end -0.2032 0.3048)
						)
						(arc
							(start 0.2032 0.3048)
							(mid 0.275042 0.275042)
							(end 0.3048 0.2032)
						)
					)
					(width 0)
					(fill yes)
				)
			)
		)
	)
	(footprint ""
		(layer "F.Cu")
		(at 461.899 -128.651 180)
		(property "Reference" "R587"
			(at 0 0 180)
			(layer "F.SilkS")
			(hide yes)
			(effects
				(font
					(size 1.27 1.27)
				)
			)
		)
		(property "Value" "0R2J-2-GP"
			(at 0.064008 -3.993896 180)
			(unlocked yes)
			(layer "F.Fab")
			(hide yes)
			(effects
				(font
					(size 1.016 1.016)
					(thickness 0.1524)
				)
			)
		)
		(property "Device Type" "R402H16"
			(at 0.064008 -5.517896 180)
			(unlocked yes)
			(layer "F.Fab")
			(hide yes)
			(effects
				(font
					(size 1.016 1.016)
					(thickness 0.1524)
				)
			)
		)
		(duplicate_pad_numbers_are_jumpers no)
		(fp_line
			(start 0.508 -0.9398)
			(end -0.508 -0.9398)
			(stroke
				(width 0.1524)
				(type default)
			)
			(layer "F.SilkS")
		)
		(fp_line
			(start -0.508 -0.9398)
			(end -0.508 0.9398)
			(stroke
				(width 0.1524)
				(type default)
			)
			(layer "F.SilkS")
		)
		(fp_rect
			(start -0.508 0.9398)
			(end 0.508 -0.9398)
			(stroke
				(width 0)
				(type default)
			)
			(fill no)
			(layer "F.CrtYd")
		)
		(fp_rect
			(start -0.508 0.9398)
			(end 0.508 -0.9398)
			(stroke
				(width 0)
				(type default)
			)
			(fill no)
			(layer "F.Fab")
		)
		(pad "1" smd custom
			(at 0 -0.4445 180)
			(size 0.1397 0.1397)
			(layers "F.Cu" "F.Mask" "F.Paste")
			(net "DRIVE_B_22_PWR")
			(options
				(clearance outline)
				(anchor circle)
			)
			(primitives
				(gr_poly
					(pts
						(arc
							(start -0.1778 -0.2794)
							(mid -0.249642 -0.249642)
							(end -0.2794 -0.1778)
						)
						(arc
							(start -0.2794 0.1778)
							(mid -0.249642 0.249642)
							(end -0.1778 0.2794)
						)
						(arc
							(start 0.1778 0.2794)
							(mid 0.249642 0.249642)
							(end 0.2794 0.1778)
						)
						(arc
							(start 0.2794 -0.1778)
							(mid 0.249642 -0.249642)
							(end 0.1778 -0.2794)
						)
					)
					(width 0)
					(fill yes)
				)
			)
		)
		(pad "2" smd custom
			(at 0 0.4445 180)
			(size 0.1397 0.1397)
			(layers "F.Cu" "F.Mask" "F.Paste")
			(net "SW_PWR_R_HDD22")
			(options
				(clearance outline)
				(anchor circle)
			)
			(primitives
				(gr_poly
					(pts
						(arc
							(start -0.1778 -0.2794)
							(mid -0.249642 -0.249642)
							(end -0.2794 -0.1778)
						)
						(arc
							(start -0.2794 0.1778)
							(mid -0.249642 0.249642)
							(end -0.1778 0.2794)
						)
						(arc
							(start 0.1778 0.2794)
							(mid 0.249642 0.249642)
							(end 0.2794 0.1778)
						)
						(arc
							(start 0.2794 -0.1778)
							(mid 0.249642 -0.249642)
							(end 0.1778 -0.2794)
						)
					)
					(width 0)
					(fill yes)
				)
			)
		)
	)
	(footprint ""
		(layer "F.Cu")
		(at 129.413762 -269.705074)
		(property "Reference" "TP36"
			(at 0 0 0)
			(layer "F.SilkS")
			(hide yes)
			(effects
				(font
					(size 1.27 1.27)
				)
			)
		)
		(property "Value" "*"
			(at -0.0508 -1.6764 0)
			(unlocked yes)
			(layer "F.Fab")
			(hide yes)
			(effects
				(font
					(size 1.016 1.016)
					(thickness 0.1524)
				)
			)
		)
		(property "Device Type" "TPAD32"
			(at -0.0508 -3.2004 0)
			(unlocked yes)
			(layer "F.Fab")
			(hide yes)
			(effects
				(font
					(size 1.016 1.016)
					(thickness 0.1524)
				)
			)
		)
		(duplicate_pad_numbers_are_jumpers no)
		(fp_poly
			(pts
				(arc
					(start 0.4064 0)
					(mid -0.4064 0)
					(end 0.4064 0)
				)
			)
			(stroke
				(width 0)
				(type default)
			)
			(fill no)
			(layer "F.CrtYd")
		)
		(fp_poly
			(pts
				(arc
					(start 0.7112 0)
					(mid -0.7112 0)
					(end 0.7112 0)
				)
			)
			(stroke
				(width 0)
				(type default)
			)
			(fill no)
			(layer "F.Fab")
		)
		(pad "1" smd circle
			(at 0 0)
			(size 0.8128 0.8128)
			(layers "F.Cu" "F.Mask" "F.Paste")
			(net "ACT_HDD_3")
		)
	)
	(footprint ""
		(layer "F.Cu")
		(at 457.581 -44.958 180)
		(property "Reference" "C477"
			(at 0 0 180)
			(layer "F.SilkS")
			(hide yes)
			(effects
				(font
					(size 1.27 1.27)
				)
			)
		)
		(property "Value" "SC4D7U25V5KX-1-GP"
			(at -0.0762 -6.1214 180)
			(unlocked yes)
			(layer "F.Fab")
			(hide yes)
			(effects
				(font
					(size 1.016 1.016)
					(thickness 0.1524)
				)
			)
		)
		(property "Device Type" "C805H58"
			(at -0.0762 -8.1534 180)
			(unlocked yes)
			(layer "F.Fab")
			(hide yes)
			(effects
				(font
					(size 1.016 1.016)
					(thickness 0.1524)
				)
			)
		)
		(duplicate_pad_numbers_are_jumpers no)
		(fp_line
			(start 0.635 0)
			(end -0.635 0)
			(stroke
				(width 0.508)
				(type default)
			)
			(layer "F.SilkS")
		)
		(fp_rect
			(start -0.9652 1.778)
			(end 0.9652 -1.778)
			(stroke
				(width 0)
				(type default)
			)
			(fill no)
			(layer "F.CrtYd")
		)
		(fp_poly
			(pts
				(xy -0.9652 -1.778) (xy 0.9652 -1.778) (xy 0.9652 1.778) (xy -0.9652 1.778)
			)
			(stroke
				(width 0)
				(type default)
			)
			(fill no)
			(layer "F.Fab")
		)
		(pad "1" smd rect
			(at 0 -0.9652 180)
			(size 1.397 1.143)
			(layers "F.Cu" "F.Mask" "F.Paste")
			(net "P12V_HDD34")
		)
		(pad "2" smd rect
			(at 0 0.9652 180)
			(size 1.397 1.143)
			(layers "F.Cu" "F.Mask" "F.Paste")
			(net "GND")
		)
	)
	(footprint ""
		(layer "F.Cu")
		(at 115.062 -134.493 180)
		(property "Reference" "Q65"
			(at 0 0 180)
			(layer "F.SilkS")
			(hide yes)
			(effects
				(font
					(size 1.27 1.27)
				)
			)
		)
		(property "Value" "2N7002KDW-GP"
			(at -2.3622 -8.2042 180)
			(unlocked yes)
			(layer "F.Fab")
			(hide yes)
			(effects
				(font
					(size 1.016 1.016)
					(thickness 0.1524)
				)
			)
		)
		(property "Device Type" "SOT-363H44"
			(at -2.3622 -10.1092 180)
			(unlocked yes)
			(layer "F.Fab")
			(hide yes)
			(effects
				(font
					(size 1.016 1.016)
					(thickness 0.1524)
				)
			)
		)
		(duplicate_pad_numbers_are_jumpers no)
		(fp_line
			(start 1.4478 1.7018)
			(end 1.4478 -1.7018)
			(stroke
				(width 0.1524)
				(type default)
			)
			(layer "F.SilkS")
		)
		(fp_line
			(start 1.4478 -1.7018)
			(end -1.4478 -1.7018)
			(stroke
				(width 0.1524)
				(type default)
			)
			(layer "F.SilkS")
		)
		(fp_line
			(start -1.27 1.524)
			(end -1.27 0.6604)
			(stroke
				(width 0.4826)
				(type default)
			)
			(layer "F.SilkS")
		)
		(fp_line
			(start -1.4478 1.7018)
			(end 1.4478 1.7018)
			(stroke
				(width 0.1524)
				(type default)
			)
			(layer "F.SilkS")
		)
		(fp_line
			(start -1.4478 -1.7018)
			(end -1.4478 1.7018)
			(stroke
				(width 0.1524)
				(type default)
			)
			(layer "F.SilkS")
		)
		(fp_poly
			(pts
				(xy -1.524 -1.778) (xy 1.524 -1.778) (xy 1.524 1.778) (xy -1.524 1.778)
			)
			(stroke
				(width 0)
				(type default)
			)
			(fill no)
			(layer "F.CrtYd")
		)
		(fp_poly
			(pts
				(xy -1.524 -1.778) (xy 1.524 -1.778) (xy 1.524 1.778) (xy -1.524 1.778)
			)
			(stroke
				(width 0)
				(type default)
			)
			(fill no)
			(layer "F.Fab")
		)
		(pad "1" smd rect
			(at -0.65024 0.9398 180)
			(size 0.4064 1.016)
			(layers "F.Cu" "F.Mask" "F.Paste")
			(net "GND")
		)
		(pad "2" smd rect
			(at 0 0.9398 180)
			(size 0.4064 1.016)
			(layers "F.Cu" "F.Mask" "F.Paste")
			(net "SW_PWR_R_HDD15")
		)
		(pad "3" smd rect
			(at 0.65024 0.9398 180)
			(size 0.4064 1.016)
			(layers "F.Cu" "F.Mask" "F.Paste")
			(net "SW_HDD_P15")
		)
		(pad "4" smd rect
			(at 0.65024 -0.9398 180)
			(size 0.4064 1.016)
			(layers "F.Cu" "F.Mask" "F.Paste")
			(net "GND")
		)
		(pad "5" smd rect
			(at 0 -0.9398 180)
			(size 0.4064 1.016)
			(layers "F.Cu" "F.Mask" "F.Paste")
			(net "SW_HDD_G15")
		)
		(pad "6" smd rect
			(at -0.65024 -0.9398 180)
			(size 0.4064 1.016)
			(layers "F.Cu" "F.Mask" "F.Paste")
			(net "SW_HDD_R15")
		)
	)
	(footprint ""
		(layer "F.Cu")
		(at 145.161 -35.687 90)
		(property "Reference" "R715"
			(at 0 0 90)
			(layer "F.SilkS")
			(hide yes)
			(effects
				(font
					(size 1.27 1.27)
				)
			)
		)
		(property "Value" "2R6F-GP"
			(at -0.0508 -4.8514 90)
			(unlocked yes)
			(layer "F.Fab")
			(hide yes)
			(effects
				(font
					(size 1.016 1.016)
					(thickness 0.1524)
				)
			)
		)
		(property "Device Type" "R1206H26"
			(at 0 -6.3754 90)
			(unlocked yes)
			(layer "F.Fab")
			(hide yes)
			(effects
				(font
					(size 1.016 1.016)
					(thickness 0.1524)
				)
			)
		)
		(duplicate_pad_numbers_are_jumpers no)
		(fp_line
			(start 1.016 -2.2352)
			(end 1.016 2.2352)
			(stroke
				(width 0.1524)
				(type default)
			)
			(layer "F.SilkS")
		)
		(fp_line
			(start -1.016 -2.2352)
			(end 1.016 -2.2352)
			(stroke
				(width 0.1524)
				(type default)
			)
			(layer "F.SilkS")
		)
		(fp_line
			(start 1.016 2.2352)
			(end -1.016 2.2352)
			(stroke
				(width 0.1524)
				(type default)
			)
			(layer "F.SilkS")
		)
		(fp_line
			(start -1.016 2.2352)
			(end -1.016 -2.2352)
			(stroke
				(width 0.1524)
				(type default)
			)
			(layer "F.SilkS")
		)
		(fp_rect
			(start -1.0922 2.3114)
			(end 1.0922 -2.3114)
			(stroke
				(width 0)
				(type default)
			)
			(fill no)
			(layer "F.CrtYd")
		)
		(fp_poly
			(pts
				(xy -1.0922 -2.3114) (xy 1.0922 -2.3114) (xy 1.0922 2.3114) (xy -1.0922 2.3114)
			)
			(stroke
				(width 0)
				(type default)
			)
			(fill no)
			(layer "F.Fab")
		)
		(pad "1" smd rect
			(at 0 -1.397 90)
			(size 1.651 1.27)
			(layers "F.Cu" "F.Mask" "F.Paste")
			(net "P12V_HDD28")
		)
		(pad "2" smd rect
			(at 0 1.397 90)
			(size 1.651 1.27)
			(layers "F.Cu" "F.Mask" "F.Paste")
			(net "12V_PRE_28")
		)
	)
	(footprint ""
		(layer "F.Cu")
		(at 73.861168 -214.860378 90)
		(property "Reference" "Q245"
			(at 0 0 90)
			(layer "F.SilkS")
			(hide yes)
			(effects
				(font
					(size 1.27 1.27)
				)
			)
		)
		(property "Value" "SSM3K324R-GP"
			(at 0.127 -8.9662 90)
			(unlocked yes)
			(layer "F.Fab")
			(hide yes)
			(effects
				(font
					(size 1.016 1.016)
					(thickness 0.1524)
				)
			)
		)
		(property "Device Type" "SOT23DGS2D4H35"
			(at 0.127 -10.4902 90)
			(unlocked yes)
			(layer "F.Fab")
			(hide yes)
			(effects
				(font
					(size 1.016 1.016)
					(thickness 0.1524)
				)
			)
		)
		(duplicate_pad_numbers_are_jumpers no)
		(fp_line
			(start 1.651 -1.778)
			(end -1.651 -1.778)
			(stroke
				(width 0.1524)
				(type default)
			)
			(layer "F.SilkS")
		)
		(fp_line
			(start -1.651 -1.778)
			(end -1.651 1.778)
			(stroke
				(width 0.1524)
				(type default)
			)
			(layer "F.SilkS")
		)
		(fp_line
			(start 1.651 1.778)
			(end 1.651 -1.778)
			(stroke
				(width 0.1524)
				(type default)
			)
			(layer "F.SilkS")
		)
		(fp_line
			(start -1.651 1.778)
			(end 1.651 1.778)
			(stroke
				(width 0.1524)
				(type default)
			)
			(layer "F.SilkS")
		)
		(fp_poly
			(pts
				(xy -1.778 1.8796) (xy -1.778 -1.8796) (xy 1.778 -1.8796) (xy 1.778 1.8796)
			)
			(stroke
				(width 0)
				(type default)
			)
			(fill no)
			(layer "F.CrtYd")
		)
		(fp_poly
			(pts
				(xy -1.778 1.8796) (xy -1.778 -1.8796) (xy 1.778 -1.8796) (xy 1.778 1.8796)
			)
			(stroke
				(width 0)
				(type default)
			)
			(fill no)
			(layer "F.Fab")
		)
		(pad "D" smd custom
			(at 0 -0.9525 90)
			(size 0.1905 0.1905)
			(layers "F.Cu" "F.Mask" "F.Paste")
			(net "DRV_ACT_2_N")
			(options
				(clearance outline)
				(anchor circle)
			)
			(primitives
				(gr_poly
					(pts
						(arc
							(start -0.1778 0.5715)
							(mid -0.321484 0.511984)
							(end -0.381 0.3683)
						)
						(arc
							(start -0.381 -0.3683)
							(mid -0.321484 -0.511984)
							(end -0.1778 -0.5715)
						)
						(arc
							(start 0.1778 -0.5715)
							(mid 0.321484 -0.511984)
							(end 0.381 -0.3683)
						)
						(arc
							(start 0.381 0.3683)
							(mid 0.321484 0.511984)
							(end 0.1778 0.5715)
						)
					)
					(width 0)
					(fill yes)
				)
			)
		)
		(pad "G" smd custom
			(at -0.98425 0.9525 90)
			(size 0.1905 0.1905)
			(layers "F.Cu" "F.Mask" "F.Paste")
			(net "DRIVE_B_2_ACT")
			(options
				(clearance outline)
				(anchor circle)
			)
			(primitives
				(gr_poly
					(pts
						(arc
							(start -0.1778 0.5715)
							(mid -0.321484 0.511984)
							(end -0.381 0.3683)
						)
						(arc
							(start -0.381 -0.3683)
							(mid -0.321484 -0.511984)
							(end -0.1778 -0.5715)
						)
						(arc
							(start 0.1778 -0.5715)
							(mid 0.321484 -0.511984)
							(end 0.381 -0.3683)
						)
						(arc
							(start 0.381 0.3683)
							(mid 0.321484 0.511984)
							(end 0.1778 0.5715)
						)
					)
					(width 0)
					(fill yes)
				)
			)
		)
		(pad "S" smd custom
			(at 0.98425 0.9525 90)
			(size 0.1905 0.1905)
			(layers "F.Cu" "F.Mask" "F.Paste")
			(net "GND")
			(options
				(clearance outline)
				(anchor circle)
			)
			(primitives
				(gr_poly
					(pts
						(arc
							(start -0.1778 0.5715)
							(mid -0.321484 0.511984)
							(end -0.381 0.3683)
						)
						(arc
							(start -0.381 -0.3683)
							(mid -0.321484 -0.511984)
							(end -0.1778 -0.5715)
						)
						(arc
							(start 0.1778 -0.5715)
							(mid 0.321484 -0.511984)
							(end 0.381 -0.3683)
						)
						(arc
							(start 0.381 0.3683)
							(mid 0.321484 0.511984)
							(end 0.1778 0.5715)
						)
					)
					(width 0)
					(fill yes)
				)
			)
		)
	)
	(footprint ""
		(layer "F.Cu")
		(at 154.399996 -143.91005 -90)
		(property "Reference" "HDDSAS16"
			(at 0 0 270)
			(layer "F.SilkS")
			(hide yes)
			(effects
				(font
					(size 1.27 1.27)
				)
			)
		)
		(property "Value" "SKT-SAS15P-14P-45-GP"
			(at -20.7645 -8.9789 270)
			(unlocked yes)
			(layer "F.Fab")
			(hide yes)
			(effects
				(font
					(size 1.016 1.016)
					(thickness 0.1524)
				)
			)
		)
		(property "Device Type" "10120818-001C-TRLF"
			(at -20.7645 -10.5029 270)
			(unlocked yes)
			(layer "F.Fab")
			(hide yes)
			(effects
				(font
					(size 1.016 1.016)
					(thickness 0.1524)
				)
			)
		)
		(duplicate_pad_numbers_are_jumpers no)
		(fp_line
			(start 1.651 4.2926)
			(end 1.651 3.0099)
			(stroke
				(width 0.1524)
				(type default)
			)
			(layer "F.SilkS")
		)
		(fp_line
			(start 8.509 4.2926)
			(end 1.651 4.2926)
			(stroke
				(width 0.1524)
				(type default)
			)
			(layer "F.SilkS")
		)
		(fp_line
			(start -23.4188 3.0099)
			(end -23.4188 -3.2512)
			(stroke
				(width 0.1524)
				(type default)
			)
			(layer "F.SilkS")
		)
		(fp_line
			(start 1.651 3.0099)
			(end -23.4188 3.0099)
			(stroke
				(width 0.1524)
				(type default)
			)
			(layer "F.SilkS")
		)
		(fp_line
			(start 8.509 3.0099)
			(end 8.509 4.2926)
			(stroke
				(width 0.1524)
				(type default)
			)
			(layer "F.SilkS")
		)
		(fp_line
			(start 23.4188 3.0099)
			(end 8.509 3.0099)
			(stroke
				(width 0.1524)
				(type default)
			)
			(layer "F.SilkS")
		)
		(fp_line
			(start -23.4188 -3.2512)
			(end 23.4188 -3.2512)
			(stroke
				(width 0.1524)
				(type default)
			)
			(layer "F.SilkS")
		)
		(fp_line
			(start 23.4188 -3.2512)
			(end 23.4188 3.0099)
			(stroke
				(width 0.1524)
				(type default)
			)
			(layer "F.SilkS")
		)
		(fp_line
			(start 15.5067 -3.3401)
			(end 16.2687 -3.3401)
			(stroke
				(width 0.3302)
				(type default)
			)
			(layer "F.SilkS")
		)
		(fp_poly
			(pts
				(xy 15.868904 -3.230372) (xy 16.503904 -3.865372) (xy 15.233904 -3.865372)
			)
			(stroke
				(width 0)
				(type default)
			)
			(fill yes)
			(layer "F.SilkS")
		)
		(fp_poly
			(pts
				(xy -22.8727 -2.7559) (xy 22.8727 -2.7559) (xy 22.8727 2.7559) (xy 8.255 2.7559) (xy 8.255 3.5179)
				(xy 1.905 3.5179) (xy 1.905 2.7559) (xy -22.8727 2.7559)
			)
			(stroke
				(width 0)
				(type default)
			)
			(fill no)
			(layer "F.CrtYd")
		)
		(fp_poly
			(pts
				(xy 1.397 4.5466) (xy 1.397 3.2639) (xy -23.6728 3.2639) (xy -23.6728 -3.5052) (xy 23.6728 -3.5052)
				(xy 23.6728 -0.00635) (xy 22.8727 -0.00635) (xy 22.8727 -2.7559) (xy -22.8727 -2.7559) (xy -22.8727 2.7559)
				(xy 1.905 2.7559) (xy 1.905 3.5179) (xy 8.255 3.5179) (xy 8.255 2.7559) (xy 22.8727 2.7559) (xy 22.8727 0.00635)
				(xy 23.6728 0.00635) (xy 23.6728 3.2639) (xy 8.763 3.2639) (xy 8.763 4.5466)
			)
			(stroke
				(width 0)
				(type default)
			)
			(fill no)
			(layer "F.CrtYd")
		)
		(fp_poly
			(pts
				(xy 1.397 4.5466) (xy 1.397 3.2639) (xy -23.6728 3.2639) (xy -23.6728 -3.5052) (xy 23.6728 -3.5052)
				(xy 23.6728 3.2639) (xy 8.763 3.2639) (xy 8.763 4.5466)
			)
			(stroke
				(width 0)
				(type default)
			)
			(fill no)
			(layer "F.Fab")
		)
		(pad "" np_thru_hole circle
			(at -18.874994 0 270)
			(size 0.254 0.254)
			(drill 1.3462)
			(layers "*.Cu" "*.Mask")
			(clearance 0.9017)
			(thermal_gap 0.9017)
		)
		(pad "" np_thru_hole circle
			(at 18.874994 0 270)
			(size 0.254 0.254)
			(drill 0.9398)
			(layers "*.Cu" "*.Mask")
			(clearance 0.6985)
			(thermal_gap 0.6985)
		)
		(pad "G1" smd rect
			(at 21.874988 0 270)
			(size 2.5908 2.5908)
			(layers "F.Cu" "F.Mask" "F.Paste")
			(net "GND")
		)
		(pad "G2" smd rect
			(at -21.874988 0 270)
			(size 2.5908 2.5908)
			(layers "F.Cu" "F.Mask" "F.Paste")
			(net "GND")
		)
		(pad "P1" smd rect
			(at 1.905 -1.82499 270)
			(size 0.6096 2.3622)
			(layers "F.Cu" "F.Mask" "F.Paste")
			(net "Net_1724")
		)
		(pad "P2" smd rect
			(at 0.635 -1.82499 270)
			(size 0.6096 2.3622)
			(layers "F.Cu" "F.Mask" "F.Paste")
			(net "Net_1725")
		)
		(pad "P3" smd rect
			(at -0.635 -1.82499 270)
			(size 0.6096 2.3622)
			(layers "F.Cu" "F.Mask" "F.Paste")
			(net "Net_1726")
		)
		(pad "P4" smd rect
			(at -1.905 -1.82499 270)
			(size 0.6096 2.3622)
			(layers "F.Cu" "F.Mask" "F.Paste")
			(net "GND")
		)
		(pad "P5" smd rect
			(at -3.175 -1.82499 270)
			(size 0.6096 2.3622)
			(layers "F.Cu" "F.Mask" "F.Paste")
			(net "HDD_PRSNT_16")
		)
		(pad "P6" smd rect
			(at -4.445 -1.82499 270)
			(size 0.6096 2.3622)
			(layers "F.Cu" "F.Mask" "F.Paste")
			(net "GND")
		)
		(pad "P7" smd rect
			(at -5.715 -1.82499 270)
			(size 0.6096 2.3622)
			(layers "F.Cu" "F.Mask" "F.Paste")
			(net "5V_PRE_16")
		)
		(pad "P8" smd rect
			(at -6.985 -1.82499 270)
			(size 0.6096 2.3622)
			(layers "F.Cu" "F.Mask" "F.Paste")
			(net "P5V_HDD16")
		)
		(pad "P9" smd rect
			(at -8.255 -1.82499 270)
			(size 0.6096 2.3622)
			(layers "F.Cu" "F.Mask" "F.Paste")
			(net "P5V_HDD16")
		)
		(pad "P10" smd rect
			(at -9.525 -1.82499 270)
			(size 0.6096 2.3622)
			(layers "F.Cu" "F.Mask" "F.Paste")
			(net "GND")
		)
		(pad "P11" smd rect
			(at -10.795 -1.82499 270)
			(size 0.6096 2.3622)
			(layers "F.Cu" "F.Mask" "F.Paste")
			(net "ACT_HDD_16")
		)
		(pad "P12" smd rect
			(at -12.065 -1.82499 270)
			(size 0.6096 2.3622)
			(layers "F.Cu" "F.Mask" "F.Paste")
			(net "GND")
		)
		(pad "P13" smd rect
			(at -13.335 -1.82499 270)
			(size 0.6096 2.3622)
			(layers "F.Cu" "F.Mask" "F.Paste")
			(net "12V_PRE_16")
		)
		(pad "P14" smd rect
			(at -14.605 -1.82499 270)
			(size 0.6096 2.3622)
			(layers "F.Cu" "F.Mask" "F.Paste")
			(net "P12V_HDD16")
		)
		(pad "P15" smd rect
			(at -15.875 -1.82499 270)
			(size 0.6096 2.3622)
			(layers "F.Cu" "F.Mask" "F.Paste")
			(net "P12V_HDD16")
		)
		(pad "S1" smd rect
			(at 15.875 -1.82499 270)
			(size 0.6096 2.3622)
			(layers "F.Cu" "F.Mask" "F.Paste")
			(net "GND")
		)
		(pad "S2" smd rect
			(at 14.605 -1.82499 270)
			(size 0.6096 2.3622)
			(layers "F.Cu" "F.Mask" "F.Paste")
			(net "SAS_HDD_RX_P16")
		)
		(pad "S3" smd rect
			(at 13.335 -1.82499 270)
			(size 0.6096 2.3622)
			(layers "F.Cu" "F.Mask" "F.Paste")
			(net "SAS_HDD_RX_N16")
		)
		(pad "S4" smd rect
			(at 12.065 -1.82499 270)
			(size 0.6096 2.3622)
			(layers "F.Cu" "F.Mask" "F.Paste")
			(net "GND")
		)
		(pad "S5" smd rect
			(at 10.795 -1.82499 270)
			(size 0.6096 2.3622)
			(layers "F.Cu" "F.Mask" "F.Paste")
			(net "PHY_DRV_B_TO_SCC_B_16_DN")
		)
		(pad "S6" smd rect
			(at 9.525 -1.82499 270)
			(size 0.6096 2.3622)
			(layers "F.Cu" "F.Mask" "F.Paste")
			(net "PHY_DRV_B_TO_SCC_B_16_DP")
		)
		(pad "S7" smd rect
			(at 8.255 -1.82499 270)
			(size 0.6096 2.3622)
			(layers "F.Cu" "F.Mask" "F.Paste")
			(net "GND")
		)
		(pad "S8" smd rect
			(at 7.480046 2.845054 270)
			(size 0.508 2.3622)
			(layers "F.Cu" "F.Mask" "F.Paste")
			(net "GND")
		)
		(pad "S9" smd rect
			(at 6.679946 2.845054 270)
			(size 0.508 2.3622)
			(layers "F.Cu" "F.Mask" "F.Paste")
			(net "Net_439")
		)
		(pad "S10" smd rect
			(at 5.8801 2.845054 270)
			(size 0.508 2.3622)
			(layers "F.Cu" "F.Mask" "F.Paste")
			(net "Net_331")
		)
		(pad "S11" smd rect
			(at 5.08 2.845054 270)
			(size 0.508 2.3622)
			(layers "F.Cu" "F.Mask" "F.Paste")
			(net "GND")
		)
		(pad "S12" smd rect
			(at 4.2799 2.845054 270)
			(size 0.508 2.3622)
			(layers "F.Cu" "F.Mask" "F.Paste")
			(net "Net_367")
		)
		(pad "S13" smd rect
			(at 3.480054 2.845054 270)
			(size 0.508 2.3622)
			(layers "F.Cu" "F.Mask" "F.Paste")
			(net "Net_403")
		)
		(pad "S14" smd rect
			(at 2.679954 2.845054 270)
			(size 0.508 2.3622)
			(layers "F.Cu" "F.Mask" "F.Paste")
			(net "GND")
		)
		(zone
			(layer "F.Cu")
			(hatch none 0.5)
			(connect_pads
				(clearance 0)
			)
			(min_thickness 0.25)
			(keepout
				(tracks not_allowed)
				(vias allowed)
				(pads allowed)
				(copperpour not_allowed)
				(footprints allowed)
			)
			(placement
				(enabled no)
				(sheetname "")
			)
			(fill
				(thermal_gap 0.5)
				(thermal_bridge_width 0.5)
				(island_removal_mode 0)
			)
			(polygon
				(pts
					(xy 158.057596 -160.64865) (xy 150.983696 -160.64865) (xy 150.983696 -167.58285) (xy 152.088596 -167.58285)
					(xy 152.088596 -163.46805) (xy 156.711396 -163.46805) (xy 156.711396 -167.58285) (xy 158.057596 -167.58285)
				)
			)
		)
		(zone
			(layer "F.Cu")
			(hatch none 0.5)
			(connect_pads
				(clearance 0)
			)
			(min_thickness 0.25)
			(keepout
				(tracks allowed)
				(vias not_allowed)
				(pads allowed)
				(copperpour not_allowed)
				(footprints allowed)
			)
			(placement
				(enabled no)
				(sheetname "")
			)
			(fill
				(thermal_gap 0.5)
				(thermal_bridge_width 0.5)
				(island_removal_mode 0)
			)
			(polygon
				(pts
					(xy 158.057596 -160.64865) (xy 150.983696 -160.64865) (xy 150.983696 -167.58285) (xy 152.088596 -167.58285)
					(xy 152.088596 -163.46805) (xy 156.711396 -163.46805) (xy 156.711396 -167.58285) (xy 158.057596 -167.58285)
				)
			)
		)
		(zone
			(layer "F.Cu")
			(hatch none 0.5)
			(connect_pads
				(clearance 0)
			)
			(min_thickness 0.25)
			(keepout
				(tracks allowed)
				(vias not_allowed)
				(pads allowed)
				(copperpour not_allowed)
				(footprints allowed)
			)
			(placement
				(enabled no)
				(sheetname "")
			)
			(fill
				(thermal_gap 0.5)
				(thermal_bridge_width 0.5)
				(island_removal_mode 0)
			)
			(polygon
				(pts
					(xy 158.057596 -127.17145) (xy 150.983696 -127.17145) (xy 150.983696 -120.23725) (xy 152.088596 -120.23725)
					(xy 152.088596 -124.35205) (xy 156.711396 -124.35205) (xy 156.711396 -120.23725) (xy 158.057596 -120.23725)
				)
			)
		)
		(zone
			(layer "F.Cu")
			(hatch none 0.5)
			(connect_pads
				(clearance 0)
			)
			(min_thickness 0.25)
			(keepout
				(tracks not_allowed)
				(vias allowed)
				(pads allowed)
				(copperpour not_allowed)
				(footprints allowed)
			)
			(placement
				(enabled no)
				(sheetname "")
			)
			(fill
				(thermal_gap 0.5)
				(thermal_bridge_width 0.5)
				(island_removal_mode 0)
			)
			(polygon
				(pts
					(xy 158.057596 -127.17145) (xy 150.983696 -127.17145) (xy 150.983696 -120.23725) (xy 152.088596 -120.23725)
					(xy 152.088596 -124.35205) (xy 156.711396 -124.35205) (xy 156.711396 -120.23725) (xy 158.057596 -120.23725)
				)
			)
		)
		(zone
			(layers "F.Cu" "B.Cu" "In1.Cu" "In2.Cu" "In3.Cu" "In4.Cu" "In5.Cu" "In6.Cu")
			(hatch none 0.5)
			(connect_pads
				(clearance 0)
			)
			(min_thickness 0.25)
			(keepout
				(tracks not_allowed)
				(vias allowed)
				(pads allowed)
				(copperpour not_allowed)
				(footprints allowed)
			)
			(placement
				(enabled no)
				(sheetname "")
			)
			(fill
				(thermal_gap 0.5)
				(thermal_bridge_width 0.5)
				(island_removal_mode 0)
			)
			(polygon
				(pts
					(arc
						(start 155.174696 -125.035056)
						(mid 153.625296 -125.035056)
						(end 155.174696 -125.035056)
					)
				)
			)
		)
		(zone
			(layers "F.Cu" "B.Cu" "In1.Cu" "In2.Cu" "In3.Cu" "In4.Cu" "In5.Cu" "In6.Cu")
			(hatch none 0.5)
			(connect_pads
				(clearance 0)
			)
			(min_thickness 0.25)
			(keepout
				(tracks not_allowed)
				(vias allowed)
				(pads allowed)
				(copperpour not_allowed)
				(footprints allowed)
			)
			(placement
				(enabled no)
				(sheetname "")
			)
			(fill
				(thermal_gap 0.5)
				(thermal_bridge_width 0.5)
				(island_removal_mode 0)
			)
			(polygon
				(pts
					(arc
						(start 155.377896 -162.785044)
						(mid 153.422096 -162.785044)
						(end 155.377896 -162.785044)
					)
				)
			)
		)
	)
	(footprint ""
		(layer "F.Cu")
		(at 459.260194 -373.634 -90)
		(property "Reference" "R1308"
			(at 0 0 270)
			(layer "F.SilkS")
			(hide yes)
			(effects
				(font
					(size 1.27 1.27)
				)
			)
		)
		(property "Value" "4K7R2F-GP"
			(at 0.064008 -3.993896 270)
			(unlocked yes)
			(layer "F.Fab")
			(hide yes)
			(effects
				(font
					(size 1.016 1.016)
					(thickness 0.1524)
				)
			)
		)
		(property "Device Type" "R402H16"
			(at 0.064008 -5.517896 270)
			(unlocked yes)
			(layer "F.Fab")
			(hide yes)
			(effects
				(font
					(size 1.016 1.016)
					(thickness 0.1524)
				)
			)
		)
		(duplicate_pad_numbers_are_jumpers no)
		(fp_line
			(start -0.508 -0.9398)
			(end -0.508 0.9398)
			(stroke
				(width 0.1524)
				(type default)
			)
			(layer "F.SilkS")
		)
		(fp_line
			(start 0.508 -0.9398)
			(end -0.508 -0.9398)
			(stroke
				(width 0.1524)
				(type default)
			)
			(layer "F.SilkS")
		)
		(fp_rect
			(start -0.508 0.9398)
			(end 0.508 -0.9398)
			(stroke
				(width 0)
				(type default)
			)
			(fill no)
			(layer "F.CrtYd")
		)
		(fp_rect
			(start -0.508 0.9398)
			(end 0.508 -0.9398)
			(stroke
				(width 0)
				(type default)
			)
			(fill no)
			(layer "F.Fab")
		)
		(pad "1" smd custom
			(at 0 -0.4445 270)
			(size 0.1397 0.1397)
			(layers "F.Cu" "F.Mask" "F.Paste")
			(net "FAN_YELLOW_LED3")
			(options
				(clearance outline)
				(anchor circle)
			)
			(primitives
				(gr_poly
					(pts
						(arc
							(start -0.1778 -0.2794)
							(mid -0.249642 -0.249642)
							(end -0.2794 -0.1778)
						)
						(arc
							(start -0.2794 0.1778)
							(mid -0.249642 0.249642)
							(end -0.1778 0.2794)
						)
						(arc
							(start 0.1778 0.2794)
							(mid 0.249642 0.249642)
							(end 0.2794 0.1778)
						)
						(arc
							(start 0.2794 -0.1778)
							(mid 0.249642 -0.249642)
							(end 0.1778 -0.2794)
						)
					)
					(width 0)
					(fill yes)
				)
			)
		)
		(pad "2" smd custom
			(at 0 0.4445 270)
			(size 0.1397 0.1397)
			(layers "F.Cu" "F.Mask" "F.Paste")
			(net "FAN_LED3_D2")
			(options
				(clearance outline)
				(anchor circle)
			)
			(primitives
				(gr_poly
					(pts
						(arc
							(start -0.1778 -0.2794)
							(mid -0.249642 -0.249642)
							(end -0.2794 -0.1778)
						)
						(arc
							(start -0.2794 0.1778)
							(mid -0.249642 0.249642)
							(end -0.1778 0.2794)
						)
						(arc
							(start 0.1778 0.2794)
							(mid 0.249642 0.249642)
							(end 0.2794 0.1778)
						)
						(arc
							(start 0.2794 -0.1778)
							(mid 0.249642 -0.249642)
							(end 0.1778 -0.2794)
						)
					)
					(width 0)
					(fill yes)
				)
			)
		)
	)
	(footprint ""
		(layer "F.Cu")
		(at 80.900016 -180.399944)
		(property "Reference" "LED3"
			(at 0 0 0)
			(layer "F.SilkS")
			(hide yes)
			(effects
				(font
					(size 1.27 1.27)
				)
			)
		)
		(property "Value" "LED-BY-19-GP"
			(at -2.132076 1.414018 0)
			(unlocked yes)
			(layer "F.Fab")
			(hide yes)
			(effects
				(font
					(size 1.016 1.016)
					(thickness 0.1524)
				)
			)
		)
		(property "Device Type" "LED-1615-4PH26"
			(at -2.132076 -0.109982 0)
			(unlocked yes)
			(layer "F.Fab")
			(hide yes)
			(effects
				(font
					(size 1.016 1.016)
					(thickness 0.1524)
				)
			)
		)
		(duplicate_pad_numbers_are_jumpers no)
		(fp_line
			(start -1.2954 0.254)
			(end -1.2954 1.6002)
			(stroke
				(width 0.508)
				(type default)
			)
			(layer "F.SilkS")
		)
		(fp_line
			(start -1.2954 1.6002)
			(end 1.2954 1.6002)
			(stroke
				(width 0.508)
				(type default)
			)
			(layer "F.SilkS")
		)
		(fp_line
			(start -1.1176 -1.4224)
			(end 1.1176 -1.4224)
			(stroke
				(width 0.1524)
				(type default)
			)
			(layer "F.SilkS")
		)
		(fp_line
			(start -1.1176 1.4224)
			(end -1.1176 -1.4224)
			(stroke
				(width 0.1524)
				(type default)
			)
			(layer "F.SilkS")
		)
		(fp_line
			(start 1.1176 -1.4224)
			(end 1.1176 1.4224)
			(stroke
				(width 0.1524)
				(type default)
			)
			(layer "F.SilkS")
		)
		(fp_line
			(start 1.1176 1.4224)
			(end -1.1176 1.4224)
			(stroke
				(width 0.1524)
				(type default)
			)
			(layer "F.SilkS")
		)
		(fp_line
			(start 1.2954 1.6002)
			(end 1.2954 0.254)
			(stroke
				(width 0.508)
				(type default)
			)
			(layer "F.SilkS")
		)
		(fp_rect
			(start -0.7493 0.8001)
			(end 0.7493 -0.8001)
			(stroke
				(width 0)
				(type default)
			)
			(fill no)
			(layer "F.CrtYd")
		)
		(fp_poly
			(pts
				(xy -1.3716 1.6764) (xy -1.3716 -1.6764) (xy 1.3716 -1.6764) (xy 1.3716 0.0635) (xy 0.7493 0.0635)
				(xy 0.7493 -0.8001) (xy -0.7493 -0.8001) (xy -0.7493 0.8001) (xy 0.7493 0.8001) (xy 0.7493 0.0762)
				(xy 1.3716 0.0762) (xy 1.3716 1.6764)
			)
			(stroke
				(width 0)
				(type default)
			)
			(fill no)
			(layer "F.CrtYd")
		)
		(fp_rect
			(start -1.3716 1.6764)
			(end 1.3716 -1.6764)
			(stroke
				(width 0)
				(type default)
			)
			(fill no)
			(layer "F.Fab")
		)
		(pad "1" smd rect
			(at 0.50038 -0.73025)
			(size 0.7112 0.8636)
			(layers "F.Cu" "F.Mask" "F.Paste")
			(net "DRV_ACT_2")
		)
		(pad "2" smd rect
			(at -0.50038 -0.73025)
			(size 0.7112 0.8636)
			(layers "F.Cu" "F.Mask" "F.Paste")
			(net "FLT_HDD2")
		)
		(pad "3" smd rect
			(at 0.50038 0.73025)
			(size 0.7112 0.8636)
			(layers "F.Cu" "F.Mask" "F.Paste")
			(net "DRV_ACT_2_N")
		)
		(pad "4" smd rect
			(at -0.50038 0.73025)
			(size 0.7112 0.8636)
			(layers "F.Cu" "F.Mask" "F.Paste")
			(net "FLT_HDD2_N")
		)
	)
	(footprint ""
		(layer "F.Cu")
		(at 180.975 -368.2238 90)
		(property "Reference" "C1"
			(at 0 0 90)
			(layer "F.SilkS")
			(hide yes)
			(effects
				(font
					(size 1.27 1.27)
				)
			)
		)
		(property "Value" "SCD1U25V2KX-2-GP"
			(at 1.1811 -2.7051 90)
			(unlocked yes)
			(layer "F.Fab")
			(hide yes)
			(effects
				(font
					(size 1.016 1.016)
					(thickness 0.1524)
				)
			)
		)
		(property "Device Type" "C402H22"
			(at 1.1811 -4.2291 90)
			(unlocked yes)
			(layer "F.Fab")
			(hide yes)
			(effects
				(font
					(size 1.016 1.016)
					(thickness 0.1524)
				)
			)
		)
		(duplicate_pad_numbers_are_jumpers no)
		(fp_rect
			(start -0.4318 0.9525)
			(end 0.4318 -0.9525)
			(stroke
				(width 0)
				(type default)
			)
			(fill no)
			(layer "F.CrtYd")
		)
		(fp_rect
			(start -0.4318 0.9525)
			(end 0.4318 -0.9525)
			(stroke
				(width 0)
				(type default)
			)
			(fill no)
			(layer "F.Fab")
		)
		(pad "1" smd custom
			(at 0 -0.4445 90)
			(size 0.1524 0.1524)
			(layers "F.Cu" "F.Mask" "F.Paste")
			(net "MB0_HS_ENABLE")
			(options
				(clearance outline)
				(anchor circle)
			)
			(primitives
				(gr_poly
					(pts
						(arc
							(start 0.3048 -0.2032)
							(mid 0.275042 -0.275042)
							(end 0.2032 -0.3048)
						)
						(arc
							(start -0.2032 -0.3048)
							(mid -0.275042 -0.275042)
							(end -0.3048 -0.2032)
						)
						(arc
							(start -0.3048 0.2032)
							(mid -0.275042 0.275042)
							(end -0.2032 0.3048)
						)
						(arc
							(start 0.2032 0.3048)
							(mid 0.275042 0.275042)
							(end 0.3048 0.2032)
						)
					)
					(width 0)
					(fill yes)
				)
			)
		)
		(pad "2" smd custom
			(at 0 0.4445 90)
			(size 0.1524 0.1524)
			(layers "F.Cu" "F.Mask" "F.Paste")
			(net "GND")
			(options
				(clearance outline)
				(anchor circle)
			)
			(primitives
				(gr_poly
					(pts
						(arc
							(start 0.3048 -0.2032)
							(mid 0.275042 -0.275042)
							(end 0.2032 -0.3048)
						)
						(arc
							(start -0.2032 -0.3048)
							(mid -0.275042 -0.275042)
							(end -0.3048 -0.2032)
						)
						(arc
							(start -0.3048 0.2032)
							(mid -0.275042 0.275042)
							(end -0.2032 0.3048)
						)
						(arc
							(start 0.2032 0.3048)
							(mid 0.275042 0.275042)
							(end 0.3048 0.2032)
						)
					)
					(width 0)
					(fill yes)
				)
			)
		)
	)
	(footprint ""
		(layer "F.Cu")
		(at 323.58965 -248.750074 -90)
		(property "Reference" "VIA14"
			(at 0 0 270)
			(layer "F.SilkS")
			(hide yes)
			(effects
				(font
					(size 1.27 1.27)
				)
			)
		)
		(property "Value" "100OHM-8L-2D36MM-L16-GP"
			(at -3.4036 -0.4572 270)
			(unlocked yes)
			(layer "F.Fab")
			(hide yes)
			(effects
				(font
					(size 1.016 1.016)
					(thickness 0.1524)
				)
			)
		)
		(property "Device Type" "VIA-PCIE-4P-427097"
			(at -3.4036 -1.9812 270)
			(unlocked yes)
			(layer "F.Fab")
			(hide yes)
			(effects
				(font
					(size 1.016 1.016)
					(thickness 0.1524)
				)
			)
		)
		(duplicate_pad_numbers_are_jumpers no)
		(fp_rect
			(start -2.1336 0.4826)
			(end 2.1336 -0.4826)
			(stroke
				(width 0)
				(type default)
			)
			(fill no)
			(layer "F.CrtYd")
		)
		(fp_rect
			(start -2.1336 0.4826)
			(end 2.1336 -0.4826)
			(stroke
				(width 0)
				(type default)
			)
			(fill no)
			(layer "F.Fab")
		)
		(pad "1" thru_hole circle
			(at -1.651 0 270)
			(size 0.508 0.508)
			(drill 0.254)
			(layers "*.Cu" "*.Mask")
			(remove_unused_layers no)
			(net "GND")
			(clearance 0.2286)
			(thermal_gap 0.2286)
		)
		(pad "2" thru_hole circle
			(at -0.635 0 270)
			(size 0.508 0.508)
			(drill 0.254)
			(layers "*.Cu" "*.Mask")
			(remove_unused_layers no)
			(net "PHY_DRV_B_TO_SCC_B_6_DP")
			(clearance 0.2286)
			(thermal_gap 0.2286)
		)
		(pad "3" thru_hole circle
			(at 0.635 0 270)
			(size 0.508 0.508)
			(drill 0.254)
			(layers "*.Cu" "*.Mask")
			(remove_unused_layers no)
			(net "PHY_DRV_B_TO_SCC_B_6_DN")
			(clearance 0.2286)
			(thermal_gap 0.2286)
		)
		(pad "4" thru_hole circle
			(at 1.651 0 270)
			(size 0.508 0.508)
			(drill 0.254)
			(layers "*.Cu" "*.Mask")
			(remove_unused_layers no)
			(net "GND")
			(clearance 0.2286)
			(thermal_gap 0.2286)
		)
	)
	(footprint ""
		(layer "F.Cu")
		(at 181.483 -263.271)
		(property "Reference" "R238"
			(at 0 0 0)
			(layer "F.SilkS")
			(hide yes)
			(effects
				(font
					(size 1.27 1.27)
				)
			)
		)
		(property "Value" "2R6F-GP"
			(at -0.0508 -4.8514 0)
			(unlocked yes)
			(layer "F.Fab")
			(hide yes)
			(effects
				(font
					(size 1.016 1.016)
					(thickness 0.1524)
				)
			)
		)
		(property "Device Type" "R1206H26"
			(at 0 -6.3754 0)
			(unlocked yes)
			(layer "F.Fab")
			(hide yes)
			(effects
				(font
					(size 1.016 1.016)
					(thickness 0.1524)
				)
			)
		)
		(duplicate_pad_numbers_are_jumpers no)
		(fp_line
			(start -1.016 -2.2352)
			(end 1.016 -2.2352)
			(stroke
				(width 0.1524)
				(type default)
			)
			(layer "F.SilkS")
		)
		(fp_line
			(start -1.016 2.2352)
			(end -1.016 -2.2352)
			(stroke
				(width 0.1524)
				(type default)
			)
			(layer "F.SilkS")
		)
		(fp_line
			(start 1.016 -2.2352)
			(end 1.016 2.2352)
			(stroke
				(width 0.1524)
				(type default)
			)
			(layer "F.SilkS")
		)
		(fp_line
			(start 1.016 2.2352)
			(end -1.016 2.2352)
			(stroke
				(width 0.1524)
				(type default)
			)
			(layer "F.SilkS")
		)
		(fp_rect
			(start -1.0922 2.3114)
			(end 1.0922 -2.3114)
			(stroke
				(width 0)
				(type default)
			)
			(fill no)
			(layer "F.CrtYd")
		)
		(fp_poly
			(pts
				(xy -1.0922 -2.3114) (xy 1.0922 -2.3114) (xy 1.0922 2.3114) (xy -1.0922 2.3114)
			)
			(stroke
				(width 0)
				(type default)
			)
			(fill no)
			(layer "F.Fab")
		)
		(pad "1" smd rect
			(at 0 -1.397)
			(size 1.651 1.27)
			(layers "F.Cu" "F.Mask" "F.Paste")
			(net "P5V_HDD5")
		)
		(pad "2" smd rect
			(at 0 1.397)
			(size 1.651 1.27)
			(layers "F.Cu" "F.Mask" "F.Paste")
			(net "5V_PRE_5")
		)
	)
	(footprint ""
		(layer "F.Cu")
		(at 370.205 -257.81 -90)
		(property "Reference" "R281"
			(at 0 0 270)
			(layer "F.SilkS")
			(hide yes)
			(effects
				(font
					(size 1.27 1.27)
				)
			)
		)
		(property "Value" "300KR2F-GP"
			(at 0.064008 -3.993896 270)
			(unlocked yes)
			(layer "F.Fab")
			(hide yes)
			(effects
				(font
					(size 1.016 1.016)
					(thickness 0.1524)
				)
			)
		)
		(property "Device Type" "R402H16"
			(at 0.064008 -5.517896 270)
			(unlocked yes)
			(layer "F.Fab")
			(hide yes)
			(effects
				(font
					(size 1.016 1.016)
					(thickness 0.1524)
				)
			)
		)
		(duplicate_pad_numbers_are_jumpers no)
		(fp_line
			(start -0.508 -0.9398)
			(end -0.508 0.9398)
			(stroke
				(width 0.1524)
				(type default)
			)
			(layer "F.SilkS")
		)
		(fp_line
			(start 0.508 -0.9398)
			(end -0.508 -0.9398)
			(stroke
				(width 0.1524)
				(type default)
			)
			(layer "F.SilkS")
		)
		(fp_rect
			(start -0.508 0.9398)
			(end 0.508 -0.9398)
			(stroke
				(width 0)
				(type default)
			)
			(fill no)
			(layer "F.CrtYd")
		)
		(fp_rect
			(start -0.508 0.9398)
			(end 0.508 -0.9398)
			(stroke
				(width 0)
				(type default)
			)
			(fill no)
			(layer "F.Fab")
		)
		(pad "1" smd custom
			(at 0 -0.4445 270)
			(size 0.1397 0.1397)
			(layers "F.Cu" "F.Mask" "F.Paste")
			(net "SW_HDD_N7")
			(options
				(clearance outline)
				(anchor circle)
			)
			(primitives
				(gr_poly
					(pts
						(arc
							(start -0.1778 -0.2794)
							(mid -0.249642 -0.249642)
							(end -0.2794 -0.1778)
						)
						(arc
							(start -0.2794 0.1778)
							(mid -0.249642 0.249642)
							(end -0.1778 0.2794)
						)
						(arc
							(start 0.1778 0.2794)
							(mid 0.249642 0.249642)
							(end 0.2794 0.1778)
						)
						(arc
							(start 0.2794 -0.1778)
							(mid 0.249642 -0.249642)
							(end 0.1778 -0.2794)
						)
					)
					(width 0)
					(fill yes)
				)
			)
		)
		(pad "2" smd custom
			(at 0 0.4445 270)
			(size 0.1397 0.1397)
			(layers "F.Cu" "F.Mask" "F.Paste")
			(net "P12V_B")
			(options
				(clearance outline)
				(anchor circle)
			)
			(primitives
				(gr_poly
					(pts
						(arc
							(start -0.1778 -0.2794)
							(mid -0.249642 -0.249642)
							(end -0.2794 -0.1778)
						)
						(arc
							(start -0.2794 0.1778)
							(mid -0.249642 0.249642)
							(end -0.1778 0.2794)
						)
						(arc
							(start 0.1778 0.2794)
							(mid 0.249642 0.249642)
							(end 0.2794 0.1778)
						)
						(arc
							(start 0.2794 -0.1778)
							(mid 0.249642 -0.249642)
							(end 0.1778 -0.2794)
						)
					)
					(width 0)
					(fill yes)
				)
			)
		)
	)
	(footprint ""
		(layer "F.Cu")
		(at 447.8782 -261.6454)
		(property "Reference" "C167"
			(at 0 0 0)
			(layer "F.SilkS")
			(hide yes)
			(effects
				(font
					(size 1.27 1.27)
				)
			)
		)
		(property "Value" "SCD01U50V2KX-1GP"
			(at 1.1811 -2.7051 0)
			(unlocked yes)
			(layer "F.Fab")
			(hide yes)
			(effects
				(font
					(size 1.016 1.016)
					(thickness 0.1524)
				)
			)
		)
		(property "Device Type" "C402H22"
			(at 1.1811 -4.2291 0)
			(unlocked yes)
			(layer "F.Fab")
			(hide yes)
			(effects
				(font
					(size 1.016 1.016)
					(thickness 0.1524)
				)
			)
		)
		(duplicate_pad_numbers_are_jumpers no)
		(fp_rect
			(start -0.4318 0.9525)
			(end 0.4318 -0.9525)
			(stroke
				(width 0)
				(type default)
			)
			(fill no)
			(layer "F.CrtYd")
		)
		(fp_rect
			(start -0.4318 0.9525)
			(end 0.4318 -0.9525)
			(stroke
				(width 0)
				(type default)
			)
			(fill no)
			(layer "F.Fab")
		)
		(pad "1" smd custom
			(at 0 -0.4445)
			(size 0.1524 0.1524)
			(layers "F.Cu" "F.Mask" "F.Paste")
			(net "HDD_PRSNT_10")
			(options
				(clearance outline)
				(anchor circle)
			)
			(primitives
				(gr_poly
					(pts
						(arc
							(start 0.3048 -0.2032)
							(mid 0.275042 -0.275042)
							(end 0.2032 -0.3048)
						)
						(arc
							(start -0.2032 -0.3048)
							(mid -0.275042 -0.275042)
							(end -0.3048 -0.2032)
						)
						(arc
							(start -0.3048 0.2032)
							(mid -0.275042 0.275042)
							(end -0.2032 0.3048)
						)
						(arc
							(start 0.2032 0.3048)
							(mid 0.275042 0.275042)
							(end 0.3048 0.2032)
						)
					)
					(width 0)
					(fill yes)
				)
			)
		)
		(pad "2" smd custom
			(at 0 0.4445)
			(size 0.1524 0.1524)
			(layers "F.Cu" "F.Mask" "F.Paste")
			(net "GND")
			(options
				(clearance outline)
				(anchor circle)
			)
			(primitives
				(gr_poly
					(pts
						(arc
							(start 0.3048 -0.2032)
							(mid 0.275042 -0.275042)
							(end 0.2032 -0.3048)
						)
						(arc
							(start -0.2032 -0.3048)
							(mid -0.275042 -0.275042)
							(end -0.3048 -0.2032)
						)
						(arc
							(start -0.3048 0.2032)
							(mid -0.275042 0.275042)
							(end -0.2032 0.3048)
						)
						(arc
							(start 0.2032 0.3048)
							(mid 0.275042 0.275042)
							(end 0.3048 0.2032)
						)
					)
					(width 0)
					(fill yes)
				)
			)
		)
	)
	(footprint ""
		(layer "F.Cu")
		(at 118.364 -263.271)
		(property "Reference" "R206"
			(at 0 0 0)
			(layer "F.SilkS")
			(hide yes)
			(effects
				(font
					(size 1.27 1.27)
				)
			)
		)
		(property "Value" "2R6F-GP"
			(at -0.0508 -4.8514 0)
			(unlocked yes)
			(layer "F.Fab")
			(hide yes)
			(effects
				(font
					(size 1.016 1.016)
					(thickness 0.1524)
				)
			)
		)
		(property "Device Type" "R1206H26"
			(at 0 -6.3754 0)
			(unlocked yes)
			(layer "F.Fab")
			(hide yes)
			(effects
				(font
					(size 1.016 1.016)
					(thickness 0.1524)
				)
			)
		)
		(duplicate_pad_numbers_are_jumpers no)
		(fp_line
			(start -1.016 -2.2352)
			(end 1.016 -2.2352)
			(stroke
				(width 0.1524)
				(type default)
			)
			(layer "F.SilkS")
		)
		(fp_line
			(start -1.016 2.2352)
			(end -1.016 -2.2352)
			(stroke
				(width 0.1524)
				(type default)
			)
			(layer "F.SilkS")
		)
		(fp_line
			(start 1.016 -2.2352)
			(end 1.016 2.2352)
			(stroke
				(width 0.1524)
				(type default)
			)
			(layer "F.SilkS")
		)
		(fp_line
			(start 1.016 2.2352)
			(end -1.016 2.2352)
			(stroke
				(width 0.1524)
				(type default)
			)
			(layer "F.SilkS")
		)
		(fp_rect
			(start -1.0922 2.3114)
			(end 1.0922 -2.3114)
			(stroke
				(width 0)
				(type default)
			)
			(fill no)
			(layer "F.CrtYd")
		)
		(fp_poly
			(pts
				(xy -1.0922 -2.3114) (xy 1.0922 -2.3114) (xy 1.0922 2.3114) (xy -1.0922 2.3114)
			)
			(stroke
				(width 0)
				(type default)
			)
			(fill no)
			(layer "F.Fab")
		)
		(pad "1" smd rect
			(at 0 -1.397)
			(size 1.651 1.27)
			(layers "F.Cu" "F.Mask" "F.Paste")
			(net "P5V_HDD3")
		)
		(pad "2" smd rect
			(at 0 1.397)
			(size 1.651 1.27)
			(layers "F.Cu" "F.Mask" "F.Paste")
			(net "5V_PRE_3")
		)
	)
	(footprint ""
		(layer "F.Cu")
		(at 165.732968 -97.328228 -90)
		(property "Reference" "R398"
			(at 0 0 270)
			(layer "F.SilkS")
			(hide yes)
			(effects
				(font
					(size 1.27 1.27)
				)
			)
		)
		(property "Value" "4K7R2F-GP"
			(at 0.064008 -3.993896 270)
			(unlocked yes)
			(layer "F.Fab")
			(hide yes)
			(effects
				(font
					(size 1.016 1.016)
					(thickness 0.1524)
				)
			)
		)
		(property "Device Type" "R402H16"
			(at 0.064008 -5.517896 270)
			(unlocked yes)
			(layer "F.Fab")
			(hide yes)
			(effects
				(font
					(size 1.016 1.016)
					(thickness 0.1524)
				)
			)
		)
		(duplicate_pad_numbers_are_jumpers no)
		(fp_line
			(start -0.508 -0.9398)
			(end -0.508 0.9398)
			(stroke
				(width 0.1524)
				(type default)
			)
			(layer "F.SilkS")
		)
		(fp_line
			(start 0.508 -0.9398)
			(end -0.508 -0.9398)
			(stroke
				(width 0.1524)
				(type default)
			)
			(layer "F.SilkS")
		)
		(fp_rect
			(start -0.508 0.9398)
			(end 0.508 -0.9398)
			(stroke
				(width 0)
				(type default)
			)
			(fill no)
			(layer "F.CrtYd")
		)
		(fp_rect
			(start -0.508 0.9398)
			(end 0.508 -0.9398)
			(stroke
				(width 0)
				(type default)
			)
			(fill no)
			(layer "F.Fab")
		)
		(pad "1" smd custom
			(at 0 -0.4445 270)
			(size 0.1397 0.1397)
			(layers "F.Cu" "F.Mask" "F.Paste")
			(net "DRIVE_B_17_ACT")
			(options
				(clearance outline)
				(anchor circle)
			)
			(primitives
				(gr_poly
					(pts
						(arc
							(start -0.1778 -0.2794)
							(mid -0.249642 -0.249642)
							(end -0.2794 -0.1778)
						)
						(arc
							(start -0.2794 0.1778)
							(mid -0.249642 0.249642)
							(end -0.1778 0.2794)
						)
						(arc
							(start 0.1778 0.2794)
							(mid 0.249642 0.249642)
							(end 0.2794 0.1778)
						)
						(arc
							(start 0.2794 -0.1778)
							(mid 0.249642 -0.249642)
							(end 0.1778 -0.2794)
						)
					)
					(width 0)
					(fill yes)
				)
			)
		)
		(pad "2" smd custom
			(at 0 0.4445 270)
			(size 0.1397 0.1397)
			(layers "F.Cu" "F.Mask" "F.Paste")
			(net "GND")
			(options
				(clearance outline)
				(anchor circle)
			)
			(primitives
				(gr_poly
					(pts
						(arc
							(start -0.1778 -0.2794)
							(mid -0.249642 -0.249642)
							(end -0.2794 -0.1778)
						)
						(arc
							(start -0.2794 0.1778)
							(mid -0.249642 0.249642)
							(end -0.1778 0.2794)
						)
						(arc
							(start 0.1778 0.2794)
							(mid 0.249642 0.249642)
							(end 0.2794 0.1778)
						)
						(arc
							(start 0.2794 -0.1778)
							(mid 0.249642 -0.249642)
							(end 0.1778 -0.2794)
						)
					)
					(width 0)
					(fill yes)
				)
			)
		)
	)
	(footprint ""
		(layer "F.Cu")
		(at 311.900062 -377.219972 180)
		(property "Reference" "FLED3"
			(at 0 0 180)
			(layer "F.SilkS")
			(hide yes)
			(effects
				(font
					(size 1.27 1.27)
				)
			)
		)
		(property "Value" "LED-BY-14-GP"
			(at -4.7752 -2.1844 180)
			(unlocked yes)
			(layer "F.Fab")
			(hide yes)
			(effects
				(font
					(size 1.016 1.016)
					(thickness 0.1524)
				)
			)
		)
		(property "Device Type" "LED-100-3PH206"
			(at -4.7752 -3.7084 180)
			(unlocked yes)
			(layer "F.Fab")
			(hide yes)
			(effects
				(font
					(size 1.016 1.016)
					(thickness 0.1524)
				)
			)
		)
		(duplicate_pad_numbers_are_jumpers no)
		(fp_line
			(start 3.7592 8.0264)
			(end -3.7592 8.0264)
			(stroke
				(width 0.1524)
				(type default)
			)
			(layer "F.SilkS")
		)
		(fp_line
			(start 3.7592 -1.524)
			(end 3.7592 8.0264)
			(stroke
				(width 0.1524)
				(type default)
			)
			(layer "F.SilkS")
		)
		(fp_line
			(start 1.87833 3.63474)
			(end 0.58293 2.33934)
			(stroke
				(width 0.1524)
				(type default)
			)
			(layer "F.SilkS")
		)
		(fp_line
			(start 1.87833 2.33934)
			(end 2.81813 2.33934)
			(stroke
				(width 0.1524)
				(type default)
			)
			(layer "F.SilkS")
		)
		(fp_line
			(start 1.87833 1.04394)
			(end 1.87833 3.63474)
			(stroke
				(width 0.1524)
				(type default)
			)
			(layer "F.SilkS")
		)
		(fp_line
			(start 0.58293 3.05054)
			(end 0.58293 1.42494)
			(stroke
				(width 0.1524)
				(type default)
			)
			(layer "F.SilkS")
		)
		(fp_line
			(start 0.58293 2.33934)
			(end 1.87833 1.04394)
			(stroke
				(width 0.1524)
				(type default)
			)
			(layer "F.SilkS")
		)
		(fp_line
			(start -0.45847 3.05054)
			(end -0.45847 1.42494)
			(stroke
				(width 0.1524)
				(type default)
			)
			(layer "F.SilkS")
		)
		(fp_line
			(start -0.45847 2.33934)
			(end 0.58293 2.33934)
			(stroke
				(width 0.1524)
				(type default)
			)
			(layer "F.SilkS")
		)
		(fp_line
			(start -0.45847 2.33934)
			(end -1.75387 1.04394)
			(stroke
				(width 0.1524)
				(type default)
			)
			(layer "F.SilkS")
		)
		(fp_line
			(start -1.75387 3.63474)
			(end -0.45847 2.33934)
			(stroke
				(width 0.1524)
				(type default)
			)
			(layer "F.SilkS")
		)
		(fp_line
			(start -1.75387 2.33934)
			(end -3.45567 2.33934)
			(stroke
				(width 0.1524)
				(type default)
			)
			(layer "F.SilkS")
		)
		(fp_line
			(start -1.75387 1.04394)
			(end -1.75387 3.63474)
			(stroke
				(width 0.1524)
				(type default)
			)
			(layer "F.SilkS")
		)
		(fp_line
			(start -3.7592 8.0264)
			(end -3.7592 -1.524)
			(stroke
				(width 0.1524)
				(type default)
			)
			(layer "F.SilkS")
		)
		(fp_line
			(start -3.7592 -1.524)
			(end 3.7592 -1.524)
			(stroke
				(width 0.1524)
				(type default)
			)
			(layer "F.SilkS")
		)
		(fp_circle
			(center 2.54 0)
			(end 1.5494 0)
			(stroke
				(width 0.3048)
				(type default)
			)
			(fill no)
			(layer "F.SilkS")
		)
		(fp_circle
			(center 0 0)
			(end -0.9906 0)
			(stroke
				(width 0.3048)
				(type default)
			)
			(fill no)
			(layer "F.SilkS")
		)
		(fp_circle
			(center -2.54 0)
			(end -3.5306 0)
			(stroke
				(width 0.3048)
				(type default)
			)
			(fill no)
			(layer "F.SilkS")
		)
		(fp_rect
			(start -3.5052 7.7724)
			(end 3.5052 -1.27)
			(stroke
				(width 0)
				(type default)
			)
			(fill no)
			(layer "F.CrtYd")
		)
		(fp_poly
			(pts
				(xy -4.0132 8.2804) (xy -4.0132 -1.778) (xy -3.5052 -1.778) (xy -3.5052 7.7724) (xy 3.5052 7.7724)
				(xy 3.5052 -1.27) (xy -3.50012 -1.27) (xy -3.50012 -1.778) (xy 4.0132 -1.778) (xy 4.0132 8.2804)
			)
			(stroke
				(width 0)
				(type default)
			)
			(fill no)
			(layer "F.CrtYd")
		)
		(fp_rect
			(start -4.0132 8.2804)
			(end 4.0132 -1.778)
			(stroke
				(width 0)
				(type default)
			)
			(fill no)
			(layer "F.Fab")
		)
		(pad "1" thru_hole circle
			(at -2.54 0 180)
			(size 1.27 1.27)
			(drill 0.889)
			(layers "*.Cu" "*.Mask")
			(remove_unused_layers no)
			(net "FAN_LED_BLUE2")
			(clearance 0.1651)
			(thermal_gap 0.1651)
		)
		(pad "2" thru_hole circle
			(at 0 0 180)
			(size 1.27 1.27)
			(drill 0.889)
			(layers "*.Cu" "*.Mask")
			(remove_unused_layers no)
			(net "GND")
			(clearance 0.1651)
			(thermal_gap 0.1651)
		)
		(pad "3" thru_hole circle
			(at 2.54 0 180)
			(size 1.27 1.27)
			(drill 0.889)
			(layers "*.Cu" "*.Mask")
			(remove_unused_layers no)
			(net "FAN_LED_YELLOW_2")
			(clearance 0.1651)
			(thermal_gap 0.1651)
		)
	)
	(footprint ""
		(layer "F.Cu")
		(at 66.7258 -262.128 90)
		(property "Reference" "C43"
			(at 0 0 90)
			(layer "F.SilkS")
			(hide yes)
			(effects
				(font
					(size 1.27 1.27)
				)
			)
		)
		(property "Value" "SCD01U50V2KX-1GP"
			(at 1.1811 -2.7051 90)
			(unlocked yes)
			(layer "F.Fab")
			(hide yes)
			(effects
				(font
					(size 1.016 1.016)
					(thickness 0.1524)
				)
			)
		)
		(property "Device Type" "C402H22"
			(at 1.1811 -4.2291 90)
			(unlocked yes)
			(layer "F.Fab")
			(hide yes)
			(effects
				(font
					(size 1.016 1.016)
					(thickness 0.1524)
				)
			)
		)
		(duplicate_pad_numbers_are_jumpers no)
		(fp_rect
			(start -0.4318 0.9525)
			(end 0.4318 -0.9525)
			(stroke
				(width 0)
				(type default)
			)
			(fill no)
			(layer "F.CrtYd")
		)
		(fp_rect
			(start -0.4318 0.9525)
			(end 0.4318 -0.9525)
			(stroke
				(width 0)
				(type default)
			)
			(fill no)
			(layer "F.Fab")
		)
		(pad "1" smd custom
			(at 0 -0.4445 90)
			(size 0.1524 0.1524)
			(layers "F.Cu" "F.Mask" "F.Paste")
			(net "HDD_PRSNT_1")
			(options
				(clearance outline)
				(anchor circle)
			)
			(primitives
				(gr_poly
					(pts
						(arc
							(start 0.3048 -0.2032)
							(mid 0.275042 -0.275042)
							(end 0.2032 -0.3048)
						)
						(arc
							(start -0.2032 -0.3048)
							(mid -0.275042 -0.275042)
							(end -0.3048 -0.2032)
						)
						(arc
							(start -0.3048 0.2032)
							(mid -0.275042 0.275042)
							(end -0.2032 0.3048)
						)
						(arc
							(start 0.2032 0.3048)
							(mid 0.275042 0.275042)
							(end 0.3048 0.2032)
						)
					)
					(width 0)
					(fill yes)
				)
			)
		)
		(pad "2" smd custom
			(at 0 0.4445 90)
			(size 0.1524 0.1524)
			(layers "F.Cu" "F.Mask" "F.Paste")
			(net "GND")
			(options
				(clearance outline)
				(anchor circle)
			)
			(primitives
				(gr_poly
					(pts
						(arc
							(start 0.3048 -0.2032)
							(mid 0.275042 -0.275042)
							(end 0.2032 -0.3048)
						)
						(arc
							(start -0.2032 -0.3048)
							(mid -0.275042 -0.275042)
							(end -0.3048 -0.2032)
						)
						(arc
							(start -0.3048 0.2032)
							(mid -0.275042 0.275042)
							(end -0.2032 0.3048)
						)
						(arc
							(start 0.2032 0.3048)
							(mid 0.275042 0.275042)
							(end 0.3048 0.2032)
						)
					)
					(width 0)
					(fill yes)
				)
			)
		)
	)
	(footprint ""
		(layer "F.Cu")
		(at 143.002 -23.114 90)
		(property "Reference" "R721"
			(at 0 0 90)
			(layer "F.SilkS")
			(hide yes)
			(effects
				(font
					(size 1.27 1.27)
				)
			)
		)
		(property "Value" "4K7R2J-2-GP"
			(at 0.064008 -3.993896 90)
			(unlocked yes)
			(layer "F.Fab")
			(hide yes)
			(effects
				(font
					(size 1.016 1.016)
					(thickness 0.1524)
				)
			)
		)
		(property "Device Type" "R402H16"
			(at 0.064008 -5.517896 90)
			(unlocked yes)
			(layer "F.Fab")
			(hide yes)
			(effects
				(font
					(size 1.016 1.016)
					(thickness 0.1524)
				)
			)
		)
		(duplicate_pad_numbers_are_jumpers no)
		(fp_line
			(start 0.508 -0.9398)
			(end -0.508 -0.9398)
			(stroke
				(width 0.1524)
				(type default)
			)
			(layer "F.SilkS")
		)
		(fp_line
			(start -0.508 -0.9398)
			(end -0.508 0.9398)
			(stroke
				(width 0.1524)
				(type default)
			)
			(layer "F.SilkS")
		)
		(fp_rect
			(start -0.508 0.9398)
			(end 0.508 -0.9398)
			(stroke
				(width 0)
				(type default)
			)
			(fill no)
			(layer "F.CrtYd")
		)
		(fp_rect
			(start -0.508 0.9398)
			(end 0.508 -0.9398)
			(stroke
				(width 0)
				(type default)
			)
			(fill no)
			(layer "F.Fab")
		)
		(pad "1" smd custom
			(at 0 -0.4445 90)
			(size 0.1397 0.1397)
			(layers "F.Cu" "F.Mask" "F.Paste")
			(net "P12V_B")
			(options
				(clearance outline)
				(anchor circle)
			)
			(primitives
				(gr_poly
					(pts
						(arc
							(start -0.1778 -0.2794)
							(mid -0.249642 -0.249642)
							(end -0.2794 -0.1778)
						)
						(arc
							(start -0.2794 0.1778)
							(mid -0.249642 0.249642)
							(end -0.1778 0.2794)
						)
						(arc
							(start 0.1778 0.2794)
							(mid 0.249642 0.249642)
							(end 0.2794 0.1778)
						)
						(arc
							(start 0.2794 -0.1778)
							(mid 0.249642 -0.249642)
							(end 0.1778 -0.2794)
						)
					)
					(width 0)
					(fill yes)
				)
			)
		)
		(pad "2" smd custom
			(at 0 0.4445 90)
			(size 0.1397 0.1397)
			(layers "F.Cu" "F.Mask" "F.Paste")
			(net "SW_HDD_P28")
			(options
				(clearance outline)
				(anchor circle)
			)
			(primitives
				(gr_poly
					(pts
						(arc
							(start -0.1778 -0.2794)
							(mid -0.249642 -0.249642)
							(end -0.2794 -0.1778)
						)
						(arc
							(start -0.2794 0.1778)
							(mid -0.249642 0.249642)
							(end -0.1778 0.2794)
						)
						(arc
							(start 0.1778 0.2794)
							(mid 0.249642 0.249642)
							(end 0.2794 0.1778)
						)
						(arc
							(start 0.2794 -0.1778)
							(mid 0.249642 -0.249642)
							(end 0.1778 -0.2794)
						)
					)
					(width 0)
					(fill yes)
				)
			)
		)
	)
	(footprint ""
		(layer "F.Cu")
		(at 221.996 -220.853 -90)
		(property "Reference" "R17"
			(at 0 0 270)
			(layer "F.SilkS")
			(hide yes)
			(effects
				(font
					(size 1.27 1.27)
				)
			)
		)
		(property "Value" "4K7R2F-GP"
			(at 0.064008 -3.993896 270)
			(unlocked yes)
			(layer "F.Fab")
			(hide yes)
			(effects
				(font
					(size 1.016 1.016)
					(thickness 0.1524)
				)
			)
		)
		(property "Device Type" "R402H16"
			(at 0.064008 -5.517896 270)
			(unlocked yes)
			(layer "F.Fab")
			(hide yes)
			(effects
				(font
					(size 1.016 1.016)
					(thickness 0.1524)
				)
			)
		)
		(duplicate_pad_numbers_are_jumpers no)
		(fp_line
			(start -0.508 -0.9398)
			(end -0.508 0.9398)
			(stroke
				(width 0.1524)
				(type default)
			)
			(layer "F.SilkS")
		)
		(fp_line
			(start 0.508 -0.9398)
			(end -0.508 -0.9398)
			(stroke
				(width 0.1524)
				(type default)
			)
			(layer "F.SilkS")
		)
		(fp_rect
			(start -0.508 0.9398)
			(end 0.508 -0.9398)
			(stroke
				(width 0)
				(type default)
			)
			(fill no)
			(layer "F.CrtYd")
		)
		(fp_rect
			(start -0.508 0.9398)
			(end 0.508 -0.9398)
			(stroke
				(width 0)
				(type default)
			)
			(fill no)
			(layer "F.Fab")
		)
		(pad "1" smd custom
			(at 0 -0.4445 270)
			(size 0.1397 0.1397)
			(layers "F.Cu" "F.Mask" "F.Paste")
			(net "P3V3_STBY_B")
			(options
				(clearance outline)
				(anchor circle)
			)
			(primitives
				(gr_poly
					(pts
						(arc
							(start -0.1778 -0.2794)
							(mid -0.249642 -0.249642)
							(end -0.2794 -0.1778)
						)
						(arc
							(start -0.2794 0.1778)
							(mid -0.249642 0.249642)
							(end -0.1778 0.2794)
						)
						(arc
							(start 0.1778 0.2794)
							(mid 0.249642 0.249642)
							(end 0.2794 0.1778)
						)
						(arc
							(start 0.2794 -0.1778)
							(mid 0.249642 -0.249642)
							(end 0.1778 -0.2794)
						)
					)
					(width 0)
					(fill yes)
				)
			)
		)
		(pad "2" smd custom
			(at 0 0.4445 270)
			(size 0.1397 0.1397)
			(layers "F.Cu" "F.Mask" "F.Paste")
			(net "IO_EXP1_HDD_FAULT_A0")
			(options
				(clearance outline)
				(anchor circle)
			)
			(primitives
				(gr_poly
					(pts
						(arc
							(start -0.1778 -0.2794)
							(mid -0.249642 -0.249642)
							(end -0.2794 -0.1778)
						)
						(arc
							(start -0.2794 0.1778)
							(mid -0.249642 0.249642)
							(end -0.1778 0.2794)
						)
						(arc
							(start 0.1778 0.2794)
							(mid 0.249642 0.249642)
							(end 0.2794 0.1778)
						)
						(arc
							(start 0.2794 -0.1778)
							(mid 0.249642 -0.249642)
							(end 0.1778 -0.2794)
						)
					)
					(width 0)
					(fill yes)
				)
			)
		)
	)
	(footprint ""
		(layer "F.Cu")
		(at 415.0868 -146.6342 180)
		(property "Reference" "R553"
			(at 0 0 180)
			(layer "F.SilkS")
			(hide yes)
			(effects
				(font
					(size 1.27 1.27)
				)
			)
		)
		(property "Value" "10KR2F-2-GP"
			(at 0.064008 -3.993896 180)
			(unlocked yes)
			(layer "F.Fab")
			(hide yes)
			(effects
				(font
					(size 1.016 1.016)
					(thickness 0.1524)
				)
			)
		)
		(property "Device Type" "R402H16"
			(at 0.064008 -5.517896 180)
			(unlocked yes)
			(layer "F.Fab")
			(hide yes)
			(effects
				(font
					(size 1.016 1.016)
					(thickness 0.1524)
				)
			)
		)
		(duplicate_pad_numbers_are_jumpers no)
		(fp_line
			(start 0.508 -0.9398)
			(end -0.508 -0.9398)
			(stroke
				(width 0.1524)
				(type default)
			)
			(layer "F.SilkS")
		)
		(fp_line
			(start -0.508 -0.9398)
			(end -0.508 0.9398)
			(stroke
				(width 0.1524)
				(type default)
			)
			(layer "F.SilkS")
		)
		(fp_rect
			(start -0.508 0.9398)
			(end 0.508 -0.9398)
			(stroke
				(width 0)
				(type default)
			)
			(fill no)
			(layer "F.CrtYd")
		)
		(fp_rect
			(start -0.508 0.9398)
			(end 0.508 -0.9398)
			(stroke
				(width 0)
				(type default)
			)
			(fill no)
			(layer "F.Fab")
		)
		(pad "1" smd custom
			(at 0 -0.4445 180)
			(size 0.1397 0.1397)
			(layers "F.Cu" "F.Mask" "F.Paste")
			(net "P3V3_STBY_B")
			(options
				(clearance outline)
				(anchor circle)
			)
			(primitives
				(gr_poly
					(pts
						(arc
							(start -0.1778 -0.2794)
							(mid -0.249642 -0.249642)
							(end -0.2794 -0.1778)
						)
						(arc
							(start -0.2794 0.1778)
							(mid -0.249642 0.249642)
							(end -0.1778 0.2794)
						)
						(arc
							(start 0.1778 0.2794)
							(mid 0.249642 0.249642)
							(end 0.2794 0.1778)
						)
						(arc
							(start 0.2794 -0.1778)
							(mid 0.249642 -0.249642)
							(end 0.1778 -0.2794)
						)
					)
					(width 0)
					(fill yes)
				)
			)
		)
		(pad "2" smd custom
			(at 0 0.4445 180)
			(size 0.1397 0.1397)
			(layers "F.Cu" "F.Mask" "F.Paste")
			(net "HDD_PRSNT_21")
			(options
				(clearance outline)
				(anchor circle)
			)
			(primitives
				(gr_poly
					(pts
						(arc
							(start -0.1778 -0.2794)
							(mid -0.249642 -0.249642)
							(end -0.2794 -0.1778)
						)
						(arc
							(start -0.2794 0.1778)
							(mid -0.249642 0.249642)
							(end -0.1778 0.2794)
						)
						(arc
							(start 0.1778 0.2794)
							(mid 0.249642 0.249642)
							(end 0.2794 0.1778)
						)
						(arc
							(start 0.2794 -0.1778)
							(mid 0.249642 -0.249642)
							(end 0.1778 -0.2794)
						)
					)
					(width 0)
					(fill yes)
				)
			)
		)
	)
	(footprint ""
		(layer "F.Cu")
		(at 44.1706 -5.3086 -90)
		(property "Reference" "R124"
			(at 0 0 270)
			(layer "F.SilkS")
			(hide yes)
			(effects
				(font
					(size 1.27 1.27)
				)
			)
		)
		(property "Value" "4K7R2F-GP"
			(at 0.064008 -3.993896 270)
			(unlocked yes)
			(layer "F.Fab")
			(hide yes)
			(effects
				(font
					(size 1.016 1.016)
					(thickness 0.1524)
				)
			)
		)
		(property "Device Type" "R402H16"
			(at 0.064008 -5.517896 270)
			(unlocked yes)
			(layer "F.Fab")
			(hide yes)
			(effects
				(font
					(size 1.016 1.016)
					(thickness 0.1524)
				)
			)
		)
		(duplicate_pad_numbers_are_jumpers no)
		(fp_line
			(start -0.508 -0.9398)
			(end -0.508 0.9398)
			(stroke
				(width 0.1524)
				(type default)
			)
			(layer "F.SilkS")
		)
		(fp_line
			(start 0.508 -0.9398)
			(end -0.508 -0.9398)
			(stroke
				(width 0.1524)
				(type default)
			)
			(layer "F.SilkS")
		)
		(fp_rect
			(start -0.508 0.9398)
			(end 0.508 -0.9398)
			(stroke
				(width 0)
				(type default)
			)
			(fill no)
			(layer "F.CrtYd")
		)
		(fp_rect
			(start -0.508 0.9398)
			(end 0.508 -0.9398)
			(stroke
				(width 0)
				(type default)
			)
			(fill no)
			(layer "F.Fab")
		)
		(pad "1" smd custom
			(at 0 -0.4445 270)
			(size 0.1397 0.1397)
			(layers "F.Cu" "F.Mask" "F.Paste")
			(net "P3V3_STBY_A")
			(options
				(clearance outline)
				(anchor circle)
			)
			(primitives
				(gr_poly
					(pts
						(arc
							(start -0.1778 -0.2794)
							(mid -0.249642 -0.249642)
							(end -0.2794 -0.1778)
						)
						(arc
							(start -0.2794 0.1778)
							(mid -0.249642 0.249642)
							(end -0.1778 0.2794)
						)
						(arc
							(start 0.1778 0.2794)
							(mid 0.249642 0.249642)
							(end 0.2794 0.1778)
						)
						(arc
							(start 0.2794 -0.1778)
							(mid 0.249642 -0.249642)
							(end 0.1778 -0.2794)
						)
					)
					(width 0)
					(fill yes)
				)
			)
		)
		(pad "2" smd custom
			(at 0 0.4445 270)
			(size 0.1397 0.1397)
			(layers "F.Cu" "F.Mask" "F.Paste")
			(net "TEMP1_A2")
			(options
				(clearance outline)
				(anchor circle)
			)
			(primitives
				(gr_poly
					(pts
						(arc
							(start -0.1778 -0.2794)
							(mid -0.249642 -0.249642)
							(end -0.2794 -0.1778)
						)
						(arc
							(start -0.2794 0.1778)
							(mid -0.249642 0.249642)
							(end -0.1778 0.2794)
						)
						(arc
							(start 0.1778 0.2794)
							(mid 0.249642 0.249642)
							(end 0.2794 0.1778)
						)
						(arc
							(start 0.2794 -0.1778)
							(mid 0.249642 -0.249642)
							(end 0.1778 -0.2794)
						)
					)
					(width 0)
					(fill yes)
				)
			)
		)
	)
	(footprint ""
		(layer "F.Cu")
		(at 35.306 -262.128 90)
		(property "Reference" "C505"
			(at 0 0 90)
			(layer "F.SilkS")
			(hide yes)
			(effects
				(font
					(size 1.27 1.27)
				)
			)
		)
		(property "Value" "SCD01U50V2KX-1GP"
			(at 1.1811 -2.7051 90)
			(unlocked yes)
			(layer "F.Fab")
			(hide yes)
			(effects
				(font
					(size 1.016 1.016)
					(thickness 0.1524)
				)
			)
		)
		(property "Device Type" "C402H22"
			(at 1.1811 -4.2291 90)
			(unlocked yes)
			(layer "F.Fab")
			(hide yes)
			(effects
				(font
					(size 1.016 1.016)
					(thickness 0.1524)
				)
			)
		)
		(duplicate_pad_numbers_are_jumpers no)
		(fp_rect
			(start -0.4318 0.9525)
			(end 0.4318 -0.9525)
			(stroke
				(width 0)
				(type default)
			)
			(fill no)
			(layer "F.CrtYd")
		)
		(fp_rect
			(start -0.4318 0.9525)
			(end 0.4318 -0.9525)
			(stroke
				(width 0)
				(type default)
			)
			(fill no)
			(layer "F.Fab")
		)
		(pad "1" smd custom
			(at 0 -0.4445 90)
			(size 0.1524 0.1524)
			(layers "F.Cu" "F.Mask" "F.Paste")
			(net "HDD_PRSNT_0")
			(options
				(clearance outline)
				(anchor circle)
			)
			(primitives
				(gr_poly
					(pts
						(arc
							(start 0.3048 -0.2032)
							(mid 0.275042 -0.275042)
							(end 0.2032 -0.3048)
						)
						(arc
							(start -0.2032 -0.3048)
							(mid -0.275042 -0.275042)
							(end -0.3048 -0.2032)
						)
						(arc
							(start -0.3048 0.2032)
							(mid -0.275042 0.275042)
							(end -0.2032 0.3048)
						)
						(arc
							(start 0.2032 0.3048)
							(mid 0.275042 0.275042)
							(end 0.3048 0.2032)
						)
					)
					(width 0)
					(fill yes)
				)
			)
		)
		(pad "2" smd custom
			(at 0 0.4445 90)
			(size 0.1524 0.1524)
			(layers "F.Cu" "F.Mask" "F.Paste")
			(net "GND")
			(options
				(clearance outline)
				(anchor circle)
			)
			(primitives
				(gr_poly
					(pts
						(arc
							(start 0.3048 -0.2032)
							(mid 0.275042 -0.275042)
							(end 0.2032 -0.3048)
						)
						(arc
							(start -0.2032 -0.3048)
							(mid -0.275042 -0.275042)
							(end -0.3048 -0.2032)
						)
						(arc
							(start -0.3048 0.2032)
							(mid -0.275042 0.275042)
							(end -0.2032 0.3048)
						)
						(arc
							(start 0.2032 0.3048)
							(mid 0.275042 0.275042)
							(end 0.3048 0.2032)
						)
					)
					(width 0)
					(fill yes)
				)
			)
		)
	)
	(footprint ""
		(layer "F.Cu")
		(at 329.819 -275.336 180)
		(property "Reference" "C114"
			(at 0 0 180)
			(layer "F.SilkS")
			(hide yes)
			(effects
				(font
					(size 1.27 1.27)
				)
			)
		)
		(property "Value" "SC1U25V3KX-GP"
			(at 0 -2.8194 180)
			(unlocked yes)
			(layer "F.Fab")
			(hide yes)
			(effects
				(font
					(size 1.016 1.016)
					(thickness 0.1524)
				)
			)
		)
		(property "Device Type" "C603H36"
			(at 0 -4.3434 180)
			(unlocked yes)
			(layer "F.Fab")
			(hide yes)
			(effects
				(font
					(size 1.016 1.016)
					(thickness 0.1524)
				)
			)
		)
		(duplicate_pad_numbers_are_jumpers no)
		(fp_line
			(start 0.508 0)
			(end -0.508 0)
			(stroke
				(width 0.2032)
				(type default)
			)
			(layer "F.SilkS")
		)
		(fp_rect
			(start -0.5842 1.3335)
			(end 0.5842 -1.3335)
			(stroke
				(width 0)
				(type default)
			)
			(fill no)
			(layer "F.CrtYd")
		)
		(fp_rect
			(start -0.5842 1.3335)
			(end 0.5842 -1.3335)
			(stroke
				(width 0)
				(type default)
			)
			(fill no)
			(layer "F.Fab")
		)
		(pad "1" smd custom
			(at 0 -0.762 180)
			(size 0.2159 0.2159)
			(layers "F.Cu" "F.Mask" "F.Paste")
			(net "P12V_HDD6")
			(options
				(clearance outline)
				(anchor circle)
			)
			(primitives
				(gr_poly
					(pts
						(arc
							(start -0.3302 -0.4318)
							(mid -0.402042 -0.402042)
							(end -0.4318 -0.3302)
						)
						(arc
							(start -0.4318 0.3302)
							(mid -0.402042 0.402042)
							(end -0.3302 0.4318)
						)
						(arc
							(start 0.3302 0.4318)
							(mid 0.402042 0.402042)
							(end 0.4318 0.3302)
						)
						(arc
							(start 0.4318 -0.3302)
							(mid 0.402042 -0.402042)
							(end 0.3302 -0.4318)
						)
					)
					(width 0)
					(fill yes)
				)
			)
		)
		(pad "2" smd custom
			(at 0 0.762 180)
			(size 0.2159 0.2159)
			(layers "F.Cu" "F.Mask" "F.Paste")
			(net "GND")
			(options
				(clearance outline)
				(anchor circle)
			)
			(primitives
				(gr_poly
					(pts
						(arc
							(start -0.3302 -0.4318)
							(mid -0.402042 -0.402042)
							(end -0.4318 -0.3302)
						)
						(arc
							(start -0.4318 0.3302)
							(mid -0.402042 0.402042)
							(end -0.3302 0.4318)
						)
						(arc
							(start 0.3302 0.4318)
							(mid 0.402042 0.402042)
							(end 0.4318 0.3302)
						)
						(arc
							(start 0.4318 -0.3302)
							(mid 0.402042 -0.402042)
							(end 0.3302 -0.4318)
						)
					)
					(width 0)
					(fill yes)
				)
			)
		)
	)
	(footprint ""
		(layer "F.Cu")
		(at 371.801644 -212.390228 -90)
		(property "Reference" "R277"
			(at 0 0 270)
			(layer "F.SilkS")
			(hide yes)
			(effects
				(font
					(size 1.27 1.27)
				)
			)
		)
		(property "Value" "4K7R2F-GP"
			(at 0.064008 -3.993896 270)
			(unlocked yes)
			(layer "F.Fab")
			(hide yes)
			(effects
				(font
					(size 1.016 1.016)
					(thickness 0.1524)
				)
			)
		)
		(property "Device Type" "R402H16"
			(at 0.064008 -5.517896 270)
			(unlocked yes)
			(layer "F.Fab")
			(hide yes)
			(effects
				(font
					(size 1.016 1.016)
					(thickness 0.1524)
				)
			)
		)
		(duplicate_pad_numbers_are_jumpers no)
		(fp_line
			(start -0.508 -0.9398)
			(end -0.508 0.9398)
			(stroke
				(width 0.1524)
				(type default)
			)
			(layer "F.SilkS")
		)
		(fp_line
			(start 0.508 -0.9398)
			(end -0.508 -0.9398)
			(stroke
				(width 0.1524)
				(type default)
			)
			(layer "F.SilkS")
		)
		(fp_rect
			(start -0.508 0.9398)
			(end 0.508 -0.9398)
			(stroke
				(width 0)
				(type default)
			)
			(fill no)
			(layer "F.CrtYd")
		)
		(fp_rect
			(start -0.508 0.9398)
			(end 0.508 -0.9398)
			(stroke
				(width 0)
				(type default)
			)
			(fill no)
			(layer "F.Fab")
		)
		(pad "1" smd custom
			(at 0 -0.4445 270)
			(size 0.1397 0.1397)
			(layers "F.Cu" "F.Mask" "F.Paste")
			(net "DRIVE_B_8_ACT")
			(options
				(clearance outline)
				(anchor circle)
			)
			(primitives
				(gr_poly
					(pts
						(arc
							(start -0.1778 -0.2794)
							(mid -0.249642 -0.249642)
							(end -0.2794 -0.1778)
						)
						(arc
							(start -0.2794 0.1778)
							(mid -0.249642 0.249642)
							(end -0.1778 0.2794)
						)
						(arc
							(start 0.1778 0.2794)
							(mid 0.249642 0.249642)
							(end 0.2794 0.1778)
						)
						(arc
							(start 0.2794 -0.1778)
							(mid 0.249642 -0.249642)
							(end 0.1778 -0.2794)
						)
					)
					(width 0)
					(fill yes)
				)
			)
		)
		(pad "2" smd custom
			(at 0 0.4445 270)
			(size 0.1397 0.1397)
			(layers "F.Cu" "F.Mask" "F.Paste")
			(net "GND")
			(options
				(clearance outline)
				(anchor circle)
			)
			(primitives
				(gr_poly
					(pts
						(arc
							(start -0.1778 -0.2794)
							(mid -0.249642 -0.249642)
							(end -0.2794 -0.1778)
						)
						(arc
							(start -0.2794 0.1778)
							(mid -0.249642 0.249642)
							(end -0.1778 0.2794)
						)
						(arc
							(start 0.1778 0.2794)
							(mid 0.249642 0.249642)
							(end 0.2794 0.1778)
						)
						(arc
							(start 0.2794 -0.1778)
							(mid 0.249642 -0.249642)
							(end 0.1778 -0.2794)
						)
					)
					(width 0)
					(fill yes)
				)
			)
		)
	)
	(footprint ""
		(layer "F.Cu")
		(at 181.483 -33.274)
		(property "Reference" "R736"
			(at 0 0 0)
			(layer "F.SilkS")
			(hide yes)
			(effects
				(font
					(size 1.27 1.27)
				)
			)
		)
		(property "Value" "2R6F-GP"
			(at -0.0508 -4.8514 0)
			(unlocked yes)
			(layer "F.Fab")
			(hide yes)
			(effects
				(font
					(size 1.016 1.016)
					(thickness 0.1524)
				)
			)
		)
		(property "Device Type" "R1206H26"
			(at 0 -6.3754 0)
			(unlocked yes)
			(layer "F.Fab")
			(hide yes)
			(effects
				(font
					(size 1.016 1.016)
					(thickness 0.1524)
				)
			)
		)
		(duplicate_pad_numbers_are_jumpers no)
		(fp_line
			(start -1.016 -2.2352)
			(end 1.016 -2.2352)
			(stroke
				(width 0.1524)
				(type default)
			)
			(layer "F.SilkS")
		)
		(fp_line
			(start -1.016 2.2352)
			(end -1.016 -2.2352)
			(stroke
				(width 0.1524)
				(type default)
			)
			(layer "F.SilkS")
		)
		(fp_line
			(start 1.016 -2.2352)
			(end 1.016 2.2352)
			(stroke
				(width 0.1524)
				(type default)
			)
			(layer "F.SilkS")
		)
		(fp_line
			(start 1.016 2.2352)
			(end -1.016 2.2352)
			(stroke
				(width 0.1524)
				(type default)
			)
			(layer "F.SilkS")
		)
		(fp_rect
			(start -1.0922 2.3114)
			(end 1.0922 -2.3114)
			(stroke
				(width 0)
				(type default)
			)
			(fill no)
			(layer "F.CrtYd")
		)
		(fp_poly
			(pts
				(xy -1.0922 -2.3114) (xy 1.0922 -2.3114) (xy 1.0922 2.3114) (xy -1.0922 2.3114)
			)
			(stroke
				(width 0)
				(type default)
			)
			(fill no)
			(layer "F.Fab")
		)
		(pad "1" smd rect
			(at 0 -1.397)
			(size 1.651 1.27)
			(layers "F.Cu" "F.Mask" "F.Paste")
			(net "P5V_HDD29")
		)
		(pad "2" smd rect
			(at 0 1.397)
			(size 1.651 1.27)
			(layers "F.Cu" "F.Mask" "F.Paste")
			(net "5V_PRE_29")
		)
	)
	(footprint ""
		(layer "F.Cu")
		(at 471.805 -138.049 90)
		(property "Reference" "R606"
			(at 0 0 90)
			(layer "F.SilkS")
			(hide yes)
			(effects
				(font
					(size 1.27 1.27)
				)
			)
		)
		(property "Value" "4K7R2J-2-GP"
			(at 0.064008 -3.993896 90)
			(unlocked yes)
			(layer "F.Fab")
			(hide yes)
			(effects
				(font
					(size 1.016 1.016)
					(thickness 0.1524)
				)
			)
		)
		(property "Device Type" "R402H16"
			(at 0.064008 -5.517896 90)
			(unlocked yes)
			(layer "F.Fab")
			(hide yes)
			(effects
				(font
					(size 1.016 1.016)
					(thickness 0.1524)
				)
			)
		)
		(duplicate_pad_numbers_are_jumpers no)
		(fp_line
			(start 0.508 -0.9398)
			(end -0.508 -0.9398)
			(stroke
				(width 0.1524)
				(type default)
			)
			(layer "F.SilkS")
		)
		(fp_line
			(start -0.508 -0.9398)
			(end -0.508 0.9398)
			(stroke
				(width 0.1524)
				(type default)
			)
			(layer "F.SilkS")
		)
		(fp_rect
			(start -0.508 0.9398)
			(end 0.508 -0.9398)
			(stroke
				(width 0)
				(type default)
			)
			(fill no)
			(layer "F.CrtYd")
		)
		(fp_rect
			(start -0.508 0.9398)
			(end 0.508 -0.9398)
			(stroke
				(width 0)
				(type default)
			)
			(fill no)
			(layer "F.Fab")
		)
		(pad "1" smd custom
			(at 0 -0.4445 90)
			(size 0.1397 0.1397)
			(layers "F.Cu" "F.Mask" "F.Paste")
			(net "P12V_B")
			(options
				(clearance outline)
				(anchor circle)
			)
			(primitives
				(gr_poly
					(pts
						(arc
							(start -0.1778 -0.2794)
							(mid -0.249642 -0.249642)
							(end -0.2794 -0.1778)
						)
						(arc
							(start -0.2794 0.1778)
							(mid -0.249642 0.249642)
							(end -0.1778 0.2794)
						)
						(arc
							(start 0.1778 0.2794)
							(mid 0.249642 0.249642)
							(end 0.2794 0.1778)
						)
						(arc
							(start 0.2794 -0.1778)
							(mid 0.249642 -0.249642)
							(end 0.1778 -0.2794)
						)
					)
					(width 0)
					(fill yes)
				)
			)
		)
		(pad "2" smd custom
			(at 0 0.4445 90)
			(size 0.1397 0.1397)
			(layers "F.Cu" "F.Mask" "F.Paste")
			(net "SW_HDD_P23")
			(options
				(clearance outline)
				(anchor circle)
			)
			(primitives
				(gr_poly
					(pts
						(arc
							(start -0.1778 -0.2794)
							(mid -0.249642 -0.249642)
							(end -0.2794 -0.1778)
						)
						(arc
							(start -0.2794 0.1778)
							(mid -0.249642 0.249642)
							(end -0.1778 0.2794)
						)
						(arc
							(start 0.1778 0.2794)
							(mid 0.249642 0.249642)
							(end 0.2794 0.1778)
						)
						(arc
							(start 0.2794 -0.1778)
							(mid 0.249642 -0.249642)
							(end 0.1778 -0.2794)
						)
					)
					(width 0)
					(fill yes)
				)
			)
		)
	)
	(footprint ""
		(layer "F.Cu")
		(at 191.219328 -370.844826)
		(property "Reference" "R1306"
			(at 0 0 0)
			(layer "F.SilkS")
			(hide yes)
			(effects
				(font
					(size 1.27 1.27)
				)
			)
		)
		(property "Value" "4K7R2F-GP"
			(at 0.064008 -3.993896 0)
			(unlocked yes)
			(layer "F.Fab")
			(hide yes)
			(effects
				(font
					(size 1.016 1.016)
					(thickness 0.1524)
				)
			)
		)
		(property "Device Type" "R402H16"
			(at 0.064008 -5.517896 0)
			(unlocked yes)
			(layer "F.Fab")
			(hide yes)
			(effects
				(font
					(size 1.016 1.016)
					(thickness 0.1524)
				)
			)
		)
		(duplicate_pad_numbers_are_jumpers no)
		(fp_line
			(start -0.508 -0.9398)
			(end -0.508 0.9398)
			(stroke
				(width 0.1524)
				(type default)
			)
			(layer "F.SilkS")
		)
		(fp_line
			(start 0.508 -0.9398)
			(end -0.508 -0.9398)
			(stroke
				(width 0.1524)
				(type default)
			)
			(layer "F.SilkS")
		)
		(fp_rect
			(start -0.508 0.9398)
			(end 0.508 -0.9398)
			(stroke
				(width 0)
				(type default)
			)
			(fill no)
			(layer "F.CrtYd")
		)
		(fp_rect
			(start -0.508 0.9398)
			(end 0.508 -0.9398)
			(stroke
				(width 0)
				(type default)
			)
			(fill no)
			(layer "F.Fab")
		)
		(pad "1" smd custom
			(at 0 -0.4445)
			(size 0.1397 0.1397)
			(layers "F.Cu" "F.Mask" "F.Paste")
			(net "FAN_YELLOW_LED1")
			(options
				(clearance outline)
				(anchor circle)
			)
			(primitives
				(gr_poly
					(pts
						(arc
							(start -0.1778 -0.2794)
							(mid -0.249642 -0.249642)
							(end -0.2794 -0.1778)
						)
						(arc
							(start -0.2794 0.1778)
							(mid -0.249642 0.249642)
							(end -0.1778 0.2794)
						)
						(arc
							(start 0.1778 0.2794)
							(mid 0.249642 0.249642)
							(end 0.2794 0.1778)
						)
						(arc
							(start 0.2794 -0.1778)
							(mid 0.249642 -0.249642)
							(end 0.1778 -0.2794)
						)
					)
					(width 0)
					(fill yes)
				)
			)
		)
		(pad "2" smd custom
			(at 0 0.4445)
			(size 0.1397 0.1397)
			(layers "F.Cu" "F.Mask" "F.Paste")
			(net "FAN_LED1_D2")
			(options
				(clearance outline)
				(anchor circle)
			)
			(primitives
				(gr_poly
					(pts
						(arc
							(start -0.1778 -0.2794)
							(mid -0.249642 -0.249642)
							(end -0.2794 -0.1778)
						)
						(arc
							(start -0.2794 0.1778)
							(mid -0.249642 0.249642)
							(end -0.1778 0.2794)
						)
						(arc
							(start 0.1778 0.2794)
							(mid 0.249642 0.249642)
							(end 0.2794 0.1778)
						)
						(arc
							(start 0.2794 -0.1778)
							(mid 0.249642 -0.249642)
							(end 0.1778 -0.2794)
						)
					)
					(width 0)
					(fill yes)
				)
			)
		)
	)
	(footprint ""
		(layer "F.Cu")
		(at 49.04486 -113.128806)
		(property "Reference" "R1120"
			(at 0 0 0)
			(layer "F.SilkS")
			(hide yes)
			(effects
				(font
					(size 1.27 1.27)
				)
			)
		)
		(property "Value" "0R3J-0-U-GP"
			(at -0.0254 -2.5146 0)
			(unlocked yes)
			(layer "F.Fab")
			(hide yes)
			(effects
				(font
					(size 1.016 1.016)
					(thickness 0.1524)
				)
			)
		)
		(property "Device Type" "R603H22"
			(at -0.0254 -4.0386 0)
			(unlocked yes)
			(layer "F.Fab")
			(hide yes)
			(effects
				(font
					(size 1.016 1.016)
					(thickness 0.1524)
				)
			)
		)
		(duplicate_pad_numbers_are_jumpers no)
		(fp_line
			(start -0.4826 0)
			(end -0.2032 0)
			(stroke
				(width 0.2032)
				(type default)
			)
			(layer "F.SilkS")
		)
		(fp_line
			(start 0.2032 0)
			(end 0.4826 0)
			(stroke
				(width 0.2032)
				(type default)
			)
			(layer "F.SilkS")
		)
		(fp_rect
			(start -0.5842 1.3335)
			(end 0.5842 -1.3335)
			(stroke
				(width 0)
				(type default)
			)
			(fill no)
			(layer "F.CrtYd")
		)
		(fp_rect
			(start -0.5842 1.3335)
			(end 0.5842 -1.3335)
			(stroke
				(width 0)
				(type default)
			)
			(fill no)
			(layer "F.Fab")
		)
		(pad "1" smd custom
			(at 0 -0.762)
			(size 0.2159 0.2159)
			(layers "F.Cu" "F.Mask" "F.Paste")
			(net "P5V_B_2_VBST")
			(options
				(clearance outline)
				(anchor circle)
			)
			(primitives
				(gr_poly
					(pts
						(arc
							(start -0.3302 -0.4318)
							(mid -0.402042 -0.402042)
							(end -0.4318 -0.3302)
						)
						(arc
							(start -0.4318 0.3302)
							(mid -0.402042 0.402042)
							(end -0.3302 0.4318)
						)
						(arc
							(start 0.3302 0.4318)
							(mid 0.402042 0.402042)
							(end 0.4318 0.3302)
						)
						(arc
							(start 0.4318 -0.3302)
							(mid 0.402042 -0.402042)
							(end 0.3302 -0.4318)
						)
					)
					(width 0)
					(fill yes)
				)
			)
		)
		(pad "2" smd custom
			(at 0 0.762)
			(size 0.2159 0.2159)
			(layers "F.Cu" "F.Mask" "F.Paste")
			(net "P5V_B_2_VBST_RC")
			(options
				(clearance outline)
				(anchor circle)
			)
			(primitives
				(gr_poly
					(pts
						(arc
							(start -0.3302 -0.4318)
							(mid -0.402042 -0.402042)
							(end -0.4318 -0.3302)
						)
						(arc
							(start -0.4318 0.3302)
							(mid -0.402042 0.402042)
							(end -0.3302 0.4318)
						)
						(arc
							(start 0.3302 0.4318)
							(mid 0.402042 0.402042)
							(end 0.4318 0.3302)
						)
						(arc
							(start 0.4318 -0.3302)
							(mid 0.402042 -0.402042)
							(end 0.3302 -0.4318)
						)
					)
					(width 0)
					(fill yes)
				)
			)
		)
	)
	(footprint ""
		(layer "F.Cu")
		(at 159.639 -371.602 180)
		(property "Reference" "R933"
			(at 0 0 180)
			(layer "F.SilkS")
			(hide yes)
			(effects
				(font
					(size 1.27 1.27)
				)
			)
		)
		(property "Value" "100KR2F-L1-GP"
			(at 0.064008 -3.993896 180)
			(unlocked yes)
			(layer "F.Fab")
			(hide yes)
			(effects
				(font
					(size 1.016 1.016)
					(thickness 0.1524)
				)
			)
		)
		(property "Device Type" "R402H16"
			(at 0.064008 -5.517896 180)
			(unlocked yes)
			(layer "F.Fab")
			(hide yes)
			(effects
				(font
					(size 1.016 1.016)
					(thickness 0.1524)
				)
			)
		)
		(duplicate_pad_numbers_are_jumpers no)
		(fp_line
			(start 0.508 -0.9398)
			(end -0.508 -0.9398)
			(stroke
				(width 0.1524)
				(type default)
			)
			(layer "F.SilkS")
		)
		(fp_line
			(start -0.508 -0.9398)
			(end -0.508 0.9398)
			(stroke
				(width 0.1524)
				(type default)
			)
			(layer "F.SilkS")
		)
		(fp_rect
			(start -0.508 0.9398)
			(end 0.508 -0.9398)
			(stroke
				(width 0)
				(type default)
			)
			(fill no)
			(layer "F.CrtYd")
		)
		(fp_rect
			(start -0.508 0.9398)
			(end 0.508 -0.9398)
			(stroke
				(width 0)
				(type default)
			)
			(fill no)
			(layer "F.Fab")
		)
		(pad "1" smd custom
			(at 0 -0.4445 180)
			(size 0.1397 0.1397)
			(layers "F.Cu" "F.Mask" "F.Paste")
			(net "P3V3_IN")
			(options
				(clearance outline)
				(anchor circle)
			)
			(primitives
				(gr_poly
					(pts
						(arc
							(start -0.1778 -0.2794)
							(mid -0.249642 -0.249642)
							(end -0.2794 -0.1778)
						)
						(arc
							(start -0.2794 0.1778)
							(mid -0.249642 0.249642)
							(end -0.1778 0.2794)
						)
						(arc
							(start 0.1778 0.2794)
							(mid 0.249642 0.249642)
							(end 0.2794 0.1778)
						)
						(arc
							(start 0.2794 -0.1778)
							(mid 0.249642 -0.249642)
							(end 0.1778 -0.2794)
						)
					)
					(width 0)
					(fill yes)
				)
			)
		)
		(pad "2" smd custom
			(at 0 0.4445 180)
			(size 0.1397 0.1397)
			(layers "F.Cu" "F.Mask" "F.Paste")
			(net "FAN_1_INS_N")
			(options
				(clearance outline)
				(anchor circle)
			)
			(primitives
				(gr_poly
					(pts
						(arc
							(start -0.1778 -0.2794)
							(mid -0.249642 -0.249642)
							(end -0.2794 -0.1778)
						)
						(arc
							(start -0.2794 0.1778)
							(mid -0.249642 0.249642)
							(end -0.1778 0.2794)
						)
						(arc
							(start 0.1778 0.2794)
							(mid 0.249642 0.249642)
							(end 0.2794 0.1778)
						)
						(arc
							(start 0.2794 -0.1778)
							(mid 0.249642 -0.249642)
							(end 0.1778 -0.2794)
						)
					)
					(width 0)
					(fill yes)
				)
			)
		)
	)
	(footprint ""
		(layer "F.Cu")
		(at 122.849894 -28.910026 -90)
		(property "Reference" "HDDSAS27"
			(at 0 0 270)
			(layer "F.SilkS")
			(hide yes)
			(effects
				(font
					(size 1.27 1.27)
				)
			)
		)
		(property "Value" "SKT-SAS15P-14P-45-GP"
			(at -20.7645 -8.9789 270)
			(unlocked yes)
			(layer "F.Fab")
			(hide yes)
			(effects
				(font
					(size 1.016 1.016)
					(thickness 0.1524)
				)
			)
		)
		(property "Device Type" "10120818-001C-TRLF"
			(at -20.7645 -10.5029 270)
			(unlocked yes)
			(layer "F.Fab")
			(hide yes)
			(effects
				(font
					(size 1.016 1.016)
					(thickness 0.1524)
				)
			)
		)
		(duplicate_pad_numbers_are_jumpers no)
		(fp_line
			(start 1.651 4.2926)
			(end 1.651 3.0099)
			(stroke
				(width 0.1524)
				(type default)
			)
			(layer "F.SilkS")
		)
		(fp_line
			(start 8.509 4.2926)
			(end 1.651 4.2926)
			(stroke
				(width 0.1524)
				(type default)
			)
			(layer "F.SilkS")
		)
		(fp_line
			(start -23.4188 3.0099)
			(end -23.4188 -3.2512)
			(stroke
				(width 0.1524)
				(type default)
			)
			(layer "F.SilkS")
		)
		(fp_line
			(start 1.651 3.0099)
			(end -23.4188 3.0099)
			(stroke
				(width 0.1524)
				(type default)
			)
			(layer "F.SilkS")
		)
		(fp_line
			(start 8.509 3.0099)
			(end 8.509 4.2926)
			(stroke
				(width 0.1524)
				(type default)
			)
			(layer "F.SilkS")
		)
		(fp_line
			(start 23.4188 3.0099)
			(end 8.509 3.0099)
			(stroke
				(width 0.1524)
				(type default)
			)
			(layer "F.SilkS")
		)
		(fp_line
			(start -23.4188 -3.2512)
			(end 23.4188 -3.2512)
			(stroke
				(width 0.1524)
				(type default)
			)
			(layer "F.SilkS")
		)
		(fp_line
			(start 23.4188 -3.2512)
			(end 23.4188 3.0099)
			(stroke
				(width 0.1524)
				(type default)
			)
			(layer "F.SilkS")
		)
		(fp_line
			(start 15.5067 -3.3401)
			(end 16.2687 -3.3401)
			(stroke
				(width 0.3302)
				(type default)
			)
			(layer "F.SilkS")
		)
		(fp_poly
			(pts
				(xy 15.868904 -3.230372) (xy 16.503904 -3.865372) (xy 15.233904 -3.865372)
			)
			(stroke
				(width 0)
				(type default)
			)
			(fill yes)
			(layer "F.SilkS")
		)
		(fp_poly
			(pts
				(xy -22.8727 -2.7559) (xy 22.8727 -2.7559) (xy 22.8727 2.7559) (xy 8.255 2.7559) (xy 8.255 3.5179)
				(xy 1.905 3.5179) (xy 1.905 2.7559) (xy -22.8727 2.7559)
			)
			(stroke
				(width 0)
				(type default)
			)
			(fill no)
			(layer "F.CrtYd")
		)
		(fp_poly
			(pts
				(xy 1.397 4.5466) (xy 1.397 3.2639) (xy -23.6728 3.2639) (xy -23.6728 -3.5052) (xy 23.6728 -3.5052)
				(xy 23.6728 -0.00635) (xy 22.8727 -0.00635) (xy 22.8727 -2.7559) (xy -22.8727 -2.7559) (xy -22.8727 2.7559)
				(xy 1.905 2.7559) (xy 1.905 3.5179) (xy 8.255 3.5179) (xy 8.255 2.7559) (xy 22.8727 2.7559) (xy 22.8727 0.00635)
				(xy 23.6728 0.00635) (xy 23.6728 3.2639) (xy 8.763 3.2639) (xy 8.763 4.5466)
			)
			(stroke
				(width 0)
				(type default)
			)
			(fill no)
			(layer "F.CrtYd")
		)
		(fp_poly
			(pts
				(xy 1.397 4.5466) (xy 1.397 3.2639) (xy -23.6728 3.2639) (xy -23.6728 -3.5052) (xy 23.6728 -3.5052)
				(xy 23.6728 3.2639) (xy 8.763 3.2639) (xy 8.763 4.5466)
			)
			(stroke
				(width 0)
				(type default)
			)
			(fill no)
			(layer "F.Fab")
		)
		(pad "" np_thru_hole circle
			(at -18.874994 0 270)
			(size 0.254 0.254)
			(drill 1.3462)
			(layers "*.Cu" "*.Mask")
			(clearance 0.9017)
			(thermal_gap 0.9017)
		)
		(pad "" np_thru_hole circle
			(at 18.874994 0 270)
			(size 0.254 0.254)
			(drill 0.9398)
			(layers "*.Cu" "*.Mask")
			(clearance 0.6985)
			(thermal_gap 0.6985)
		)
		(pad "G1" smd rect
			(at 21.874988 0 270)
			(size 2.5908 2.5908)
			(layers "F.Cu" "F.Mask" "F.Paste")
			(net "GND")
		)
		(pad "G2" smd rect
			(at -21.874988 0 270)
			(size 2.5908 2.5908)
			(layers "F.Cu" "F.Mask" "F.Paste")
			(net "GND")
		)
		(pad "P1" smd rect
			(at 1.905 -1.82499 270)
			(size 0.6096 2.3622)
			(layers "F.Cu" "F.Mask" "F.Paste")
			(net "Net_1664")
		)
		(pad "P2" smd rect
			(at 0.635 -1.82499 270)
			(size 0.6096 2.3622)
			(layers "F.Cu" "F.Mask" "F.Paste")
			(net "Net_1665")
		)
		(pad "P3" smd rect
			(at -0.635 -1.82499 270)
			(size 0.6096 2.3622)
			(layers "F.Cu" "F.Mask" "F.Paste")
			(net "Net_1666")
		)
		(pad "P4" smd rect
			(at -1.905 -1.82499 270)
			(size 0.6096 2.3622)
			(layers "F.Cu" "F.Mask" "F.Paste")
			(net "GND")
		)
		(pad "P5" smd rect
			(at -3.175 -1.82499 270)
			(size 0.6096 2.3622)
			(layers "F.Cu" "F.Mask" "F.Paste")
			(net "HDD_PRSNT_27")
		)
		(pad "P6" smd rect
			(at -4.445 -1.82499 270)
			(size 0.6096 2.3622)
			(layers "F.Cu" "F.Mask" "F.Paste")
			(net "GND")
		)
		(pad "P7" smd rect
			(at -5.715 -1.82499 270)
			(size 0.6096 2.3622)
			(layers "F.Cu" "F.Mask" "F.Paste")
			(net "5V_PRE_27")
		)
		(pad "P8" smd rect
			(at -6.985 -1.82499 270)
			(size 0.6096 2.3622)
			(layers "F.Cu" "F.Mask" "F.Paste")
			(net "P5V_HDD27")
		)
		(pad "P9" smd rect
			(at -8.255 -1.82499 270)
			(size 0.6096 2.3622)
			(layers "F.Cu" "F.Mask" "F.Paste")
			(net "P5V_HDD27")
		)
		(pad "P10" smd rect
			(at -9.525 -1.82499 270)
			(size 0.6096 2.3622)
			(layers "F.Cu" "F.Mask" "F.Paste")
			(net "GND")
		)
		(pad "P11" smd rect
			(at -10.795 -1.82499 270)
			(size 0.6096 2.3622)
			(layers "F.Cu" "F.Mask" "F.Paste")
			(net "ACT_HDD_27")
		)
		(pad "P12" smd rect
			(at -12.065 -1.82499 270)
			(size 0.6096 2.3622)
			(layers "F.Cu" "F.Mask" "F.Paste")
			(net "GND")
		)
		(pad "P13" smd rect
			(at -13.335 -1.82499 270)
			(size 0.6096 2.3622)
			(layers "F.Cu" "F.Mask" "F.Paste")
			(net "12V_PRE_27")
		)
		(pad "P14" smd rect
			(at -14.605 -1.82499 270)
			(size 0.6096 2.3622)
			(layers "F.Cu" "F.Mask" "F.Paste")
			(net "P12V_HDD27")
		)
		(pad "P15" smd rect
			(at -15.875 -1.82499 270)
			(size 0.6096 2.3622)
			(layers "F.Cu" "F.Mask" "F.Paste")
			(net "P12V_HDD27")
		)
		(pad "S1" smd rect
			(at 15.875 -1.82499 270)
			(size 0.6096 2.3622)
			(layers "F.Cu" "F.Mask" "F.Paste")
			(net "GND")
		)
		(pad "S2" smd rect
			(at 14.605 -1.82499 270)
			(size 0.6096 2.3622)
			(layers "F.Cu" "F.Mask" "F.Paste")
			(net "SAS_HDD_RX_P27")
		)
		(pad "S3" smd rect
			(at 13.335 -1.82499 270)
			(size 0.6096 2.3622)
			(layers "F.Cu" "F.Mask" "F.Paste")
			(net "SAS_HDD_RX_N27")
		)
		(pad "S4" smd rect
			(at 12.065 -1.82499 270)
			(size 0.6096 2.3622)
			(layers "F.Cu" "F.Mask" "F.Paste")
			(net "GND")
		)
		(pad "S5" smd rect
			(at 10.795 -1.82499 270)
			(size 0.6096 2.3622)
			(layers "F.Cu" "F.Mask" "F.Paste")
			(net "PHY_DRV_B_TO_SCC_B_27_DN")
		)
		(pad "S6" smd rect
			(at 9.525 -1.82499 270)
			(size 0.6096 2.3622)
			(layers "F.Cu" "F.Mask" "F.Paste")
			(net "PHY_DRV_B_TO_SCC_B_27_DP")
		)
		(pad "S7" smd rect
			(at 8.255 -1.82499 270)
			(size 0.6096 2.3622)
			(layers "F.Cu" "F.Mask" "F.Paste")
			(net "GND")
		)
		(pad "S8" smd rect
			(at 7.480046 2.845054 270)
			(size 0.508 2.3622)
			(layers "F.Cu" "F.Mask" "F.Paste")
			(net "GND")
		)
		(pad "S9" smd rect
			(at 6.679946 2.845054 270)
			(size 0.508 2.3622)
			(layers "F.Cu" "F.Mask" "F.Paste")
			(net "Net_451")
		)
		(pad "S10" smd rect
			(at 5.8801 2.845054 270)
			(size 0.508 2.3622)
			(layers "F.Cu" "F.Mask" "F.Paste")
			(net "Net_343")
		)
		(pad "S11" smd rect
			(at 5.08 2.845054 270)
			(size 0.508 2.3622)
			(layers "F.Cu" "F.Mask" "F.Paste")
			(net "GND")
		)
		(pad "S12" smd rect
			(at 4.2799 2.845054 270)
			(size 0.508 2.3622)
			(layers "F.Cu" "F.Mask" "F.Paste")
			(net "Net_379")
		)
		(pad "S13" smd rect
			(at 3.480054 2.845054 270)
			(size 0.508 2.3622)
			(layers "F.Cu" "F.Mask" "F.Paste")
			(net "Net_415")
		)
		(pad "S14" smd rect
			(at 2.679954 2.845054 270)
			(size 0.508 2.3622)
			(layers "F.Cu" "F.Mask" "F.Paste")
			(net "GND")
		)
		(zone
			(layer "F.Cu")
			(hatch none 0.5)
			(connect_pads
				(clearance 0)
			)
			(min_thickness 0.25)
			(keepout
				(tracks not_allowed)
				(vias allowed)
				(pads allowed)
				(copperpour not_allowed)
				(footprints allowed)
			)
			(placement
				(enabled no)
				(sheetname "")
			)
			(fill
				(thermal_gap 0.5)
				(thermal_bridge_width 0.5)
				(island_removal_mode 0)
			)
			(polygon
				(pts
					(xy 126.507494 -45.648626) (xy 119.433594 -45.648626) (xy 119.433594 -52.582826) (xy 120.538494 -52.582826)
					(xy 120.538494 -48.468026) (xy 125.161294 -48.468026) (xy 125.161294 -52.582826) (xy 126.507494 -52.582826)
				)
			)
		)
		(zone
			(layer "F.Cu")
			(hatch none 0.5)
			(connect_pads
				(clearance 0)
			)
			(min_thickness 0.25)
			(keepout
				(tracks allowed)
				(vias not_allowed)
				(pads allowed)
				(copperpour not_allowed)
				(footprints allowed)
			)
			(placement
				(enabled no)
				(sheetname "")
			)
			(fill
				(thermal_gap 0.5)
				(thermal_bridge_width 0.5)
				(island_removal_mode 0)
			)
			(polygon
				(pts
					(xy 126.507494 -45.648626) (xy 119.433594 -45.648626) (xy 119.433594 -52.582826) (xy 120.538494 -52.582826)
					(xy 120.538494 -48.468026) (xy 125.161294 -48.468026) (xy 125.161294 -52.582826) (xy 126.507494 -52.582826)
				)
			)
		)
		(zone
			(layer "F.Cu")
			(hatch none 0.5)
			(connect_pads
				(clearance 0)
			)
			(min_thickness 0.25)
			(keepout
				(tracks allowed)
				(vias not_allowed)
				(pads allowed)
				(copperpour not_allowed)
				(footprints allowed)
			)
			(placement
				(enabled no)
				(sheetname "")
			)
			(fill
				(thermal_gap 0.5)
				(thermal_bridge_width 0.5)
				(island_removal_mode 0)
			)
			(polygon
				(pts
					(xy 126.507494 -12.171426) (xy 119.433594 -12.171426) (xy 119.433594 -5.237226) (xy 120.538494 -5.237226)
					(xy 120.538494 -9.352026) (xy 125.161294 -9.352026) (xy 125.161294 -5.237226) (xy 126.507494 -5.237226)
				)
			)
		)
		(zone
			(layer "F.Cu")
			(hatch none 0.5)
			(connect_pads
				(clearance 0)
			)
			(min_thickness 0.25)
			(keepout
				(tracks not_allowed)
				(vias allowed)
				(pads allowed)
				(copperpour not_allowed)
				(footprints allowed)
			)
			(placement
				(enabled no)
				(sheetname "")
			)
			(fill
				(thermal_gap 0.5)
				(thermal_bridge_width 0.5)
				(island_removal_mode 0)
			)
			(polygon
				(pts
					(xy 126.507494 -12.171426) (xy 119.433594 -12.171426) (xy 119.433594 -5.237226) (xy 120.538494 -5.237226)
					(xy 120.538494 -9.352026) (xy 125.161294 -9.352026) (xy 125.161294 -5.237226) (xy 126.507494 -5.237226)
				)
			)
		)
		(zone
			(layers "F.Cu" "B.Cu" "In1.Cu" "In2.Cu" "In3.Cu" "In4.Cu" "In5.Cu" "In6.Cu")
			(hatch none 0.5)
			(connect_pads
				(clearance 0)
			)
			(min_thickness 0.25)
			(keepout
				(tracks not_allowed)
				(vias allowed)
				(pads allowed)
				(copperpour not_allowed)
				(footprints allowed)
			)
			(placement
				(enabled no)
				(sheetname "")
			)
			(fill
				(thermal_gap 0.5)
				(thermal_bridge_width 0.5)
				(island_removal_mode 0)
			)
			(polygon
				(pts
					(arc
						(start 123.624594 -10.035032)
						(mid 122.075194 -10.035032)
						(end 123.624594 -10.035032)
					)
				)
			)
		)
		(zone
			(layers "F.Cu" "B.Cu" "In1.Cu" "In2.Cu" "In3.Cu" "In4.Cu" "In5.Cu" "In6.Cu")
			(hatch none 0.5)
			(connect_pads
				(clearance 0)
			)
			(min_thickness 0.25)
			(keepout
				(tracks not_allowed)
				(vias allowed)
				(pads allowed)
				(copperpour not_allowed)
				(footprints allowed)
			)
			(placement
				(enabled no)
				(sheetname "")
			)
			(fill
				(thermal_gap 0.5)
				(thermal_bridge_width 0.5)
				(island_removal_mode 0)
			)
			(polygon
				(pts
					(arc
						(start 123.827794 -47.78502)
						(mid 121.871994 -47.78502)
						(end 123.827794 -47.78502)
					)
				)
			)
		)
	)
	(footprint ""
		(layer "F.Cu")
		(at 370.205 -28.829 90)
		(property "Reference" "C442"
			(at 0 0 90)
			(layer "F.SilkS")
			(hide yes)
			(effects
				(font
					(size 1.27 1.27)
				)
			)
		)
		(property "Value" "SCD033U25V2KX-GP"
			(at 1.1811 -2.7051 90)
			(unlocked yes)
			(layer "F.Fab")
			(hide yes)
			(effects
				(font
					(size 1.016 1.016)
					(thickness 0.1524)
				)
			)
		)
		(property "Device Type" "C402H22"
			(at 1.1811 -4.2291 90)
			(unlocked yes)
			(layer "F.Fab")
			(hide yes)
			(effects
				(font
					(size 1.016 1.016)
					(thickness 0.1524)
				)
			)
		)
		(duplicate_pad_numbers_are_jumpers no)
		(fp_rect
			(start -0.4318 0.9525)
			(end 0.4318 -0.9525)
			(stroke
				(width 0)
				(type default)
			)
			(fill no)
			(layer "F.CrtYd")
		)
		(fp_rect
			(start -0.4318 0.9525)
			(end 0.4318 -0.9525)
			(stroke
				(width 0)
				(type default)
			)
			(fill no)
			(layer "F.Fab")
		)
		(pad "1" smd custom
			(at 0 -0.4445 90)
			(size 0.1524 0.1524)
			(layers "F.Cu" "F.Mask" "F.Paste")
			(net "P12V_B")
			(options
				(clearance outline)
				(anchor circle)
			)
			(primitives
				(gr_poly
					(pts
						(arc
							(start 0.3048 -0.2032)
							(mid 0.275042 -0.275042)
							(end 0.2032 -0.3048)
						)
						(arc
							(start -0.2032 -0.3048)
							(mid -0.275042 -0.275042)
							(end -0.3048 -0.2032)
						)
						(arc
							(start -0.3048 0.2032)
							(mid -0.275042 0.275042)
							(end -0.2032 0.3048)
						)
						(arc
							(start 0.2032 0.3048)
							(mid 0.275042 0.275042)
							(end 0.3048 0.2032)
						)
					)
					(width 0)
					(fill yes)
				)
			)
		)
		(pad "2" smd custom
			(at 0 0.4445 90)
			(size 0.1524 0.1524)
			(layers "F.Cu" "F.Mask" "F.Paste")
			(net "SW_HDD_N31")
			(options
				(clearance outline)
				(anchor circle)
			)
			(primitives
				(gr_poly
					(pts
						(arc
							(start 0.3048 -0.2032)
							(mid 0.275042 -0.275042)
							(end 0.2032 -0.3048)
						)
						(arc
							(start -0.2032 -0.3048)
							(mid -0.275042 -0.275042)
							(end -0.3048 -0.2032)
						)
						(arc
							(start -0.3048 0.2032)
							(mid -0.275042 0.275042)
							(end -0.2032 0.3048)
						)
						(arc
							(start 0.2032 0.3048)
							(mid 0.275042 0.275042)
							(end 0.3048 0.2032)
						)
					)
					(width 0)
					(fill yes)
				)
			)
		)
	)
	(footprint ""
		(layer "F.Cu")
		(at 117.856 -19.177)
		(property "Reference" "R699"
			(at 0 0 0)
			(layer "F.SilkS")
			(hide yes)
			(effects
				(font
					(size 1.27 1.27)
				)
			)
		)
		(property "Value" "1KR2F-3-GP"
			(at 0.064008 -3.993896 0)
			(unlocked yes)
			(layer "F.Fab")
			(hide yes)
			(effects
				(font
					(size 1.016 1.016)
					(thickness 0.1524)
				)
			)
		)
		(property "Device Type" "R402H16"
			(at 0.064008 -5.517896 0)
			(unlocked yes)
			(layer "F.Fab")
			(hide yes)
			(effects
				(font
					(size 1.016 1.016)
					(thickness 0.1524)
				)
			)
		)
		(duplicate_pad_numbers_are_jumpers no)
		(fp_line
			(start -0.508 -0.9398)
			(end -0.508 0.9398)
			(stroke
				(width 0.1524)
				(type default)
			)
			(layer "F.SilkS")
		)
		(fp_line
			(start 0.508 -0.9398)
			(end -0.508 -0.9398)
			(stroke
				(width 0.1524)
				(type default)
			)
			(layer "F.SilkS")
		)
		(fp_rect
			(start -0.508 0.9398)
			(end 0.508 -0.9398)
			(stroke
				(width 0)
				(type default)
			)
			(fill no)
			(layer "F.CrtYd")
		)
		(fp_rect
			(start -0.508 0.9398)
			(end 0.508 -0.9398)
			(stroke
				(width 0)
				(type default)
			)
			(fill no)
			(layer "F.Fab")
		)
		(pad "1" smd custom
			(at 0 -0.4445)
			(size 0.1397 0.1397)
			(layers "F.Cu" "F.Mask" "F.Paste")
			(net "P3V3_STBY_B")
			(options
				(clearance outline)
				(anchor circle)
			)
			(primitives
				(gr_poly
					(pts
						(arc
							(start -0.1778 -0.2794)
							(mid -0.249642 -0.249642)
							(end -0.2794 -0.1778)
						)
						(arc
							(start -0.2794 0.1778)
							(mid -0.249642 0.249642)
							(end -0.1778 0.2794)
						)
						(arc
							(start 0.1778 0.2794)
							(mid 0.249642 0.249642)
							(end 0.2794 0.1778)
						)
						(arc
							(start 0.2794 -0.1778)
							(mid 0.249642 -0.249642)
							(end 0.1778 -0.2794)
						)
					)
					(width 0)
					(fill yes)
				)
			)
		)
		(pad "2" smd custom
			(at 0 0.4445)
			(size 0.1397 0.1397)
			(layers "F.Cu" "F.Mask" "F.Paste")
			(net "SW_PWR_R_HDD27")
			(options
				(clearance outline)
				(anchor circle)
			)
			(primitives
				(gr_poly
					(pts
						(arc
							(start -0.1778 -0.2794)
							(mid -0.249642 -0.249642)
							(end -0.2794 -0.1778)
						)
						(arc
							(start -0.2794 0.1778)
							(mid -0.249642 0.249642)
							(end -0.1778 0.2794)
						)
						(arc
							(start 0.1778 0.2794)
							(mid 0.249642 0.249642)
							(end 0.2794 0.1778)
						)
						(arc
							(start 0.2794 -0.1778)
							(mid 0.249642 -0.249642)
							(end 0.1778 -0.2794)
						)
					)
					(width 0)
					(fill yes)
				)
			)
		)
	)
	(footprint ""
		(layer "F.Cu")
		(at 426.974 -36.83 180)
		(property "Reference" "C460"
			(at 0 0 180)
			(layer "F.SilkS")
			(hide yes)
			(effects
				(font
					(size 1.27 1.27)
				)
			)
		)
		(property "Value" "SC10U16V6KX-2GP"
			(at -0.0762 -5.1308 180)
			(unlocked yes)
			(layer "F.Fab")
			(hide yes)
			(effects
				(font
					(size 1.016 1.016)
					(thickness 0.1524)
				)
			)
		)
		(property "Device Type" "C1206H71"
			(at -0.127 -6.6548 180)
			(unlocked yes)
			(layer "F.Fab")
			(hide yes)
			(effects
				(font
					(size 1.016 1.016)
					(thickness 0.1524)
				)
			)
		)
		(duplicate_pad_numbers_are_jumpers no)
		(fp_line
			(start 1.016 2.2352)
			(end -1.016 2.2352)
			(stroke
				(width 0.1524)
				(type default)
			)
			(layer "F.SilkS")
		)
		(fp_line
			(start 1.016 0.8382)
			(end 1.016 2.2352)
			(stroke
				(width 0.1524)
				(type default)
			)
			(layer "F.SilkS")
		)
		(fp_line
			(start 1.016 -2.2352)
			(end 1.016 -0.8382)
			(stroke
				(width 0.1524)
				(type default)
			)
			(layer "F.SilkS")
		)
		(fp_line
			(start -1.016 2.2352)
			(end -1.016 0.8382)
			(stroke
				(width 0.1524)
				(type default)
			)
			(layer "F.SilkS")
		)
		(fp_line
			(start -1.016 -0.8382)
			(end -1.016 -2.2352)
			(stroke
				(width 0.1524)
				(type default)
			)
			(layer "F.SilkS")
		)
		(fp_line
			(start -1.016 -2.2352)
			(end 1.016 -2.2352)
			(stroke
				(width 0.1524)
				(type default)
			)
			(layer "F.SilkS")
		)
		(fp_rect
			(start -1.0922 2.3114)
			(end 1.0922 -2.3114)
			(stroke
				(width 0)
				(type default)
			)
			(fill no)
			(layer "F.CrtYd")
		)
		(fp_poly
			(pts
				(xy 1.0922 -2.3114) (xy 1.0922 2.3114) (xy -1.0922 2.3114) (xy -1.0922 -2.3114)
			)
			(stroke
				(width 0)
				(type default)
			)
			(fill no)
			(layer "F.Fab")
		)
		(pad "1" smd rect
			(at 0 -1.397 180)
			(size 1.651 1.27)
			(layers "F.Cu" "F.Mask" "F.Paste")
			(net "P5V_HDD33")
		)
		(pad "2" smd rect
			(at 0 1.397 180)
			(size 1.651 1.27)
			(layers "F.Cu" "F.Mask" "F.Paste")
			(net "GND")
		)
	)
	(footprint ""
		(layer "F.Cu")
		(at 254.585978 -229.38105 90)
		(property "Reference" "R122"
			(at 0 0 90)
			(layer "F.SilkS")
			(hide yes)
			(effects
				(font
					(size 1.27 1.27)
				)
			)
		)
		(property "Value" "16K2R2F-GP"
			(at 0.064008 -3.993896 90)
			(unlocked yes)
			(layer "F.Fab")
			(hide yes)
			(effects
				(font
					(size 1.016 1.016)
					(thickness 0.1524)
				)
			)
		)
		(property "Device Type" "R402H16"
			(at 0.064008 -5.517896 90)
			(unlocked yes)
			(layer "F.Fab")
			(hide yes)
			(effects
				(font
					(size 1.016 1.016)
					(thickness 0.1524)
				)
			)
		)
		(duplicate_pad_numbers_are_jumpers no)
		(fp_line
			(start 0.508 -0.9398)
			(end -0.508 -0.9398)
			(stroke
				(width 0.1524)
				(type default)
			)
			(layer "F.SilkS")
		)
		(fp_line
			(start -0.508 -0.9398)
			(end -0.508 0.9398)
			(stroke
				(width 0.1524)
				(type default)
			)
			(layer "F.SilkS")
		)
		(fp_rect
			(start -0.508 0.9398)
			(end 0.508 -0.9398)
			(stroke
				(width 0)
				(type default)
			)
			(fill no)
			(layer "F.CrtYd")
		)
		(fp_rect
			(start -0.508 0.9398)
			(end 0.508 -0.9398)
			(stroke
				(width 0)
				(type default)
			)
			(fill no)
			(layer "F.Fab")
		)
		(pad "1" smd custom
			(at 0 -0.4445 90)
			(size 0.1397 0.1397)
			(layers "F.Cu" "F.Mask" "F.Paste")
			(net "P5V_B_1")
			(options
				(clearance outline)
				(anchor circle)
			)
			(primitives
				(gr_poly
					(pts
						(arc
							(start -0.1778 -0.2794)
							(mid -0.249642 -0.249642)
							(end -0.2794 -0.1778)
						)
						(arc
							(start -0.2794 0.1778)
							(mid -0.249642 0.249642)
							(end -0.1778 0.2794)
						)
						(arc
							(start 0.1778 0.2794)
							(mid 0.249642 0.249642)
							(end 0.2794 0.1778)
						)
						(arc
							(start 0.2794 -0.1778)
							(mid 0.249642 -0.249642)
							(end 0.1778 -0.2794)
						)
					)
					(width 0)
					(fill yes)
				)
			)
		)
		(pad "2" smd custom
			(at 0 0.4445 90)
			(size 0.1397 0.1397)
			(layers "F.Cu" "F.Mask" "F.Paste")
			(net "P5V_B_1_SENSE")
			(options
				(clearance outline)
				(anchor circle)
			)
			(primitives
				(gr_poly
					(pts
						(arc
							(start -0.1778 -0.2794)
							(mid -0.249642 -0.249642)
							(end -0.2794 -0.1778)
						)
						(arc
							(start -0.2794 0.1778)
							(mid -0.249642 0.249642)
							(end -0.1778 0.2794)
						)
						(arc
							(start 0.1778 0.2794)
							(mid 0.249642 0.249642)
							(end 0.2794 0.1778)
						)
						(arc
							(start 0.2794 -0.1778)
							(mid 0.249642 -0.249642)
							(end 0.1778 -0.2794)
						)
					)
					(width 0)
					(fill yes)
				)
			)
		)
	)
	(footprint ""
		(layer "F.Cu")
		(at 261.224522 -363.575346 90)
		(property "Reference" "R1033"
			(at 0 0 90)
			(layer "F.SilkS")
			(hide yes)
			(effects
				(font
					(size 1.27 1.27)
				)
			)
		)
		(property "Value" "0R0603-PAD-2-GP-U"
			(at 2.1209 -0.1397 90)
			(unlocked yes)
			(layer "F.Fab")
			(hide yes)
			(effects
				(font
					(size 1.016 1.016)
					(thickness 0.1524)
				)
			)
		)
		(property "Device Type" "0R0603-PAD-1-U"
			(at 2.1209 -1.6637 90)
			(unlocked yes)
			(layer "F.Fab")
			(hide yes)
			(effects
				(font
					(size 1.016 1.016)
					(thickness 0.1524)
				)
			)
		)
		(duplicate_pad_numbers_are_jumpers no)
		(fp_rect
			(start -0.5842 1.3335)
			(end 0.5842 -1.3335)
			(stroke
				(width 0)
				(type default)
			)
			(fill no)
			(layer "F.CrtYd")
		)
		(fp_rect
			(start -0.5842 1.3335)
			(end 0.5842 -1.3335)
			(stroke
				(width 0)
				(type default)
			)
			(fill no)
			(layer "F.Fab")
		)
		(pad "1" smd custom
			(at 0 -0.762 90)
			(size 0.2159 0.2159)
			(layers "F.Cu" "F.Mask" "F.Paste")
			(net "AGND_CURRENT_DPB")
			(options
				(clearance outline)
				(anchor circle)
			)
			(primitives
				(gr_poly
					(pts
						(arc
							(start -0.3302 -0.5842)
							(mid -0.402042 -0.554442)
							(end -0.4318 -0.4826)
						)
						(arc
							(start -0.4318 0.4826)
							(mid -0.402042 0.554442)
							(end -0.3302 0.5842)
						)
						(arc
							(start 0.3302 0.5842)
							(mid 0.402042 0.554442)
							(end 0.4318 0.4826)
						)
						(arc
							(start 0.4318 -0.4826)
							(mid 0.402042 -0.554442)
							(end 0.3302 -0.5842)
						)
					)
					(width 0)
					(fill yes)
				)
			)
		)
		(pad "2" smd custom
			(at 0 0.762 90)
			(size 0.2159 0.2159)
			(layers "F.Cu" "F.Mask" "F.Paste")
			(net "GND")
			(options
				(clearance outline)
				(anchor circle)
			)
			(primitives
				(gr_poly
					(pts
						(arc
							(start -0.4318 0.4826)
							(mid -0.402042 0.554442)
							(end -0.3302 0.5842)
						)
						(arc
							(start 0.3302 0.5842)
							(mid 0.402042 0.554442)
							(end 0.4318 0.4826)
						)
						(arc
							(start 0.4318 -0.4826)
							(mid 0.402042 -0.554442)
							(end 0.3302 -0.5842)
						)
						(arc
							(start -0.3302 -0.5842)
							(mid -0.402042 -0.554442)
							(end -0.4318 -0.4826)
						)
					)
					(width 0)
					(fill yes)
				)
			)
		)
	)
	(footprint ""
		(layer "F.Cu")
		(at 445.9859 -13.6271 180)
		(property "Reference" "VIA69"
			(at 0 0 180)
			(layer "F.SilkS")
			(hide yes)
			(effects
				(font
					(size 1.27 1.27)
				)
			)
		)
		(property "Value" "100OHM-8L-2D36MM-L18-GP"
			(at 3.8989 0.5715 180)
			(unlocked yes)
			(layer "F.Fab")
			(hide yes)
			(effects
				(font
					(size 1.016 1.016)
					(thickness 0.1524)
				)
			)
		)
		(property "Device Type" "VIA-PCIE-4P-414097"
			(at 3.8989 -0.9525 180)
			(unlocked yes)
			(layer "F.Fab")
			(hide yes)
			(effects
				(font
					(size 1.016 1.016)
					(thickness 0.1524)
				)
			)
		)
		(duplicate_pad_numbers_are_jumpers no)
		(fp_rect
			(start -2.0701 0.4826)
			(end 2.0701 -0.4826)
			(stroke
				(width 0)
				(type default)
			)
			(fill no)
			(layer "F.CrtYd")
		)
		(fp_rect
			(start -2.0701 0.4826)
			(end 2.0701 -0.4826)
			(stroke
				(width 0)
				(type default)
			)
			(fill no)
			(layer "F.Fab")
		)
		(pad "1" thru_hole circle
			(at -1.5875 0 180)
			(size 0.508 0.508)
			(drill 0.254)
			(layers "*.Cu" "*.Mask")
			(remove_unused_layers no)
			(net "GND")
			(clearance 0.2286)
			(thermal_gap 0.2286)
		)
		(pad "2" thru_hole circle
			(at -0.5715 0 180)
			(size 0.508 0.508)
			(drill 0.254)
			(layers "*.Cu" "*.Mask")
			(remove_unused_layers no)
			(net "PHY_SCC_B_TO_DRV_B_34_DP")
			(clearance 0.2286)
			(thermal_gap 0.2286)
		)
		(pad "3" thru_hole circle
			(at 0.5715 0 180)
			(size 0.508 0.508)
			(drill 0.254)
			(layers "*.Cu" "*.Mask")
			(remove_unused_layers no)
			(net "PHY_SCC_B_TO_DRV_B_34_DN")
			(clearance 0.2286)
			(thermal_gap 0.2286)
		)
		(pad "4" thru_hole circle
			(at 1.5875 0 180)
			(size 0.508 0.508)
			(drill 0.254)
			(layers "*.Cu" "*.Mask")
			(remove_unused_layers no)
			(net "GND")
			(clearance 0.2286)
			(thermal_gap 0.2286)
		)
	)
	(footprint ""
		(layer "F.Cu")
		(at 77.978 -254.508 -90)
		(property "Reference" "R201"
			(at 0 0 270)
			(layer "F.SilkS")
			(hide yes)
			(effects
				(font
					(size 1.27 1.27)
				)
			)
		)
		(property "Value" "300KR2F-GP"
			(at 0.064008 -3.993896 270)
			(unlocked yes)
			(layer "F.Fab")
			(hide yes)
			(effects
				(font
					(size 1.016 1.016)
					(thickness 0.1524)
				)
			)
		)
		(property "Device Type" "R402H16"
			(at 0.064008 -5.517896 270)
			(unlocked yes)
			(layer "F.Fab")
			(hide yes)
			(effects
				(font
					(size 1.016 1.016)
					(thickness 0.1524)
				)
			)
		)
		(duplicate_pad_numbers_are_jumpers no)
		(fp_line
			(start -0.508 -0.9398)
			(end -0.508 0.9398)
			(stroke
				(width 0.1524)
				(type default)
			)
			(layer "F.SilkS")
		)
		(fp_line
			(start 0.508 -0.9398)
			(end -0.508 -0.9398)
			(stroke
				(width 0.1524)
				(type default)
			)
			(layer "F.SilkS")
		)
		(fp_rect
			(start -0.508 0.9398)
			(end 0.508 -0.9398)
			(stroke
				(width 0)
				(type default)
			)
			(fill no)
			(layer "F.CrtYd")
		)
		(fp_rect
			(start -0.508 0.9398)
			(end 0.508 -0.9398)
			(stroke
				(width 0)
				(type default)
			)
			(fill no)
			(layer "F.Fab")
		)
		(pad "1" smd custom
			(at 0 -0.4445 270)
			(size 0.1397 0.1397)
			(layers "F.Cu" "F.Mask" "F.Paste")
			(net "SW_HDD_N2")
			(options
				(clearance outline)
				(anchor circle)
			)
			(primitives
				(gr_poly
					(pts
						(arc
							(start -0.1778 -0.2794)
							(mid -0.249642 -0.249642)
							(end -0.2794 -0.1778)
						)
						(arc
							(start -0.2794 0.1778)
							(mid -0.249642 0.249642)
							(end -0.1778 0.2794)
						)
						(arc
							(start 0.1778 0.2794)
							(mid 0.249642 0.249642)
							(end 0.2794 0.1778)
						)
						(arc
							(start 0.2794 -0.1778)
							(mid 0.249642 -0.249642)
							(end 0.1778 -0.2794)
						)
					)
					(width 0)
					(fill yes)
				)
			)
		)
		(pad "2" smd custom
			(at 0 0.4445 270)
			(size 0.1397 0.1397)
			(layers "F.Cu" "F.Mask" "F.Paste")
			(net "P12V_B")
			(options
				(clearance outline)
				(anchor circle)
			)
			(primitives
				(gr_poly
					(pts
						(arc
							(start -0.1778 -0.2794)
							(mid -0.249642 -0.249642)
							(end -0.2794 -0.1778)
						)
						(arc
							(start -0.2794 0.1778)
							(mid -0.249642 0.249642)
							(end -0.1778 0.2794)
						)
						(arc
							(start 0.1778 0.2794)
							(mid 0.249642 0.249642)
							(end 0.2794 0.1778)
						)
						(arc
							(start 0.2794 -0.1778)
							(mid 0.249642 -0.249642)
							(end 0.1778 -0.2794)
						)
					)
					(width 0)
					(fill yes)
				)
			)
		)
	)
	(footprint ""
		(layer "F.Cu")
		(at 180.848 -366.649 90)
		(property "Reference" "R993"
			(at 0 0 90)
			(layer "F.SilkS")
			(hide yes)
			(effects
				(font
					(size 1.27 1.27)
				)
			)
		)
		(property "Value" "0R2J-2-GP"
			(at 0.064008 -3.993896 90)
			(unlocked yes)
			(layer "F.Fab")
			(hide yes)
			(effects
				(font
					(size 1.016 1.016)
					(thickness 0.1524)
				)
			)
		)
		(property "Device Type" "R402H16"
			(at 0.064008 -5.517896 90)
			(unlocked yes)
			(layer "F.Fab")
			(hide yes)
			(effects
				(font
					(size 1.016 1.016)
					(thickness 0.1524)
				)
			)
		)
		(duplicate_pad_numbers_are_jumpers no)
		(fp_line
			(start 0.508 -0.9398)
			(end -0.508 -0.9398)
			(stroke
				(width 0.1524)
				(type default)
			)
			(layer "F.SilkS")
		)
		(fp_line
			(start -0.508 -0.9398)
			(end -0.508 0.9398)
			(stroke
				(width 0.1524)
				(type default)
			)
			(layer "F.SilkS")
		)
		(fp_rect
			(start -0.508 0.9398)
			(end 0.508 -0.9398)
			(stroke
				(width 0)
				(type default)
			)
			(fill no)
			(layer "F.CrtYd")
		)
		(fp_rect
			(start -0.508 0.9398)
			(end 0.508 -0.9398)
			(stroke
				(width 0)
				(type default)
			)
			(fill no)
			(layer "F.Fab")
		)
		(pad "1" smd custom
			(at 0 -0.4445 90)
			(size 0.1397 0.1397)
			(layers "F.Cu" "F.Mask" "F.Paste")
			(net "MB0_SPISS_PD")
			(options
				(clearance outline)
				(anchor circle)
			)
			(primitives
				(gr_poly
					(pts
						(arc
							(start -0.1778 -0.2794)
							(mid -0.249642 -0.249642)
							(end -0.2794 -0.1778)
						)
						(arc
							(start -0.2794 0.1778)
							(mid -0.249642 0.249642)
							(end -0.1778 0.2794)
						)
						(arc
							(start 0.1778 0.2794)
							(mid 0.249642 0.249642)
							(end 0.2794 0.1778)
						)
						(arc
							(start 0.2794 -0.1778)
							(mid 0.249642 -0.249642)
							(end 0.1778 -0.2794)
						)
					)
					(width 0)
					(fill yes)
				)
			)
		)
		(pad "2" smd custom
			(at 0 0.4445 90)
			(size 0.1397 0.1397)
			(layers "F.Cu" "F.Mask" "F.Paste")
			(net "AGND_CURRENT_MON")
			(options
				(clearance outline)
				(anchor circle)
			)
			(primitives
				(gr_poly
					(pts
						(arc
							(start -0.1778 -0.2794)
							(mid -0.249642 -0.249642)
							(end -0.2794 -0.1778)
						)
						(arc
							(start -0.2794 0.1778)
							(mid -0.249642 0.249642)
							(end -0.1778 0.2794)
						)
						(arc
							(start 0.1778 0.2794)
							(mid 0.249642 0.249642)
							(end 0.2794 0.1778)
						)
						(arc
							(start 0.2794 -0.1778)
							(mid 0.249642 -0.249642)
							(end 0.1778 -0.2794)
						)
					)
					(width 0)
					(fill yes)
				)
			)
		)
	)
	(footprint ""
		(layer "F.Cu")
		(at 367.284 -128.651 180)
		(property "Reference" "R517"
			(at 0 0 180)
			(layer "F.SilkS")
			(hide yes)
			(effects
				(font
					(size 1.27 1.27)
				)
			)
		)
		(property "Value" "0R2J-2-GP"
			(at 0.064008 -3.993896 180)
			(unlocked yes)
			(layer "F.Fab")
			(hide yes)
			(effects
				(font
					(size 1.016 1.016)
					(thickness 0.1524)
				)
			)
		)
		(property "Device Type" "R402H16"
			(at 0.064008 -5.517896 180)
			(unlocked yes)
			(layer "F.Fab")
			(hide yes)
			(effects
				(font
					(size 1.016 1.016)
					(thickness 0.1524)
				)
			)
		)
		(duplicate_pad_numbers_are_jumpers no)
		(fp_line
			(start 0.508 -0.9398)
			(end -0.508 -0.9398)
			(stroke
				(width 0.1524)
				(type default)
			)
			(layer "F.SilkS")
		)
		(fp_line
			(start -0.508 -0.9398)
			(end -0.508 0.9398)
			(stroke
				(width 0.1524)
				(type default)
			)
			(layer "F.SilkS")
		)
		(fp_rect
			(start -0.508 0.9398)
			(end 0.508 -0.9398)
			(stroke
				(width 0)
				(type default)
			)
			(fill no)
			(layer "F.CrtYd")
		)
		(fp_rect
			(start -0.508 0.9398)
			(end 0.508 -0.9398)
			(stroke
				(width 0)
				(type default)
			)
			(fill no)
			(layer "F.Fab")
		)
		(pad "1" smd custom
			(at 0 -0.4445 180)
			(size 0.1397 0.1397)
			(layers "F.Cu" "F.Mask" "F.Paste")
			(net "DRIVE_B_19_PWR")
			(options
				(clearance outline)
				(anchor circle)
			)
			(primitives
				(gr_poly
					(pts
						(arc
							(start -0.1778 -0.2794)
							(mid -0.249642 -0.249642)
							(end -0.2794 -0.1778)
						)
						(arc
							(start -0.2794 0.1778)
							(mid -0.249642 0.249642)
							(end -0.1778 0.2794)
						)
						(arc
							(start 0.1778 0.2794)
							(mid 0.249642 0.249642)
							(end 0.2794 0.1778)
						)
						(arc
							(start 0.2794 -0.1778)
							(mid 0.249642 -0.249642)
							(end 0.1778 -0.2794)
						)
					)
					(width 0)
					(fill yes)
				)
			)
		)
		(pad "2" smd custom
			(at 0 0.4445 180)
			(size 0.1397 0.1397)
			(layers "F.Cu" "F.Mask" "F.Paste")
			(net "SW_PWR_R_HDD19")
			(options
				(clearance outline)
				(anchor circle)
			)
			(primitives
				(gr_poly
					(pts
						(arc
							(start -0.1778 -0.2794)
							(mid -0.249642 -0.249642)
							(end -0.2794 -0.1778)
						)
						(arc
							(start -0.2794 0.1778)
							(mid -0.249642 0.249642)
							(end -0.1778 0.2794)
						)
						(arc
							(start 0.1778 0.2794)
							(mid 0.249642 0.249642)
							(end 0.2794 0.1778)
						)
						(arc
							(start 0.2794 -0.1778)
							(mid 0.249642 -0.249642)
							(end 0.1778 -0.2794)
						)
					)
					(width 0)
					(fill yes)
				)
			)
		)
	)
	(footprint ""
		(layer "F.Cu")
		(at 475.742 -141.224 180)
		(property "Reference" "Q111"
			(at 0 0 180)
			(layer "F.SilkS")
			(hide yes)
			(effects
				(font
					(size 1.27 1.27)
				)
			)
		)
		(property "Value" "AO4406AL-GP"
			(at -3.707384 -1.5367 180)
			(unlocked yes)
			(layer "F.Fab")
			(hide yes)
			(effects
				(font
					(size 1.016 1.016)
					(thickness 0.1524)
				)
			)
		)
		(property "Device Type" "SOIC8H69"
			(at -3.707384 -3.0607 180)
			(unlocked yes)
			(layer "F.Fab")
			(hide yes)
			(effects
				(font
					(size 1.016 1.016)
					(thickness 0.1524)
				)
			)
		)
		(duplicate_pad_numbers_are_jumpers no)
		(fp_line
			(start 2.1336 1.4224)
			(end 2.1336 -1.4224)
			(stroke
				(width 0.1524)
				(type default)
			)
			(layer "F.SilkS")
		)
		(fp_line
			(start 2.1336 -1.4224)
			(end -2.7432 -1.4224)
			(stroke
				(width 0.1524)
				(type default)
			)
			(layer "F.SilkS")
		)
		(fp_line
			(start -2.1844 -0.0508)
			(end -2.7178 0.508)
			(stroke
				(width 0.1524)
				(type default)
			)
			(layer "F.SilkS")
		)
		(fp_line
			(start -2.6289 3.4417)
			(end -2.6289 1.4732)
			(stroke
				(width 0.381)
				(type default)
			)
			(layer "F.SilkS")
		)
		(fp_line
			(start -2.7178 -0.508)
			(end -2.1844 -0.0508)
			(stroke
				(width 0.1524)
				(type default)
			)
			(layer "F.SilkS")
		)
		(fp_line
			(start -2.7432 1.4224)
			(end 2.1336 1.4224)
			(stroke
				(width 0.1524)
				(type default)
			)
			(layer "F.SilkS")
		)
		(fp_line
			(start -2.7432 1.4224)
			(end -2.6416 1.4224)
			(stroke
				(width 0.1524)
				(type default)
			)
			(layer "F.SilkS")
		)
		(fp_line
			(start -2.7432 -1.4224)
			(end -2.7432 1.4224)
			(stroke
				(width 0.1524)
				(type default)
			)
			(layer "F.SilkS")
		)
		(fp_poly
			(pts
				(xy -2.2098 -1.4224) (xy -2.2098 1.4224) (xy 2.2098 1.4224) (xy 2.2098 -1.4224)
			)
			(stroke
				(width 0)
				(type default)
			)
			(fill yes)
			(layer "F.SilkS")
		)
		(fp_rect
			(start -2.450084 2.999994)
			(end 2.450084 -2.999994)
			(stroke
				(width 0)
				(type default)
			)
			(fill no)
			(layer "F.CrtYd")
		)
		(fp_poly
			(pts
				(xy -2.8194 3.6322) (xy -2.8194 -3.6322) (xy 2.8194 -3.6322) (xy 2.8194 1.18364) (xy 2.450084 1.18364)
				(xy 2.450084 -2.999994) (xy -2.450084 -2.999994) (xy -2.450084 2.999994) (xy 2.450084 2.999994)
				(xy 2.450084 1.18618) (xy 2.8194 1.18618) (xy 2.8194 3.6322)
			)
			(stroke
				(width 0)
				(type default)
			)
			(fill no)
			(layer "F.CrtYd")
		)
		(fp_rect
			(start -2.8194 3.6322)
			(end 2.8194 -3.6322)
			(stroke
				(width 0)
				(type default)
			)
			(fill no)
			(layer "F.Fab")
		)
		(pad "1" smd rect
			(at -1.905 2.54 180)
			(size 0.635 1.651)
			(layers "F.Cu" "F.Mask" "F.Paste")
			(net "P5V_HDD23")
		)
		(pad "2" smd rect
			(at -0.635 2.54 180)
			(size 0.635 1.651)
			(layers "F.Cu" "F.Mask" "F.Paste")
			(net "P5V_HDD23")
		)
		(pad "3" smd rect
			(at 0.635 2.54 180)
			(size 0.635 1.651)
			(layers "F.Cu" "F.Mask" "F.Paste")
			(net "P5V_HDD23")
		)
		(pad "4" smd rect
			(at 1.905 2.54 180)
			(size 0.635 1.651)
			(layers "F.Cu" "F.Mask" "F.Paste")
			(net "SW_HDD_P23")
		)
		(pad "5" smd rect
			(at 1.905 -2.54 180)
			(size 0.635 1.651)
			(layers "F.Cu" "F.Mask" "F.Paste")
			(net "P5V_B_4")
		)
		(pad "6" smd rect
			(at 0.635 -2.54 180)
			(size 0.635 1.651)
			(layers "F.Cu" "F.Mask" "F.Paste")
			(net "P5V_B_4")
		)
		(pad "7" smd rect
			(at -0.635 -2.54 180)
			(size 0.635 1.651)
			(layers "F.Cu" "F.Mask" "F.Paste")
			(net "P5V_B_4")
		)
		(pad "8" smd rect
			(at -1.905 -2.54 180)
			(size 0.635 1.651)
			(layers "F.Cu" "F.Mask" "F.Paste")
			(net "P5V_B_4")
		)
	)
	(footprint ""
		(layer "F.Cu")
		(at 46.736 -133.096 180)
		(property "Reference" "R385"
			(at 0 0 180)
			(layer "F.SilkS")
			(hide yes)
			(effects
				(font
					(size 1.27 1.27)
				)
			)
		)
		(property "Value" "200KR2F-L-GP"
			(at 0.064008 -3.993896 180)
			(unlocked yes)
			(layer "F.Fab")
			(hide yes)
			(effects
				(font
					(size 1.016 1.016)
					(thickness 0.1524)
				)
			)
		)
		(property "Device Type" "R402H16"
			(at 0.064008 -5.517896 180)
			(unlocked yes)
			(layer "F.Fab")
			(hide yes)
			(effects
				(font
					(size 1.016 1.016)
					(thickness 0.1524)
				)
			)
		)
		(duplicate_pad_numbers_are_jumpers no)
		(fp_line
			(start 0.508 -0.9398)
			(end -0.508 -0.9398)
			(stroke
				(width 0.1524)
				(type default)
			)
			(layer "F.SilkS")
		)
		(fp_line
			(start -0.508 -0.9398)
			(end -0.508 0.9398)
			(stroke
				(width 0.1524)
				(type default)
			)
			(layer "F.SilkS")
		)
		(fp_rect
			(start -0.508 0.9398)
			(end 0.508 -0.9398)
			(stroke
				(width 0)
				(type default)
			)
			(fill no)
			(layer "F.CrtYd")
		)
		(fp_rect
			(start -0.508 0.9398)
			(end 0.508 -0.9398)
			(stroke
				(width 0)
				(type default)
			)
			(fill no)
			(layer "F.Fab")
		)
		(pad "1" smd custom
			(at 0 -0.4445 180)
			(size 0.1397 0.1397)
			(layers "F.Cu" "F.Mask" "F.Paste")
			(net "SW_HDD_R13")
			(options
				(clearance outline)
				(anchor circle)
			)
			(primitives
				(gr_poly
					(pts
						(arc
							(start -0.1778 -0.2794)
							(mid -0.249642 -0.249642)
							(end -0.2794 -0.1778)
						)
						(arc
							(start -0.2794 0.1778)
							(mid -0.249642 0.249642)
							(end -0.1778 0.2794)
						)
						(arc
							(start 0.1778 0.2794)
							(mid 0.249642 0.249642)
							(end 0.2794 0.1778)
						)
						(arc
							(start 0.2794 -0.1778)
							(mid 0.249642 -0.249642)
							(end 0.1778 -0.2794)
						)
					)
					(width 0)
					(fill yes)
				)
			)
		)
		(pad "2" smd custom
			(at 0 0.4445 180)
			(size 0.1397 0.1397)
			(layers "F.Cu" "F.Mask" "F.Paste")
			(net "SW_HDD_N13")
			(options
				(clearance outline)
				(anchor circle)
			)
			(primitives
				(gr_poly
					(pts
						(arc
							(start -0.1778 -0.2794)
							(mid -0.249642 -0.249642)
							(end -0.2794 -0.1778)
						)
						(arc
							(start -0.2794 0.1778)
							(mid -0.249642 0.249642)
							(end -0.1778 0.2794)
						)
						(arc
							(start 0.1778 0.2794)
							(mid 0.249642 0.249642)
							(end 0.2794 0.1778)
						)
						(arc
							(start 0.2794 -0.1778)
							(mid 0.249642 -0.249642)
							(end 0.1778 -0.2794)
						)
					)
					(width 0)
					(fill yes)
				)
			)
		)
	)
	(footprint ""
		(layer "F.Cu")
		(at 168.9354 -99.7204 180)
		(property "Reference" "Q236"
			(at 0 0 180)
			(layer "F.SilkS")
			(hide yes)
			(effects
				(font
					(size 1.27 1.27)
				)
			)
		)
		(property "Value" "2N7002K-2-GP"
			(at 0.127 -8.9662 180)
			(unlocked yes)
			(layer "F.Fab")
			(hide yes)
			(effects
				(font
					(size 1.016 1.016)
					(thickness 0.1524)
				)
			)
		)
		(property "Device Type" "SOT23DGS2D4H44"
			(at 0.127 -10.4902 180)
			(unlocked yes)
			(layer "F.Fab")
			(hide yes)
			(effects
				(font
					(size 1.016 1.016)
					(thickness 0.1524)
				)
			)
		)
		(duplicate_pad_numbers_are_jumpers no)
		(fp_line
			(start 1.651 1.778)
			(end 1.651 -1.778)
			(stroke
				(width 0.1524)
				(type default)
			)
			(layer "F.SilkS")
		)
		(fp_line
			(start 1.651 -1.778)
			(end -1.651 -1.778)
			(stroke
				(width 0.1524)
				(type default)
			)
			(layer "F.SilkS")
		)
		(fp_line
			(start -1.651 1.778)
			(end 1.651 1.778)
			(stroke
				(width 0.1524)
				(type default)
			)
			(layer "F.SilkS")
		)
		(fp_line
			(start -1.651 -1.778)
			(end -1.651 1.778)
			(stroke
				(width 0.1524)
				(type default)
			)
			(layer "F.SilkS")
		)
		(fp_poly
			(pts
				(xy -1.778 1.8796) (xy -1.778 -1.8796) (xy 1.778 -1.8796) (xy 1.778 1.8796)
			)
			(stroke
				(width 0)
				(type default)
			)
			(fill no)
			(layer "F.CrtYd")
		)
		(fp_poly
			(pts
				(xy -1.778 1.8796) (xy -1.778 -1.8796) (xy 1.778 -1.8796) (xy 1.778 1.8796)
			)
			(stroke
				(width 0)
				(type default)
			)
			(fill no)
			(layer "F.Fab")
		)
		(pad "D" smd custom
			(at 0 -0.9525 180)
			(size 0.1905 0.1905)
			(layers "F.Cu" "F.Mask" "F.Paste")
			(net "FLT_HDD17_N")
			(options
				(clearance outline)
				(anchor circle)
			)
			(primitives
				(gr_poly
					(pts
						(arc
							(start -0.1778 0.5715)
							(mid -0.321484 0.511984)
							(end -0.381 0.3683)
						)
						(arc
							(start -0.381 -0.3683)
							(mid -0.321484 -0.511984)
							(end -0.1778 -0.5715)
						)
						(arc
							(start 0.1778 -0.5715)
							(mid 0.321484 -0.511984)
							(end 0.381 -0.3683)
						)
						(arc
							(start 0.381 0.3683)
							(mid 0.321484 0.511984)
							(end 0.1778 0.5715)
						)
					)
					(width 0)
					(fill yes)
				)
			)
		)
		(pad "G" smd custom
			(at -0.98425 0.9525 180)
			(size 0.1905 0.1905)
			(layers "F.Cu" "F.Mask" "F.Paste")
			(net "DRIVE_B_17_FLT_LED")
			(options
				(clearance outline)
				(anchor circle)
			)
			(primitives
				(gr_poly
					(pts
						(arc
							(start -0.1778 0.5715)
							(mid -0.321484 0.511984)
							(end -0.381 0.3683)
						)
						(arc
							(start -0.381 -0.3683)
							(mid -0.321484 -0.511984)
							(end -0.1778 -0.5715)
						)
						(arc
							(start 0.1778 -0.5715)
							(mid 0.321484 -0.511984)
							(end 0.381 -0.3683)
						)
						(arc
							(start 0.381 0.3683)
							(mid 0.321484 0.511984)
							(end 0.1778 0.5715)
						)
					)
					(width 0)
					(fill yes)
				)
			)
		)
		(pad "S" smd custom
			(at 0.98425 0.9525 180)
			(size 0.1905 0.1905)
			(layers "F.Cu" "F.Mask" "F.Paste")
			(net "GND")
			(options
				(clearance outline)
				(anchor circle)
			)
			(primitives
				(gr_poly
					(pts
						(arc
							(start -0.1778 0.5715)
							(mid -0.321484 0.511984)
							(end -0.381 0.3683)
						)
						(arc
							(start -0.381 -0.3683)
							(mid -0.321484 -0.511984)
							(end -0.1778 -0.5715)
						)
						(arc
							(start 0.1778 -0.5715)
							(mid 0.321484 -0.511984)
							(end 0.381 -0.3683)
						)
						(arc
							(start 0.381 0.3683)
							(mid 0.321484 0.511984)
							(end 0.1778 0.5715)
						)
					)
					(width 0)
					(fill yes)
				)
			)
		)
	)
	(footprint ""
		(layer "F.Cu")
		(at 308.110382 -332.979776 180)
		(property "Reference" "C38"
			(at 0 0 180)
			(layer "F.SilkS")
			(hide yes)
			(effects
				(font
					(size 1.27 1.27)
				)
			)
		)
		(property "Value" "SC1U16V3KX-5GP"
			(at 0 -2.8194 180)
			(unlocked yes)
			(layer "F.Fab")
			(hide yes)
			(effects
				(font
					(size 1.016 1.016)
					(thickness 0.1524)
				)
			)
		)
		(property "Device Type" "C603H36"
			(at 0 -4.3434 180)
			(unlocked yes)
			(layer "F.Fab")
			(hide yes)
			(effects
				(font
					(size 1.016 1.016)
					(thickness 0.1524)
				)
			)
		)
		(duplicate_pad_numbers_are_jumpers no)
		(fp_line
			(start 0.508 0)
			(end -0.508 0)
			(stroke
				(width 0.2032)
				(type default)
			)
			(layer "F.SilkS")
		)
		(fp_rect
			(start -0.5842 1.3335)
			(end 0.5842 -1.3335)
			(stroke
				(width 0)
				(type default)
			)
			(fill no)
			(layer "F.CrtYd")
		)
		(fp_rect
			(start -0.5842 1.3335)
			(end 0.5842 -1.3335)
			(stroke
				(width 0)
				(type default)
			)
			(fill no)
			(layer "F.Fab")
		)
		(pad "1" smd custom
			(at 0 -0.762 180)
			(size 0.2159 0.2159)
			(layers "F.Cu" "F.Mask" "F.Paste")
			(net "P3V3_IN")
			(options
				(clearance outline)
				(anchor circle)
			)
			(primitives
				(gr_poly
					(pts
						(arc
							(start -0.3302 -0.4318)
							(mid -0.402042 -0.402042)
							(end -0.4318 -0.3302)
						)
						(arc
							(start -0.4318 0.3302)
							(mid -0.402042 0.402042)
							(end -0.3302 0.4318)
						)
						(arc
							(start 0.3302 0.4318)
							(mid 0.402042 0.402042)
							(end 0.4318 0.3302)
						)
						(arc
							(start 0.4318 -0.3302)
							(mid 0.402042 -0.402042)
							(end 0.3302 -0.4318)
						)
					)
					(width 0)
					(fill yes)
				)
			)
		)
		(pad "2" smd custom
			(at 0 0.762 180)
			(size 0.2159 0.2159)
			(layers "F.Cu" "F.Mask" "F.Paste")
			(net "GND")
			(options
				(clearance outline)
				(anchor circle)
			)
			(primitives
				(gr_poly
					(pts
						(arc
							(start -0.3302 -0.4318)
							(mid -0.402042 -0.402042)
							(end -0.4318 -0.3302)
						)
						(arc
							(start -0.4318 0.3302)
							(mid -0.402042 0.402042)
							(end -0.3302 0.4318)
						)
						(arc
							(start 0.3302 0.4318)
							(mid 0.402042 0.402042)
							(end 0.4318 0.3302)
						)
						(arc
							(start 0.4318 -0.3302)
							(mid 0.402042 -0.402042)
							(end 0.3302 -0.4318)
						)
					)
					(width 0)
					(fill yes)
				)
			)
		)
	)
	(footprint ""
		(layer "F.Cu")
		(at 83.185 -146.939 -90)
		(property "Reference" "C213"
			(at 0 0 270)
			(layer "F.SilkS")
			(hide yes)
			(effects
				(font
					(size 1.27 1.27)
				)
			)
		)
		(property "Value" "SC10U16V6KX-2GP"
			(at -0.0762 -5.1308 270)
			(unlocked yes)
			(layer "F.Fab")
			(hide yes)
			(effects
				(font
					(size 1.016 1.016)
					(thickness 0.1524)
				)
			)
		)
		(property "Device Type" "C1206H71"
			(at -0.127 -6.6548 270)
			(unlocked yes)
			(layer "F.Fab")
			(hide yes)
			(effects
				(font
					(size 1.016 1.016)
					(thickness 0.1524)
				)
			)
		)
		(duplicate_pad_numbers_are_jumpers no)
		(fp_line
			(start -1.016 2.2352)
			(end -1.016 0.8382)
			(stroke
				(width 0.1524)
				(type default)
			)
			(layer "F.SilkS")
		)
		(fp_line
			(start 1.016 2.2352)
			(end -1.016 2.2352)
			(stroke
				(width 0.1524)
				(type default)
			)
			(layer "F.SilkS")
		)
		(fp_line
			(start 1.016 0.8382)
			(end 1.016 2.2352)
			(stroke
				(width 0.1524)
				(type default)
			)
			(layer "F.SilkS")
		)
		(fp_line
			(start -1.016 -0.8382)
			(end -1.016 -2.2352)
			(stroke
				(width 0.1524)
				(type default)
			)
			(layer "F.SilkS")
		)
		(fp_line
			(start -1.016 -2.2352)
			(end 1.016 -2.2352)
			(stroke
				(width 0.1524)
				(type default)
			)
			(layer "F.SilkS")
		)
		(fp_line
			(start 1.016 -2.2352)
			(end 1.016 -0.8382)
			(stroke
				(width 0.1524)
				(type default)
			)
			(layer "F.SilkS")
		)
		(fp_rect
			(start -1.0922 2.3114)
			(end 1.0922 -2.3114)
			(stroke
				(width 0)
				(type default)
			)
			(fill no)
			(layer "F.CrtYd")
		)
		(fp_poly
			(pts
				(xy 1.0922 -2.3114) (xy 1.0922 2.3114) (xy -1.0922 2.3114) (xy -1.0922 -2.3114)
			)
			(stroke
				(width 0)
				(type default)
			)
			(fill no)
			(layer "F.Fab")
		)
		(pad "1" smd rect
			(at 0 -1.397 270)
			(size 1.651 1.27)
			(layers "F.Cu" "F.Mask" "F.Paste")
			(net "P5V_HDD14")
		)
		(pad "2" smd rect
			(at 0 1.397 270)
			(size 1.651 1.27)
			(layers "F.Cu" "F.Mask" "F.Paste")
			(net "GND")
		)
	)
	(footprint ""
		(layer "F.Cu")
		(at 306.932076 -340.812882)
		(property "Reference" "R100"
			(at 0 0 0)
			(layer "F.SilkS")
			(hide yes)
			(effects
				(font
					(size 1.27 1.27)
				)
			)
		)
		(property "Value" "4K7R2F-GP"
			(at 0.064008 -3.993896 0)
			(unlocked yes)
			(layer "F.Fab")
			(hide yes)
			(effects
				(font
					(size 1.016 1.016)
					(thickness 0.1524)
				)
			)
		)
		(property "Device Type" "R402H16"
			(at 0.064008 -5.517896 0)
			(unlocked yes)
			(layer "F.Fab")
			(hide yes)
			(effects
				(font
					(size 1.016 1.016)
					(thickness 0.1524)
				)
			)
		)
		(duplicate_pad_numbers_are_jumpers no)
		(fp_line
			(start -0.508 -0.9398)
			(end -0.508 0.9398)
			(stroke
				(width 0.1524)
				(type default)
			)
			(layer "F.SilkS")
		)
		(fp_line
			(start 0.508 -0.9398)
			(end -0.508 -0.9398)
			(stroke
				(width 0.1524)
				(type default)
			)
			(layer "F.SilkS")
		)
		(fp_rect
			(start -0.508 0.9398)
			(end 0.508 -0.9398)
			(stroke
				(width 0)
				(type default)
			)
			(fill no)
			(layer "F.CrtYd")
		)
		(fp_rect
			(start -0.508 0.9398)
			(end 0.508 -0.9398)
			(stroke
				(width 0)
				(type default)
			)
			(fill no)
			(layer "F.Fab")
		)
		(pad "1" smd custom
			(at 0 -0.4445)
			(size 0.1397 0.1397)
			(layers "F.Cu" "F.Mask" "F.Paste")
			(net "P3V3_IN")
			(options
				(clearance outline)
				(anchor circle)
			)
			(primitives
				(gr_poly
					(pts
						(arc
							(start -0.1778 -0.2794)
							(mid -0.249642 -0.249642)
							(end -0.2794 -0.1778)
						)
						(arc
							(start -0.2794 0.1778)
							(mid -0.249642 0.249642)
							(end -0.1778 0.2794)
						)
						(arc
							(start 0.1778 0.2794)
							(mid 0.249642 0.249642)
							(end 0.2794 0.1778)
						)
						(arc
							(start 0.2794 -0.1778)
							(mid 0.249642 -0.249642)
							(end 0.1778 -0.2794)
						)
					)
					(width 0)
					(fill yes)
				)
			)
		)
		(pad "2" smd custom
			(at 0 0.4445)
			(size 0.1397 0.1397)
			(layers "F.Cu" "F.Mask" "F.Paste")
			(net "PWM_CAMP_SEL1")
			(options
				(clearance outline)
				(anchor circle)
			)
			(primitives
				(gr_poly
					(pts
						(arc
							(start -0.1778 -0.2794)
							(mid -0.249642 -0.249642)
							(end -0.2794 -0.1778)
						)
						(arc
							(start -0.2794 0.1778)
							(mid -0.249642 0.249642)
							(end -0.1778 0.2794)
						)
						(arc
							(start 0.1778 0.2794)
							(mid 0.249642 0.249642)
							(end 0.2794 0.1778)
						)
						(arc
							(start 0.2794 -0.1778)
							(mid 0.249642 -0.249642)
							(end 0.1778 -0.2794)
						)
					)
					(width 0)
					(fill yes)
				)
			)
		)
	)
	(footprint ""
		(layer "F.Cu")
		(at 82.042 -150.622 90)
		(property "Reference" "R393"
			(at 0 0 90)
			(layer "F.SilkS")
			(hide yes)
			(effects
				(font
					(size 1.27 1.27)
				)
			)
		)
		(property "Value" "2R6F-GP"
			(at -0.0508 -4.8514 90)
			(unlocked yes)
			(layer "F.Fab")
			(hide yes)
			(effects
				(font
					(size 1.016 1.016)
					(thickness 0.1524)
				)
			)
		)
		(property "Device Type" "R1206H26"
			(at 0 -6.3754 90)
			(unlocked yes)
			(layer "F.Fab")
			(hide yes)
			(effects
				(font
					(size 1.016 1.016)
					(thickness 0.1524)
				)
			)
		)
		(duplicate_pad_numbers_are_jumpers no)
		(fp_line
			(start 1.016 -2.2352)
			(end 1.016 2.2352)
			(stroke
				(width 0.1524)
				(type default)
			)
			(layer "F.SilkS")
		)
		(fp_line
			(start -1.016 -2.2352)
			(end 1.016 -2.2352)
			(stroke
				(width 0.1524)
				(type default)
			)
			(layer "F.SilkS")
		)
		(fp_line
			(start 1.016 2.2352)
			(end -1.016 2.2352)
			(stroke
				(width 0.1524)
				(type default)
			)
			(layer "F.SilkS")
		)
		(fp_line
			(start -1.016 2.2352)
			(end -1.016 -2.2352)
			(stroke
				(width 0.1524)
				(type default)
			)
			(layer "F.SilkS")
		)
		(fp_rect
			(start -1.0922 2.3114)
			(end 1.0922 -2.3114)
			(stroke
				(width 0)
				(type default)
			)
			(fill no)
			(layer "F.CrtYd")
		)
		(fp_poly
			(pts
				(xy -1.0922 -2.3114) (xy 1.0922 -2.3114) (xy 1.0922 2.3114) (xy -1.0922 2.3114)
			)
			(stroke
				(width 0)
				(type default)
			)
			(fill no)
			(layer "F.Fab")
		)
		(pad "1" smd rect
			(at 0 -1.397 90)
			(size 1.651 1.27)
			(layers "F.Cu" "F.Mask" "F.Paste")
			(net "P12V_HDD14")
		)
		(pad "2" smd rect
			(at 0 1.397 90)
			(size 1.651 1.27)
			(layers "F.Cu" "F.Mask" "F.Paste")
			(net "12V_PRE_14")
		)
	)
	(footprint ""
		(layer "F.Cu")
		(at 445.415924 -39.705026)
		(property "Reference" "TP191"
			(at 0 0 0)
			(layer "F.SilkS")
			(hide yes)
			(effects
				(font
					(size 1.27 1.27)
				)
			)
		)
		(property "Value" "*"
			(at -0.0508 -1.6764 0)
			(unlocked yes)
			(layer "F.Fab")
			(hide yes)
			(effects
				(font
					(size 1.016 1.016)
					(thickness 0.1524)
				)
			)
		)
		(property "Device Type" "TPAD32"
			(at -0.0508 -3.2004 0)
			(unlocked yes)
			(layer "F.Fab")
			(hide yes)
			(effects
				(font
					(size 1.016 1.016)
					(thickness 0.1524)
				)
			)
		)
		(duplicate_pad_numbers_are_jumpers no)
		(fp_poly
			(pts
				(arc
					(start 0.4064 0)
					(mid -0.4064 0)
					(end 0.4064 0)
				)
			)
			(stroke
				(width 0)
				(type default)
			)
			(fill no)
			(layer "F.CrtYd")
		)
		(fp_poly
			(pts
				(arc
					(start 0.7112 0)
					(mid -0.7112 0)
					(end 0.7112 0)
				)
			)
			(stroke
				(width 0)
				(type default)
			)
			(fill no)
			(layer "F.Fab")
		)
		(pad "1" smd circle
			(at 0 0)
			(size 0.8128 0.8128)
			(layers "F.Cu" "F.Mask" "F.Paste")
			(net "ACT_HDD_34")
		)
	)
	(footprint ""
		(layer "F.Cu")
		(at 109.474 -254.508 -90)
		(property "Reference" "R217"
			(at 0 0 270)
			(layer "F.SilkS")
			(hide yes)
			(effects
				(font
					(size 1.27 1.27)
				)
			)
		)
		(property "Value" "300KR2F-GP"
			(at 0.064008 -3.993896 270)
			(unlocked yes)
			(layer "F.Fab")
			(hide yes)
			(effects
				(font
					(size 1.016 1.016)
					(thickness 0.1524)
				)
			)
		)
		(property "Device Type" "R402H16"
			(at 0.064008 -5.517896 270)
			(unlocked yes)
			(layer "F.Fab")
			(hide yes)
			(effects
				(font
					(size 1.016 1.016)
					(thickness 0.1524)
				)
			)
		)
		(duplicate_pad_numbers_are_jumpers no)
		(fp_line
			(start -0.508 -0.9398)
			(end -0.508 0.9398)
			(stroke
				(width 0.1524)
				(type default)
			)
			(layer "F.SilkS")
		)
		(fp_line
			(start 0.508 -0.9398)
			(end -0.508 -0.9398)
			(stroke
				(width 0.1524)
				(type default)
			)
			(layer "F.SilkS")
		)
		(fp_rect
			(start -0.508 0.9398)
			(end 0.508 -0.9398)
			(stroke
				(width 0)
				(type default)
			)
			(fill no)
			(layer "F.CrtYd")
		)
		(fp_rect
			(start -0.508 0.9398)
			(end 0.508 -0.9398)
			(stroke
				(width 0)
				(type default)
			)
			(fill no)
			(layer "F.Fab")
		)
		(pad "1" smd custom
			(at 0 -0.4445 270)
			(size 0.1397 0.1397)
			(layers "F.Cu" "F.Mask" "F.Paste")
			(net "SW_HDD_N3")
			(options
				(clearance outline)
				(anchor circle)
			)
			(primitives
				(gr_poly
					(pts
						(arc
							(start -0.1778 -0.2794)
							(mid -0.249642 -0.249642)
							(end -0.2794 -0.1778)
						)
						(arc
							(start -0.2794 0.1778)
							(mid -0.249642 0.249642)
							(end -0.1778 0.2794)
						)
						(arc
							(start 0.1778 0.2794)
							(mid 0.249642 0.249642)
							(end 0.2794 0.1778)
						)
						(arc
							(start 0.2794 -0.1778)
							(mid 0.249642 -0.249642)
							(end 0.1778 -0.2794)
						)
					)
					(width 0)
					(fill yes)
				)
			)
		)
		(pad "2" smd custom
			(at 0 0.4445 270)
			(size 0.1397 0.1397)
			(layers "F.Cu" "F.Mask" "F.Paste")
			(net "P12V_B")
			(options
				(clearance outline)
				(anchor circle)
			)
			(primitives
				(gr_poly
					(pts
						(arc
							(start -0.1778 -0.2794)
							(mid -0.249642 -0.249642)
							(end -0.2794 -0.1778)
						)
						(arc
							(start -0.2794 0.1778)
							(mid -0.249642 0.249642)
							(end -0.1778 0.2794)
						)
						(arc
							(start 0.1778 0.2794)
							(mid 0.249642 0.249642)
							(end 0.2794 0.1778)
						)
						(arc
							(start 0.2794 -0.1778)
							(mid 0.249642 -0.249642)
							(end 0.1778 -0.2794)
						)
					)
					(width 0)
					(fill yes)
				)
			)
		)
	)
	(footprint ""
		(layer "F.Cu")
		(at 32.508952 -18.750026 -90)
		(property "Reference" "VIA50"
			(at 0 0 270)
			(layer "F.SilkS")
			(hide yes)
			(effects
				(font
					(size 1.27 1.27)
				)
			)
		)
		(property "Value" "100OHM-8L-2D36MM-L16-GP"
			(at -3.4036 -0.4572 270)
			(unlocked yes)
			(layer "F.Fab")
			(hide yes)
			(effects
				(font
					(size 1.016 1.016)
					(thickness 0.1524)
				)
			)
		)
		(property "Device Type" "VIA-PCIE-4P-427097"
			(at -3.4036 -1.9812 270)
			(unlocked yes)
			(layer "F.Fab")
			(hide yes)
			(effects
				(font
					(size 1.016 1.016)
					(thickness 0.1524)
				)
			)
		)
		(duplicate_pad_numbers_are_jumpers no)
		(fp_rect
			(start -2.1336 0.4826)
			(end 2.1336 -0.4826)
			(stroke
				(width 0)
				(type default)
			)
			(fill no)
			(layer "F.CrtYd")
		)
		(fp_rect
			(start -2.1336 0.4826)
			(end 2.1336 -0.4826)
			(stroke
				(width 0)
				(type default)
			)
			(fill no)
			(layer "F.Fab")
		)
		(pad "1" thru_hole circle
			(at -1.651 0 270)
			(size 0.508 0.508)
			(drill 0.254)
			(layers "*.Cu" "*.Mask")
			(remove_unused_layers no)
			(net "GND")
			(clearance 0.2286)
			(thermal_gap 0.2286)
		)
		(pad "2" thru_hole circle
			(at -0.635 0 270)
			(size 0.508 0.508)
			(drill 0.254)
			(layers "*.Cu" "*.Mask")
			(remove_unused_layers no)
			(net "PHY_DRV_B_TO_SCC_B_24_DP")
			(clearance 0.2286)
			(thermal_gap 0.2286)
		)
		(pad "3" thru_hole circle
			(at 0.635 0 270)
			(size 0.508 0.508)
			(drill 0.254)
			(layers "*.Cu" "*.Mask")
			(remove_unused_layers no)
			(net "PHY_DRV_B_TO_SCC_B_24_DN")
			(clearance 0.2286)
			(thermal_gap 0.2286)
		)
		(pad "4" thru_hole circle
			(at 1.651 0 270)
			(size 0.508 0.508)
			(drill 0.254)
			(layers "*.Cu" "*.Mask")
			(remove_unused_layers no)
			(net "GND")
			(clearance 0.2286)
			(thermal_gap 0.2286)
		)
	)
	(footprint ""
		(layer "F.Cu")
		(at 35.400996 -375.92)
		(property "Reference" "R930"
			(at 0 0 0)
			(layer "F.SilkS")
			(hide yes)
			(effects
				(font
					(size 1.27 1.27)
				)
			)
		)
		(property "Value" "100KR2F-L1-GP"
			(at 0.064008 -3.993896 0)
			(unlocked yes)
			(layer "F.Fab")
			(hide yes)
			(effects
				(font
					(size 1.016 1.016)
					(thickness 0.1524)
				)
			)
		)
		(property "Device Type" "R402H16"
			(at 0.064008 -5.517896 0)
			(unlocked yes)
			(layer "F.Fab")
			(hide yes)
			(effects
				(font
					(size 1.016 1.016)
					(thickness 0.1524)
				)
			)
		)
		(duplicate_pad_numbers_are_jumpers no)
		(fp_line
			(start -0.508 -0.9398)
			(end -0.508 0.9398)
			(stroke
				(width 0.1524)
				(type default)
			)
			(layer "F.SilkS")
		)
		(fp_line
			(start 0.508 -0.9398)
			(end -0.508 -0.9398)
			(stroke
				(width 0.1524)
				(type default)
			)
			(layer "F.SilkS")
		)
		(fp_rect
			(start -0.508 0.9398)
			(end 0.508 -0.9398)
			(stroke
				(width 0)
				(type default)
			)
			(fill no)
			(layer "F.CrtYd")
		)
		(fp_rect
			(start -0.508 0.9398)
			(end 0.508 -0.9398)
			(stroke
				(width 0)
				(type default)
			)
			(fill no)
			(layer "F.Fab")
		)
		(pad "1" smd custom
			(at 0 -0.4445)
			(size 0.1397 0.1397)
			(layers "F.Cu" "F.Mask" "F.Paste")
			(net "P3V3_IN")
			(options
				(clearance outline)
				(anchor circle)
			)
			(primitives
				(gr_poly
					(pts
						(arc
							(start -0.1778 -0.2794)
							(mid -0.249642 -0.249642)
							(end -0.2794 -0.1778)
						)
						(arc
							(start -0.2794 0.1778)
							(mid -0.249642 0.249642)
							(end -0.1778 0.2794)
						)
						(arc
							(start 0.1778 0.2794)
							(mid 0.249642 0.249642)
							(end 0.2794 0.1778)
						)
						(arc
							(start 0.2794 -0.1778)
							(mid 0.249642 -0.249642)
							(end 0.1778 -0.2794)
						)
					)
					(width 0)
					(fill yes)
				)
			)
		)
		(pad "2" smd custom
			(at 0 0.4445)
			(size 0.1397 0.1397)
			(layers "F.Cu" "F.Mask" "F.Paste")
			(net "FAN_0_INS_N")
			(options
				(clearance outline)
				(anchor circle)
			)
			(primitives
				(gr_poly
					(pts
						(arc
							(start -0.1778 -0.2794)
							(mid -0.249642 -0.249642)
							(end -0.2794 -0.1778)
						)
						(arc
							(start -0.2794 0.1778)
							(mid -0.249642 0.249642)
							(end -0.1778 0.2794)
						)
						(arc
							(start 0.1778 0.2794)
							(mid 0.249642 0.249642)
							(end 0.2794 0.1778)
						)
						(arc
							(start 0.2794 -0.1778)
							(mid 0.249642 -0.249642)
							(end 0.1778 -0.2794)
						)
					)
					(width 0)
					(fill yes)
				)
			)
		)
	)
	(footprint ""
		(layer "F.Cu")
		(at 338.455 -28.829 90)
		(property "Reference" "C429"
			(at 0 0 90)
			(layer "F.SilkS")
			(hide yes)
			(effects
				(font
					(size 1.27 1.27)
				)
			)
		)
		(property "Value" "SCD033U25V2KX-GP"
			(at 1.1811 -2.7051 90)
			(unlocked yes)
			(layer "F.Fab")
			(hide yes)
			(effects
				(font
					(size 1.016 1.016)
					(thickness 0.1524)
				)
			)
		)
		(property "Device Type" "C402H22"
			(at 1.1811 -4.2291 90)
			(unlocked yes)
			(layer "F.Fab")
			(hide yes)
			(effects
				(font
					(size 1.016 1.016)
					(thickness 0.1524)
				)
			)
		)
		(duplicate_pad_numbers_are_jumpers no)
		(fp_rect
			(start -0.4318 0.9525)
			(end 0.4318 -0.9525)
			(stroke
				(width 0)
				(type default)
			)
			(fill no)
			(layer "F.CrtYd")
		)
		(fp_rect
			(start -0.4318 0.9525)
			(end 0.4318 -0.9525)
			(stroke
				(width 0)
				(type default)
			)
			(fill no)
			(layer "F.Fab")
		)
		(pad "1" smd custom
			(at 0 -0.4445 90)
			(size 0.1524 0.1524)
			(layers "F.Cu" "F.Mask" "F.Paste")
			(net "P12V_B")
			(options
				(clearance outline)
				(anchor circle)
			)
			(primitives
				(gr_poly
					(pts
						(arc
							(start 0.3048 -0.2032)
							(mid 0.275042 -0.275042)
							(end 0.2032 -0.3048)
						)
						(arc
							(start -0.2032 -0.3048)
							(mid -0.275042 -0.275042)
							(end -0.3048 -0.2032)
						)
						(arc
							(start -0.3048 0.2032)
							(mid -0.275042 0.275042)
							(end -0.2032 0.3048)
						)
						(arc
							(start 0.2032 0.3048)
							(mid 0.275042 0.275042)
							(end 0.3048 0.2032)
						)
					)
					(width 0)
					(fill yes)
				)
			)
		)
		(pad "2" smd custom
			(at 0 0.4445 90)
			(size 0.1524 0.1524)
			(layers "F.Cu" "F.Mask" "F.Paste")
			(net "SW_HDD_N30")
			(options
				(clearance outline)
				(anchor circle)
			)
			(primitives
				(gr_poly
					(pts
						(arc
							(start 0.3048 -0.2032)
							(mid 0.275042 -0.275042)
							(end 0.2032 -0.3048)
						)
						(arc
							(start -0.2032 -0.3048)
							(mid -0.275042 -0.275042)
							(end -0.3048 -0.2032)
						)
						(arc
							(start -0.3048 0.2032)
							(mid -0.275042 0.275042)
							(end -0.2032 0.3048)
						)
						(arc
							(start 0.2032 0.3048)
							(mid 0.275042 0.275042)
							(end 0.3048 0.2032)
						)
					)
					(width 0)
					(fill yes)
				)
			)
		)
	)
	(footprint ""
		(layer "F.Cu")
		(at 36.035996 -365.379 -90)
		(property "Reference" "R929"
			(at 0 0 270)
			(layer "F.SilkS")
			(hide yes)
			(effects
				(font
					(size 1.27 1.27)
				)
			)
		)
		(property "Value" "27KR3F-GP"
			(at -0.0254 -2.5146 270)
			(unlocked yes)
			(layer "F.Fab")
			(hide yes)
			(effects
				(font
					(size 1.016 1.016)
					(thickness 0.1524)
				)
			)
		)
		(property "Device Type" "R603H22"
			(at -0.0254 -4.0386 270)
			(unlocked yes)
			(layer "F.Fab")
			(hide yes)
			(effects
				(font
					(size 1.016 1.016)
					(thickness 0.1524)
				)
			)
		)
		(duplicate_pad_numbers_are_jumpers no)
		(fp_line
			(start -0.4826 0)
			(end -0.2032 0)
			(stroke
				(width 0.2032)
				(type default)
			)
			(layer "F.SilkS")
		)
		(fp_line
			(start 0.2032 0)
			(end 0.4826 0)
			(stroke
				(width 0.2032)
				(type default)
			)
			(layer "F.SilkS")
		)
		(fp_rect
			(start -0.5842 1.3335)
			(end 0.5842 -1.3335)
			(stroke
				(width 0)
				(type default)
			)
			(fill no)
			(layer "F.CrtYd")
		)
		(fp_rect
			(start -0.5842 1.3335)
			(end 0.5842 -1.3335)
			(stroke
				(width 0)
				(type default)
			)
			(fill no)
			(layer "F.Fab")
		)
		(pad "1" smd custom
			(at 0 -0.762 270)
			(size 0.2159 0.2159)
			(layers "F.Cu" "F.Mask" "F.Paste")
			(net "FAN_0_TACH1")
			(options
				(clearance outline)
				(anchor circle)
			)
			(primitives
				(gr_poly
					(pts
						(arc
							(start -0.3302 -0.4318)
							(mid -0.402042 -0.402042)
							(end -0.4318 -0.3302)
						)
						(arc
							(start -0.4318 0.3302)
							(mid -0.402042 0.402042)
							(end -0.3302 0.4318)
						)
						(arc
							(start 0.3302 0.4318)
							(mid 0.402042 0.402042)
							(end 0.4318 0.3302)
						)
						(arc
							(start 0.4318 -0.3302)
							(mid 0.402042 -0.402042)
							(end 0.3302 -0.4318)
						)
					)
					(width 0)
					(fill yes)
				)
			)
		)
		(pad "2" smd custom
			(at 0 0.762 270)
			(size 0.2159 0.2159)
			(layers "F.Cu" "F.Mask" "F.Paste")
			(net "FANTACH_F0")
			(options
				(clearance outline)
				(anchor circle)
			)
			(primitives
				(gr_poly
					(pts
						(arc
							(start -0.3302 -0.4318)
							(mid -0.402042 -0.402042)
							(end -0.4318 -0.3302)
						)
						(arc
							(start -0.4318 0.3302)
							(mid -0.402042 0.402042)
							(end -0.3302 0.4318)
						)
						(arc
							(start 0.3302 0.4318)
							(mid 0.402042 0.402042)
							(end 0.4318 0.3302)
						)
						(arc
							(start 0.4318 -0.3302)
							(mid 0.402042 -0.402042)
							(end 0.3302 -0.4318)
						)
					)
					(width 0)
					(fill yes)
				)
			)
		)
	)
	(footprint ""
		(layer "F.Cu")
		(at 348.582996 -360.934 90)
		(property "Reference" "C530"
			(at 0 0 90)
			(layer "F.SilkS")
			(hide yes)
			(effects
				(font
					(size 1.27 1.27)
				)
			)
		)
		(property "Value" "SC22U25V0MX-2-GP"
			(at -0.00254 -4.78536 90)
			(unlocked yes)
			(layer "F.Fab")
			(hide yes)
			(effects
				(font
					(size 1.016 1.016)
					(thickness 0.1524)
				)
			)
		)
		(property "Device Type" "C1210H111"
			(at -0.00254 -6.38048 90)
			(unlocked yes)
			(layer "F.Fab")
			(hide yes)
			(effects
				(font
					(size 1.016 1.016)
					(thickness 0.1524)
				)
			)
		)
		(duplicate_pad_numbers_are_jumpers no)
		(fp_line
			(start 1.5748 -2.3368)
			(end -1.5748 -2.3368)
			(stroke
				(width 0.1524)
				(type default)
			)
			(layer "F.SilkS")
		)
		(fp_line
			(start -1.5748 -2.3368)
			(end -1.5748 -0.762)
			(stroke
				(width 0.1524)
				(type default)
			)
			(layer "F.SilkS")
		)
		(fp_line
			(start 1.5748 -0.762)
			(end 1.5748 -2.3368)
			(stroke
				(width 0.1524)
				(type default)
			)
			(layer "F.SilkS")
		)
		(fp_line
			(start -1.5748 0.762)
			(end -1.5748 2.3368)
			(stroke
				(width 0.1524)
				(type default)
			)
			(layer "F.SilkS")
		)
		(fp_line
			(start 1.5748 2.3368)
			(end 1.5748 0.762)
			(stroke
				(width 0.1524)
				(type default)
			)
			(layer "F.SilkS")
		)
		(fp_line
			(start -1.5748 2.3368)
			(end 1.5748 2.3368)
			(stroke
				(width 0.1524)
				(type default)
			)
			(layer "F.SilkS")
		)
		(fp_rect
			(start -1.651 2.413)
			(end 1.651 -2.413)
			(stroke
				(width 0)
				(type default)
			)
			(fill no)
			(layer "F.CrtYd")
		)
		(fp_poly
			(pts
				(xy 1.651 2.413) (xy 1.651 -2.413) (xy -1.651 -2.413) (xy -1.651 2.413)
			)
			(stroke
				(width 0)
				(type default)
			)
			(fill no)
			(layer "F.Fab")
		)
		(pad "1" smd rect
			(at 0 -1.4732 90)
			(size 2.794 1.397)
			(layers "F.Cu" "F.Mask" "F.Paste")
			(net "P12V_FAN2")
		)
		(pad "2" smd rect
			(at 0 1.4732 90)
			(size 2.794 1.397)
			(layers "F.Cu" "F.Mask" "F.Paste")
			(net "GND")
		)
	)
	(footprint ""
		(layer "F.Cu")
		(at 346.700094 -180.399944)
		(property "Reference" "LED8"
			(at 0 0 0)
			(layer "F.SilkS")
			(hide yes)
			(effects
				(font
					(size 1.27 1.27)
				)
			)
		)
		(property "Value" "LED-BY-19-GP"
			(at -2.132076 1.414018 0)
			(unlocked yes)
			(layer "F.Fab")
			(hide yes)
			(effects
				(font
					(size 1.016 1.016)
					(thickness 0.1524)
				)
			)
		)
		(property "Device Type" "LED-1615-4PH26"
			(at -2.132076 -0.109982 0)
			(unlocked yes)
			(layer "F.Fab")
			(hide yes)
			(effects
				(font
					(size 1.016 1.016)
					(thickness 0.1524)
				)
			)
		)
		(duplicate_pad_numbers_are_jumpers no)
		(fp_line
			(start -1.2954 0.254)
			(end -1.2954 1.6002)
			(stroke
				(width 0.508)
				(type default)
			)
			(layer "F.SilkS")
		)
		(fp_line
			(start -1.2954 1.6002)
			(end 1.2954 1.6002)
			(stroke
				(width 0.508)
				(type default)
			)
			(layer "F.SilkS")
		)
		(fp_line
			(start -1.1176 -1.4224)
			(end 1.1176 -1.4224)
			(stroke
				(width 0.1524)
				(type default)
			)
			(layer "F.SilkS")
		)
		(fp_line
			(start -1.1176 1.4224)
			(end -1.1176 -1.4224)
			(stroke
				(width 0.1524)
				(type default)
			)
			(layer "F.SilkS")
		)
		(fp_line
			(start 1.1176 -1.4224)
			(end 1.1176 1.4224)
			(stroke
				(width 0.1524)
				(type default)
			)
			(layer "F.SilkS")
		)
		(fp_line
			(start 1.1176 1.4224)
			(end -1.1176 1.4224)
			(stroke
				(width 0.1524)
				(type default)
			)
			(layer "F.SilkS")
		)
		(fp_line
			(start 1.2954 1.6002)
			(end 1.2954 0.254)
			(stroke
				(width 0.508)
				(type default)
			)
			(layer "F.SilkS")
		)
		(fp_rect
			(start -0.7493 0.8001)
			(end 0.7493 -0.8001)
			(stroke
				(width 0)
				(type default)
			)
			(fill no)
			(layer "F.CrtYd")
		)
		(fp_poly
			(pts
				(xy -1.3716 1.6764) (xy -1.3716 -1.6764) (xy 1.3716 -1.6764) (xy 1.3716 0.0635) (xy 0.7493 0.0635)
				(xy 0.7493 -0.8001) (xy -0.7493 -0.8001) (xy -0.7493 0.8001) (xy 0.7493 0.8001) (xy 0.7493 0.0762)
				(xy 1.3716 0.0762) (xy 1.3716 1.6764)
			)
			(stroke
				(width 0)
				(type default)
			)
			(fill no)
			(layer "F.CrtYd")
		)
		(fp_rect
			(start -1.3716 1.6764)
			(end 1.3716 -1.6764)
			(stroke
				(width 0)
				(type default)
			)
			(fill no)
			(layer "F.Fab")
		)
		(pad "1" smd rect
			(at 0.50038 -0.73025)
			(size 0.7112 0.8636)
			(layers "F.Cu" "F.Mask" "F.Paste")
			(net "DRV_ACT_7")
		)
		(pad "2" smd rect
			(at -0.50038 -0.73025)
			(size 0.7112 0.8636)
			(layers "F.Cu" "F.Mask" "F.Paste")
			(net "FLT_HDD7")
		)
		(pad "3" smd rect
			(at 0.50038 0.73025)
			(size 0.7112 0.8636)
			(layers "F.Cu" "F.Mask" "F.Paste")
			(net "DRV_ACT_7_N")
		)
		(pad "4" smd rect
			(at -0.50038 0.73025)
			(size 0.7112 0.8636)
			(layers "F.Cu" "F.Mask" "F.Paste")
			(net "FLT_HDD7_N")
		)
	)
	(footprint ""
		(layer "F.Cu")
		(at 81.534 -131.572)
		(property "Reference" "R409"
			(at 0 0 0)
			(layer "F.SilkS")
			(hide yes)
			(effects
				(font
					(size 1.27 1.27)
				)
			)
		)
		(property "Value" "0R2J-2-GP"
			(at 0.064008 -3.993896 0)
			(unlocked yes)
			(layer "F.Fab")
			(hide yes)
			(effects
				(font
					(size 1.016 1.016)
					(thickness 0.1524)
				)
			)
		)
		(property "Device Type" "R402H16"
			(at 0.064008 -5.517896 0)
			(unlocked yes)
			(layer "F.Fab")
			(hide yes)
			(effects
				(font
					(size 1.016 1.016)
					(thickness 0.1524)
				)
			)
		)
		(duplicate_pad_numbers_are_jumpers no)
		(fp_line
			(start -0.508 -0.9398)
			(end -0.508 0.9398)
			(stroke
				(width 0.1524)
				(type default)
			)
			(layer "F.SilkS")
		)
		(fp_line
			(start 0.508 -0.9398)
			(end -0.508 -0.9398)
			(stroke
				(width 0.1524)
				(type default)
			)
			(layer "F.SilkS")
		)
		(fp_rect
			(start -0.508 0.9398)
			(end 0.508 -0.9398)
			(stroke
				(width 0)
				(type default)
			)
			(fill no)
			(layer "F.CrtYd")
		)
		(fp_rect
			(start -0.508 0.9398)
			(end 0.508 -0.9398)
			(stroke
				(width 0)
				(type default)
			)
			(fill no)
			(layer "F.Fab")
		)
		(pad "1" smd custom
			(at 0 -0.4445)
			(size 0.1397 0.1397)
			(layers "F.Cu" "F.Mask" "F.Paste")
			(net "SW_HDD_G14")
			(options
				(clearance outline)
				(anchor circle)
			)
			(primitives
				(gr_poly
					(pts
						(arc
							(start -0.1778 -0.2794)
							(mid -0.249642 -0.249642)
							(end -0.2794 -0.1778)
						)
						(arc
							(start -0.2794 0.1778)
							(mid -0.249642 0.249642)
							(end -0.1778 0.2794)
						)
						(arc
							(start 0.1778 0.2794)
							(mid 0.249642 0.249642)
							(end 0.2794 0.1778)
						)
						(arc
							(start 0.2794 -0.1778)
							(mid 0.249642 -0.249642)
							(end 0.1778 -0.2794)
						)
					)
					(width 0)
					(fill yes)
				)
			)
		)
		(pad "2" smd custom
			(at 0 0.4445)
			(size 0.1397 0.1397)
			(layers "F.Cu" "F.Mask" "F.Paste")
			(net "SW_HDD_R14")
			(options
				(clearance outline)
				(anchor circle)
			)
			(primitives
				(gr_poly
					(pts
						(arc
							(start -0.1778 -0.2794)
							(mid -0.249642 -0.249642)
							(end -0.2794 -0.1778)
						)
						(arc
							(start -0.2794 0.1778)
							(mid -0.249642 0.249642)
							(end -0.1778 0.2794)
						)
						(arc
							(start 0.1778 0.2794)
							(mid 0.249642 0.249642)
							(end 0.2794 0.1778)
						)
						(arc
							(start 0.2794 -0.1778)
							(mid 0.249642 -0.249642)
							(end 0.1778 -0.2794)
						)
					)
					(width 0)
					(fill yes)
				)
			)
		)
	)
	(footprint ""
		(layer "F.Cu")
		(at 382.88595 -128.627124 180)
		(property "Reference" "VIA41"
			(at 0 0 180)
			(layer "F.SilkS")
			(hide yes)
			(effects
				(font
					(size 1.27 1.27)
				)
			)
		)
		(property "Value" "100OHM-8L-2D36MM-L18-GP"
			(at 3.8989 0.5715 180)
			(unlocked yes)
			(layer "F.Fab")
			(hide yes)
			(effects
				(font
					(size 1.016 1.016)
					(thickness 0.1524)
				)
			)
		)
		(property "Device Type" "VIA-PCIE-4P-414097"
			(at 3.8989 -0.9525 180)
			(unlocked yes)
			(layer "F.Fab")
			(hide yes)
			(effects
				(font
					(size 1.016 1.016)
					(thickness 0.1524)
				)
			)
		)
		(duplicate_pad_numbers_are_jumpers no)
		(fp_rect
			(start -2.0701 0.4826)
			(end 2.0701 -0.4826)
			(stroke
				(width 0)
				(type default)
			)
			(fill no)
			(layer "F.CrtYd")
		)
		(fp_rect
			(start -2.0701 0.4826)
			(end 2.0701 -0.4826)
			(stroke
				(width 0)
				(type default)
			)
			(fill no)
			(layer "F.Fab")
		)
		(pad "1" thru_hole circle
			(at -1.5875 0 180)
			(size 0.508 0.508)
			(drill 0.254)
			(layers "*.Cu" "*.Mask")
			(remove_unused_layers no)
			(net "GND")
			(clearance 0.2286)
			(thermal_gap 0.2286)
		)
		(pad "2" thru_hole circle
			(at -0.5715 0 180)
			(size 0.508 0.508)
			(drill 0.254)
			(layers "*.Cu" "*.Mask")
			(remove_unused_layers no)
			(net "PHY_SCC_B_TO_DRV_B_20_DP")
			(clearance 0.2286)
			(thermal_gap 0.2286)
		)
		(pad "3" thru_hole circle
			(at 0.5715 0 180)
			(size 0.508 0.508)
			(drill 0.254)
			(layers "*.Cu" "*.Mask")
			(remove_unused_layers no)
			(net "PHY_SCC_B_TO_DRV_B_20_DN")
			(clearance 0.2286)
			(thermal_gap 0.2286)
		)
		(pad "4" thru_hole circle
			(at 1.5875 0 180)
			(size 0.508 0.508)
			(drill 0.254)
			(layers "*.Cu" "*.Mask")
			(remove_unused_layers no)
			(net "GND")
			(clearance 0.2286)
			(thermal_gap 0.2286)
		)
	)
	(footprint ""
		(layer "F.Cu")
		(at 395.478 -151.892 180)
		(property "Reference" "C291"
			(at 0 0 180)
			(layer "F.SilkS")
			(hide yes)
			(effects
				(font
					(size 1.27 1.27)
				)
			)
		)
		(property "Value" "SC10U16V6KX-2GP"
			(at -0.0762 -5.1308 180)
			(unlocked yes)
			(layer "F.Fab")
			(hide yes)
			(effects
				(font
					(size 1.016 1.016)
					(thickness 0.1524)
				)
			)
		)
		(property "Device Type" "C1206H71"
			(at -0.127 -6.6548 180)
			(unlocked yes)
			(layer "F.Fab")
			(hide yes)
			(effects
				(font
					(size 1.016 1.016)
					(thickness 0.1524)
				)
			)
		)
		(duplicate_pad_numbers_are_jumpers no)
		(fp_line
			(start 1.016 2.2352)
			(end -1.016 2.2352)
			(stroke
				(width 0.1524)
				(type default)
			)
			(layer "F.SilkS")
		)
		(fp_line
			(start 1.016 0.8382)
			(end 1.016 2.2352)
			(stroke
				(width 0.1524)
				(type default)
			)
			(layer "F.SilkS")
		)
		(fp_line
			(start 1.016 -2.2352)
			(end 1.016 -0.8382)
			(stroke
				(width 0.1524)
				(type default)
			)
			(layer "F.SilkS")
		)
		(fp_line
			(start -1.016 2.2352)
			(end -1.016 0.8382)
			(stroke
				(width 0.1524)
				(type default)
			)
			(layer "F.SilkS")
		)
		(fp_line
			(start -1.016 -0.8382)
			(end -1.016 -2.2352)
			(stroke
				(width 0.1524)
				(type default)
			)
			(layer "F.SilkS")
		)
		(fp_line
			(start -1.016 -2.2352)
			(end 1.016 -2.2352)
			(stroke
				(width 0.1524)
				(type default)
			)
			(layer "F.SilkS")
		)
		(fp_rect
			(start -1.0922 2.3114)
			(end 1.0922 -2.3114)
			(stroke
				(width 0)
				(type default)
			)
			(fill no)
			(layer "F.CrtYd")
		)
		(fp_poly
			(pts
				(xy 1.0922 -2.3114) (xy 1.0922 2.3114) (xy -1.0922 2.3114) (xy -1.0922 -2.3114)
			)
			(stroke
				(width 0)
				(type default)
			)
			(fill no)
			(layer "F.Fab")
		)
		(pad "1" smd rect
			(at 0 -1.397 180)
			(size 1.651 1.27)
			(layers "F.Cu" "F.Mask" "F.Paste")
			(net "P5V_HDD20")
		)
		(pad "2" smd rect
			(at 0 1.397 180)
			(size 1.651 1.27)
			(layers "F.Cu" "F.Mask" "F.Paste")
			(net "GND")
		)
	)
	(footprint ""
		(layer "F.Cu")
		(at 321.634612 -245.219474 -90)
		(property "Reference" "C106"
			(at 0 0 270)
			(layer "F.SilkS")
			(hide yes)
			(effects
				(font
					(size 1.27 1.27)
				)
			)
		)
		(property "Value" "SCD01U16V1KX-GP"
			(at -2.8321 -1.7399 270)
			(unlocked yes)
			(layer "F.Fab")
			(hide yes)
			(effects
				(font
					(size 1.016 1.016)
					(thickness 0.1524)
				)
			)
		)
		(property "Device Type" "C0201H13"
			(at -2.8321 -3.2639 270)
			(unlocked yes)
			(layer "F.Fab")
			(hide yes)
			(effects
				(font
					(size 1.016 1.016)
					(thickness 0.1524)
				)
			)
		)
		(duplicate_pad_numbers_are_jumpers no)
		(fp_rect
			(start -0.2794 0.6477)
			(end 0.2794 -0.6477)
			(stroke
				(width 0)
				(type default)
			)
			(fill no)
			(layer "F.CrtYd")
		)
		(fp_rect
			(start -0.2794 0.6477)
			(end 0.2794 -0.6477)
			(stroke
				(width 0)
				(type default)
			)
			(fill no)
			(layer "F.Fab")
		)
		(pad "1" smd custom
			(at 0 -0.2794 270)
			(size 0.0762 0.0762)
			(layers "F.Cu" "F.Mask" "F.Paste")
			(net "SAS_HDD_RX_N6")
			(options
				(clearance outline)
				(anchor circle)
			)
			(primitives
				(gr_poly
					(pts
						(arc
							(start 0.1524 -0.127)
							(mid 0.137521 -0.162921)
							(end 0.1016 -0.1778)
						)
						(arc
							(start -0.1016 -0.1778)
							(mid -0.137521 -0.162921)
							(end -0.1524 -0.127)
						)
						(arc
							(start -0.1524 0.127)
							(mid -0.137521 0.162921)
							(end -0.1016 0.1778)
						)
						(arc
							(start 0.1016 0.1778)
							(mid 0.137521 0.162921)
							(end 0.1524 0.127)
						)
					)
					(width 0)
					(fill yes)
				)
			)
		)
		(pad "2" smd custom
			(at 0 0.2794 270)
			(size 0.0762 0.0762)
			(layers "F.Cu" "F.Mask" "F.Paste")
			(net "PHY_SCC_B_TO_DRV_B_6_DN")
			(options
				(clearance outline)
				(anchor circle)
			)
			(primitives
				(gr_poly
					(pts
						(arc
							(start 0.1524 -0.127)
							(mid 0.137521 -0.162921)
							(end 0.1016 -0.1778)
						)
						(arc
							(start -0.1016 -0.1778)
							(mid -0.137521 -0.162921)
							(end -0.1524 -0.127)
						)
						(arc
							(start -0.1524 0.127)
							(mid -0.137521 0.162921)
							(end -0.1016 0.1778)
						)
						(arc
							(start 0.1016 0.1778)
							(mid 0.137521 0.162921)
							(end 0.1524 0.127)
						)
					)
					(width 0)
					(fill yes)
				)
			)
		)
	)
	(footprint ""
		(layer "F.Cu")
		(at 363.1184 -250.5456 -90)
		(property "Reference" "C129"
			(at 0 0 270)
			(layer "F.SilkS")
			(hide yes)
			(effects
				(font
					(size 1.27 1.27)
				)
			)
		)
		(property "Value" "SCD033U25V2KX-GP"
			(at 1.1811 -2.7051 270)
			(unlocked yes)
			(layer "F.Fab")
			(hide yes)
			(effects
				(font
					(size 1.016 1.016)
					(thickness 0.1524)
				)
			)
		)
		(property "Device Type" "C402H22"
			(at 1.1811 -4.2291 270)
			(unlocked yes)
			(layer "F.Fab")
			(hide yes)
			(effects
				(font
					(size 1.016 1.016)
					(thickness 0.1524)
				)
			)
		)
		(duplicate_pad_numbers_are_jumpers no)
		(fp_rect
			(start -0.4318 0.9525)
			(end 0.4318 -0.9525)
			(stroke
				(width 0)
				(type default)
			)
			(fill no)
			(layer "F.CrtYd")
		)
		(fp_rect
			(start -0.4318 0.9525)
			(end 0.4318 -0.9525)
			(stroke
				(width 0)
				(type default)
			)
			(fill no)
			(layer "F.Fab")
		)
		(pad "1" smd custom
			(at 0 -0.4445 270)
			(size 0.1524 0.1524)
			(layers "F.Cu" "F.Mask" "F.Paste")
			(net "SW_HDD_P7")
			(options
				(clearance outline)
				(anchor circle)
			)
			(primitives
				(gr_poly
					(pts
						(arc
							(start 0.3048 -0.2032)
							(mid 0.275042 -0.275042)
							(end 0.2032 -0.3048)
						)
						(arc
							(start -0.2032 -0.3048)
							(mid -0.275042 -0.275042)
							(end -0.3048 -0.2032)
						)
						(arc
							(start -0.3048 0.2032)
							(mid -0.275042 0.275042)
							(end -0.2032 0.3048)
						)
						(arc
							(start 0.2032 0.3048)
							(mid 0.275042 0.275042)
							(end 0.3048 0.2032)
						)
					)
					(width 0)
					(fill yes)
				)
			)
		)
		(pad "2" smd custom
			(at 0 0.4445 270)
			(size 0.1524 0.1524)
			(layers "F.Cu" "F.Mask" "F.Paste")
			(net "GND")
			(options
				(clearance outline)
				(anchor circle)
			)
			(primitives
				(gr_poly
					(pts
						(arc
							(start 0.3048 -0.2032)
							(mid 0.275042 -0.275042)
							(end 0.2032 -0.3048)
						)
						(arc
							(start -0.2032 -0.3048)
							(mid -0.275042 -0.275042)
							(end -0.3048 -0.2032)
						)
						(arc
							(start -0.3048 0.2032)
							(mid -0.275042 0.275042)
							(end -0.2032 0.3048)
						)
						(arc
							(start 0.2032 0.3048)
							(mid 0.275042 0.275042)
							(end 0.3048 0.2032)
						)
					)
					(width 0)
					(fill yes)
				)
			)
		)
	)
	(footprint ""
		(layer "F.Cu")
		(at 427.0756 -20.574 90)
		(property "Reference" "C467"
			(at 0 0 90)
			(layer "F.SilkS")
			(hide yes)
			(effects
				(font
					(size 1.27 1.27)
				)
			)
		)
		(property "Value" "SCD033U25V2KX-GP"
			(at 1.1811 -2.7051 90)
			(unlocked yes)
			(layer "F.Fab")
			(hide yes)
			(effects
				(font
					(size 1.016 1.016)
					(thickness 0.1524)
				)
			)
		)
		(property "Device Type" "C402H22"
			(at 1.1811 -4.2291 90)
			(unlocked yes)
			(layer "F.Fab")
			(hide yes)
			(effects
				(font
					(size 1.016 1.016)
					(thickness 0.1524)
				)
			)
		)
		(duplicate_pad_numbers_are_jumpers no)
		(fp_rect
			(start -0.4318 0.9525)
			(end 0.4318 -0.9525)
			(stroke
				(width 0)
				(type default)
			)
			(fill no)
			(layer "F.CrtYd")
		)
		(fp_rect
			(start -0.4318 0.9525)
			(end 0.4318 -0.9525)
			(stroke
				(width 0)
				(type default)
			)
			(fill no)
			(layer "F.Fab")
		)
		(pad "1" smd custom
			(at 0 -0.4445 90)
			(size 0.1524 0.1524)
			(layers "F.Cu" "F.Mask" "F.Paste")
			(net "SW_HDD_P33")
			(options
				(clearance outline)
				(anchor circle)
			)
			(primitives
				(gr_poly
					(pts
						(arc
							(start 0.3048 -0.2032)
							(mid 0.275042 -0.275042)
							(end 0.2032 -0.3048)
						)
						(arc
							(start -0.2032 -0.3048)
							(mid -0.275042 -0.275042)
							(end -0.3048 -0.2032)
						)
						(arc
							(start -0.3048 0.2032)
							(mid -0.275042 0.275042)
							(end -0.2032 0.3048)
						)
						(arc
							(start 0.2032 0.3048)
							(mid 0.275042 0.275042)
							(end 0.3048 0.2032)
						)
					)
					(width 0)
					(fill yes)
				)
			)
		)
		(pad "2" smd custom
			(at 0 0.4445 90)
			(size 0.1524 0.1524)
			(layers "F.Cu" "F.Mask" "F.Paste")
			(net "GND")
			(options
				(clearance outline)
				(anchor circle)
			)
			(primitives
				(gr_poly
					(pts
						(arc
							(start 0.3048 -0.2032)
							(mid 0.275042 -0.275042)
							(end 0.2032 -0.3048)
						)
						(arc
							(start -0.2032 -0.3048)
							(mid -0.275042 -0.275042)
							(end -0.3048 -0.2032)
						)
						(arc
							(start -0.3048 0.2032)
							(mid -0.275042 0.275042)
							(end -0.2032 0.3048)
						)
						(arc
							(start 0.2032 0.3048)
							(mid 0.275042 0.275042)
							(end 0.3048 0.2032)
						)
					)
					(width 0)
					(fill yes)
				)
			)
		)
	)
	(footprint ""
		(layer "F.Cu")
		(at 312.9534 -340.812882 180)
		(property "Reference" "R159"
			(at 0 0 180)
			(layer "F.SilkS")
			(hide yes)
			(effects
				(font
					(size 1.27 1.27)
				)
			)
		)
		(property "Value" "4K7R2F-GP"
			(at 0.064008 -3.993896 180)
			(unlocked yes)
			(layer "F.Fab")
			(hide yes)
			(effects
				(font
					(size 1.016 1.016)
					(thickness 0.1524)
				)
			)
		)
		(property "Device Type" "R402H16"
			(at 0.064008 -5.517896 180)
			(unlocked yes)
			(layer "F.Fab")
			(hide yes)
			(effects
				(font
					(size 1.016 1.016)
					(thickness 0.1524)
				)
			)
		)
		(duplicate_pad_numbers_are_jumpers no)
		(fp_line
			(start 0.508 -0.9398)
			(end -0.508 -0.9398)
			(stroke
				(width 0.1524)
				(type default)
			)
			(layer "F.SilkS")
		)
		(fp_line
			(start -0.508 -0.9398)
			(end -0.508 0.9398)
			(stroke
				(width 0.1524)
				(type default)
			)
			(layer "F.SilkS")
		)
		(fp_rect
			(start -0.508 0.9398)
			(end 0.508 -0.9398)
			(stroke
				(width 0)
				(type default)
			)
			(fill no)
			(layer "F.CrtYd")
		)
		(fp_rect
			(start -0.508 0.9398)
			(end 0.508 -0.9398)
			(stroke
				(width 0)
				(type default)
			)
			(fill no)
			(layer "F.Fab")
		)
		(pad "1" smd custom
			(at 0 -0.4445 180)
			(size 0.1397 0.1397)
			(layers "F.Cu" "F.Mask" "F.Paste")
			(net "THERMHOT#_D")
			(options
				(clearance outline)
				(anchor circle)
			)
			(primitives
				(gr_poly
					(pts
						(arc
							(start -0.1778 -0.2794)
							(mid -0.249642 -0.249642)
							(end -0.2794 -0.1778)
						)
						(arc
							(start -0.2794 0.1778)
							(mid -0.249642 0.249642)
							(end -0.1778 0.2794)
						)
						(arc
							(start 0.1778 0.2794)
							(mid 0.249642 0.249642)
							(end 0.2794 0.1778)
						)
						(arc
							(start 0.2794 -0.1778)
							(mid 0.249642 -0.249642)
							(end 0.1778 -0.2794)
						)
					)
					(width 0)
					(fill yes)
				)
			)
		)
		(pad "2" smd custom
			(at 0 0.4445 180)
			(size 0.1397 0.1397)
			(layers "F.Cu" "F.Mask" "F.Paste")
			(net "GND")
			(options
				(clearance outline)
				(anchor circle)
			)
			(primitives
				(gr_poly
					(pts
						(arc
							(start -0.1778 -0.2794)
							(mid -0.249642 -0.249642)
							(end -0.2794 -0.1778)
						)
						(arc
							(start -0.2794 0.1778)
							(mid -0.249642 0.249642)
							(end -0.1778 0.2794)
						)
						(arc
							(start 0.1778 0.2794)
							(mid 0.249642 0.249642)
							(end 0.2794 0.1778)
						)
						(arc
							(start 0.2794 -0.1778)
							(mid 0.249642 -0.249642)
							(end 0.1778 -0.2794)
						)
					)
					(width 0)
					(fill yes)
				)
			)
		)
	)
	(footprint ""
		(layer "F.Cu")
		(at 353.3648 -31.6484)
		(property "Reference" "C440"
			(at 0 0 0)
			(layer "F.SilkS")
			(hide yes)
			(effects
				(font
					(size 1.27 1.27)
				)
			)
		)
		(property "Value" "SCD01U50V2KX-1GP"
			(at 1.1811 -2.7051 0)
			(unlocked yes)
			(layer "F.Fab")
			(hide yes)
			(effects
				(font
					(size 1.016 1.016)
					(thickness 0.1524)
				)
			)
		)
		(property "Device Type" "C402H22"
			(at 1.1811 -4.2291 0)
			(unlocked yes)
			(layer "F.Fab")
			(hide yes)
			(effects
				(font
					(size 1.016 1.016)
					(thickness 0.1524)
				)
			)
		)
		(duplicate_pad_numbers_are_jumpers no)
		(fp_rect
			(start -0.4318 0.9525)
			(end 0.4318 -0.9525)
			(stroke
				(width 0)
				(type default)
			)
			(fill no)
			(layer "F.CrtYd")
		)
		(fp_rect
			(start -0.4318 0.9525)
			(end 0.4318 -0.9525)
			(stroke
				(width 0)
				(type default)
			)
			(fill no)
			(layer "F.Fab")
		)
		(pad "1" smd custom
			(at 0 -0.4445)
			(size 0.1524 0.1524)
			(layers "F.Cu" "F.Mask" "F.Paste")
			(net "HDD_PRSNT_31")
			(options
				(clearance outline)
				(anchor circle)
			)
			(primitives
				(gr_poly
					(pts
						(arc
							(start 0.3048 -0.2032)
							(mid 0.275042 -0.275042)
							(end 0.2032 -0.3048)
						)
						(arc
							(start -0.2032 -0.3048)
							(mid -0.275042 -0.275042)
							(end -0.3048 -0.2032)
						)
						(arc
							(start -0.3048 0.2032)
							(mid -0.275042 0.275042)
							(end -0.2032 0.3048)
						)
						(arc
							(start 0.2032 0.3048)
							(mid 0.275042 0.275042)
							(end 0.3048 0.2032)
						)
					)
					(width 0)
					(fill yes)
				)
			)
		)
		(pad "2" smd custom
			(at 0 0.4445)
			(size 0.1524 0.1524)
			(layers "F.Cu" "F.Mask" "F.Paste")
			(net "GND")
			(options
				(clearance outline)
				(anchor circle)
			)
			(primitives
				(gr_poly
					(pts
						(arc
							(start 0.3048 -0.2032)
							(mid 0.275042 -0.275042)
							(end 0.2032 -0.3048)
						)
						(arc
							(start -0.2032 -0.3048)
							(mid -0.275042 -0.275042)
							(end -0.3048 -0.2032)
						)
						(arc
							(start -0.3048 0.2032)
							(mid -0.275042 0.275042)
							(end -0.2032 0.3048)
						)
						(arc
							(start 0.2032 0.3048)
							(mid 0.275042 0.275042)
							(end 0.3048 0.2032)
						)
					)
					(width 0)
					(fill yes)
				)
			)
		)
	)
	(footprint ""
		(layer "F.Cu")
		(at 29.530802 -231.52735)
		(property "Reference" "TP202"
			(at 0 0 0)
			(layer "F.SilkS")
			(hide yes)
			(effects
				(font
					(size 1.27 1.27)
				)
			)
		)
		(property "Value" "*"
			(at -0.0508 -1.6764 0)
			(unlocked yes)
			(layer "F.Fab")
			(hide yes)
			(effects
				(font
					(size 1.016 1.016)
					(thickness 0.1524)
				)
			)
		)
		(property "Device Type" "TPAD32"
			(at -0.0508 -3.2004 0)
			(unlocked yes)
			(layer "F.Fab")
			(hide yes)
			(effects
				(font
					(size 1.016 1.016)
					(thickness 0.1524)
				)
			)
		)
		(duplicate_pad_numbers_are_jumpers no)
		(fp_poly
			(pts
				(arc
					(start 0.4064 0)
					(mid -0.4064 0)
					(end 0.4064 0)
				)
			)
			(stroke
				(width 0)
				(type default)
			)
			(fill no)
			(layer "F.CrtYd")
		)
		(fp_poly
			(pts
				(arc
					(start 0.7112 0)
					(mid -0.7112 0)
					(end 0.7112 0)
				)
			)
			(stroke
				(width 0)
				(type default)
			)
			(fill no)
			(layer "F.Fab")
		)
		(pad "1" smd circle
			(at 0 0)
			(size 0.8128 0.8128)
			(layers "F.Cu" "F.Mask" "F.Paste")
			(net "P5V_B_1_PGOOD")
		)
	)
	(footprint ""
		(layer "F.Cu")
		(at 434.880004 -360.2355 180)
		(property "Reference" "C404"
			(at 0 0 180)
			(layer "F.SilkS")
			(hide yes)
			(effects
				(font
					(size 1.27 1.27)
				)
			)
		)
		(property "Value" "SCD033U25V2KX-GP"
			(at 1.1811 -2.7051 180)
			(unlocked yes)
			(layer "F.Fab")
			(hide yes)
			(effects
				(font
					(size 1.016 1.016)
					(thickness 0.1524)
				)
			)
		)
		(property "Device Type" "C402H22"
			(at 1.1811 -4.2291 180)
			(unlocked yes)
			(layer "F.Fab")
			(hide yes)
			(effects
				(font
					(size 1.016 1.016)
					(thickness 0.1524)
				)
			)
		)
		(duplicate_pad_numbers_are_jumpers no)
		(fp_rect
			(start -0.4318 0.9525)
			(end 0.4318 -0.9525)
			(stroke
				(width 0)
				(type default)
			)
			(fill no)
			(layer "F.CrtYd")
		)
		(fp_rect
			(start -0.4318 0.9525)
			(end 0.4318 -0.9525)
			(stroke
				(width 0)
				(type default)
			)
			(fill no)
			(layer "F.Fab")
		)
		(pad "1" smd custom
			(at 0 -0.4445 180)
			(size 0.1524 0.1524)
			(layers "F.Cu" "F.Mask" "F.Paste")
			(net "GATE_FAN3_R")
			(options
				(clearance outline)
				(anchor circle)
			)
			(primitives
				(gr_poly
					(pts
						(arc
							(start 0.3048 -0.2032)
							(mid 0.275042 -0.275042)
							(end 0.2032 -0.3048)
						)
						(arc
							(start -0.2032 -0.3048)
							(mid -0.275042 -0.275042)
							(end -0.3048 -0.2032)
						)
						(arc
							(start -0.3048 0.2032)
							(mid -0.275042 0.275042)
							(end -0.2032 0.3048)
						)
						(arc
							(start 0.2032 0.3048)
							(mid 0.275042 0.275042)
							(end 0.3048 0.2032)
						)
					)
					(width 0)
					(fill yes)
				)
			)
		)
		(pad "2" smd custom
			(at 0 0.4445 180)
			(size 0.1524 0.1524)
			(layers "F.Cu" "F.Mask" "F.Paste")
			(net "P12V_IN")
			(options
				(clearance outline)
				(anchor circle)
			)
			(primitives
				(gr_poly
					(pts
						(arc
							(start 0.3048 -0.2032)
							(mid 0.275042 -0.275042)
							(end 0.2032 -0.3048)
						)
						(arc
							(start -0.2032 -0.3048)
							(mid -0.275042 -0.275042)
							(end -0.3048 -0.2032)
						)
						(arc
							(start -0.3048 0.2032)
							(mid -0.275042 0.275042)
							(end -0.2032 0.3048)
						)
						(arc
							(start 0.2032 0.3048)
							(mid 0.275042 0.275042)
							(end 0.3048 0.2032)
						)
					)
					(width 0)
					(fill yes)
				)
			)
		)
	)
	(footprint ""
		(layer "F.Cu")
		(at 286.032448 -347.541342)
		(property "Reference" "R1078"
			(at 0 0 0)
			(layer "F.SilkS")
			(hide yes)
			(effects
				(font
					(size 1.27 1.27)
				)
			)
		)
		(property "Value" "0R2J-2-GP"
			(at 0.064008 -3.993896 0)
			(unlocked yes)
			(layer "F.Fab")
			(hide yes)
			(effects
				(font
					(size 1.016 1.016)
					(thickness 0.1524)
				)
			)
		)
		(property "Device Type" "R402H16"
			(at 0.064008 -5.517896 0)
			(unlocked yes)
			(layer "F.Fab")
			(hide yes)
			(effects
				(font
					(size 1.016 1.016)
					(thickness 0.1524)
				)
			)
		)
		(duplicate_pad_numbers_are_jumpers no)
		(fp_line
			(start -0.508 -0.9398)
			(end -0.508 0.9398)
			(stroke
				(width 0.1524)
				(type default)
			)
			(layer "F.SilkS")
		)
		(fp_line
			(start 0.508 -0.9398)
			(end -0.508 -0.9398)
			(stroke
				(width 0.1524)
				(type default)
			)
			(layer "F.SilkS")
		)
		(fp_rect
			(start -0.508 0.9398)
			(end 0.508 -0.9398)
			(stroke
				(width 0)
				(type default)
			)
			(fill no)
			(layer "F.CrtYd")
		)
		(fp_rect
			(start -0.508 0.9398)
			(end 0.508 -0.9398)
			(stroke
				(width 0)
				(type default)
			)
			(fill no)
			(layer "F.Fab")
		)
		(pad "1" smd custom
			(at 0 -0.4445)
			(size 0.1397 0.1397)
			(layers "F.Cu" "F.Mask" "F.Paste")
			(net "MAX31790_B_ADD1")
			(options
				(clearance outline)
				(anchor circle)
			)
			(primitives
				(gr_poly
					(pts
						(arc
							(start -0.1778 -0.2794)
							(mid -0.249642 -0.249642)
							(end -0.2794 -0.1778)
						)
						(arc
							(start -0.2794 0.1778)
							(mid -0.249642 0.249642)
							(end -0.1778 0.2794)
						)
						(arc
							(start 0.1778 0.2794)
							(mid 0.249642 0.249642)
							(end 0.2794 0.1778)
						)
						(arc
							(start 0.2794 -0.1778)
							(mid 0.249642 -0.249642)
							(end 0.1778 -0.2794)
						)
					)
					(width 0)
					(fill yes)
				)
			)
		)
		(pad "2" smd custom
			(at 0 0.4445)
			(size 0.1397 0.1397)
			(layers "F.Cu" "F.Mask" "F.Paste")
			(net "GND")
			(options
				(clearance outline)
				(anchor circle)
			)
			(primitives
				(gr_poly
					(pts
						(arc
							(start -0.1778 -0.2794)
							(mid -0.249642 -0.249642)
							(end -0.2794 -0.1778)
						)
						(arc
							(start -0.2794 0.1778)
							(mid -0.249642 0.249642)
							(end -0.1778 0.2794)
						)
						(arc
							(start 0.1778 0.2794)
							(mid 0.249642 0.249642)
							(end 0.2794 0.1778)
						)
						(arc
							(start 0.2794 -0.1778)
							(mid 0.249642 -0.249642)
							(end 0.1778 -0.2794)
						)
					)
					(width 0)
					(fill yes)
				)
			)
		)
	)
	(footprint ""
		(layer "F.Cu")
		(at 174.117 -214.249)
		(property "Reference" "R285"
			(at 0 0 0)
			(layer "F.SilkS")
			(hide yes)
			(effects
				(font
					(size 1.27 1.27)
				)
			)
		)
		(property "Value" "91R3F-1-GP"
			(at -0.0254 -2.5146 0)
			(unlocked yes)
			(layer "F.Fab")
			(hide yes)
			(effects
				(font
					(size 1.016 1.016)
					(thickness 0.1524)
				)
			)
		)
		(property "Device Type" "R603H22"
			(at -0.0254 -4.0386 0)
			(unlocked yes)
			(layer "F.Fab")
			(hide yes)
			(effects
				(font
					(size 1.016 1.016)
					(thickness 0.1524)
				)
			)
		)
		(duplicate_pad_numbers_are_jumpers no)
		(fp_line
			(start -0.4826 0)
			(end -0.2032 0)
			(stroke
				(width 0.2032)
				(type default)
			)
			(layer "F.SilkS")
		)
		(fp_line
			(start 0.2032 0)
			(end 0.4826 0)
			(stroke
				(width 0.2032)
				(type default)
			)
			(layer "F.SilkS")
		)
		(fp_rect
			(start -0.5842 1.3335)
			(end 0.5842 -1.3335)
			(stroke
				(width 0)
				(type default)
			)
			(fill no)
			(layer "F.CrtYd")
		)
		(fp_rect
			(start -0.5842 1.3335)
			(end 0.5842 -1.3335)
			(stroke
				(width 0)
				(type default)
			)
			(fill no)
			(layer "F.Fab")
		)
		(pad "1" smd custom
			(at 0 -0.762)
			(size 0.2159 0.2159)
			(layers "F.Cu" "F.Mask" "F.Paste")
			(net "P5V_B_1")
			(options
				(clearance outline)
				(anchor circle)
			)
			(primitives
				(gr_poly
					(pts
						(arc
							(start -0.3302 -0.4318)
							(mid -0.402042 -0.402042)
							(end -0.4318 -0.3302)
						)
						(arc
							(start -0.4318 0.3302)
							(mid -0.402042 0.402042)
							(end -0.3302 0.4318)
						)
						(arc
							(start 0.3302 0.4318)
							(mid 0.402042 0.402042)
							(end 0.4318 0.3302)
						)
						(arc
							(start 0.4318 -0.3302)
							(mid 0.402042 -0.402042)
							(end 0.3302 -0.4318)
						)
					)
					(width 0)
					(fill yes)
				)
			)
		)
		(pad "2" smd custom
			(at 0 0.762)
			(size 0.2159 0.2159)
			(layers "F.Cu" "F.Mask" "F.Paste")
			(net "DRV_ACT_5")
			(options
				(clearance outline)
				(anchor circle)
			)
			(primitives
				(gr_poly
					(pts
						(arc
							(start -0.3302 -0.4318)
							(mid -0.402042 -0.402042)
							(end -0.4318 -0.3302)
						)
						(arc
							(start -0.4318 0.3302)
							(mid -0.402042 0.402042)
							(end -0.3302 0.4318)
						)
						(arc
							(start 0.3302 0.4318)
							(mid 0.402042 0.402042)
							(end 0.4318 0.3302)
						)
						(arc
							(start 0.4318 -0.3302)
							(mid 0.402042 -0.402042)
							(end 0.3302 -0.4318)
						)
					)
					(width 0)
					(fill yes)
				)
			)
		)
	)
	(footprint ""
		(layer "F.Cu")
		(at 54.737 -19.177)
		(property "Reference" "R653"
			(at 0 0 0)
			(layer "F.SilkS")
			(hide yes)
			(effects
				(font
					(size 1.27 1.27)
				)
			)
		)
		(property "Value" "1KR2F-3-GP"
			(at 0.064008 -3.993896 0)
			(unlocked yes)
			(layer "F.Fab")
			(hide yes)
			(effects
				(font
					(size 1.016 1.016)
					(thickness 0.1524)
				)
			)
		)
		(property "Device Type" "R402H16"
			(at 0.064008 -5.517896 0)
			(unlocked yes)
			(layer "F.Fab")
			(hide yes)
			(effects
				(font
					(size 1.016 1.016)
					(thickness 0.1524)
				)
			)
		)
		(duplicate_pad_numbers_are_jumpers no)
		(fp_line
			(start -0.508 -0.9398)
			(end -0.508 0.9398)
			(stroke
				(width 0.1524)
				(type default)
			)
			(layer "F.SilkS")
		)
		(fp_line
			(start 0.508 -0.9398)
			(end -0.508 -0.9398)
			(stroke
				(width 0.1524)
				(type default)
			)
			(layer "F.SilkS")
		)
		(fp_rect
			(start -0.508 0.9398)
			(end 0.508 -0.9398)
			(stroke
				(width 0)
				(type default)
			)
			(fill no)
			(layer "F.CrtYd")
		)
		(fp_rect
			(start -0.508 0.9398)
			(end 0.508 -0.9398)
			(stroke
				(width 0)
				(type default)
			)
			(fill no)
			(layer "F.Fab")
		)
		(pad "1" smd custom
			(at 0 -0.4445)
			(size 0.1397 0.1397)
			(layers "F.Cu" "F.Mask" "F.Paste")
			(net "P3V3_STBY_B")
			(options
				(clearance outline)
				(anchor circle)
			)
			(primitives
				(gr_poly
					(pts
						(arc
							(start -0.1778 -0.2794)
							(mid -0.249642 -0.249642)
							(end -0.2794 -0.1778)
						)
						(arc
							(start -0.2794 0.1778)
							(mid -0.249642 0.249642)
							(end -0.1778 0.2794)
						)
						(arc
							(start 0.1778 0.2794)
							(mid 0.249642 0.249642)
							(end 0.2794 0.1778)
						)
						(arc
							(start 0.2794 -0.1778)
							(mid 0.249642 -0.249642)
							(end 0.1778 -0.2794)
						)
					)
					(width 0)
					(fill yes)
				)
			)
		)
		(pad "2" smd custom
			(at 0 0.4445)
			(size 0.1397 0.1397)
			(layers "F.Cu" "F.Mask" "F.Paste")
			(net "SW_PWR_R_HDD25")
			(options
				(clearance outline)
				(anchor circle)
			)
			(primitives
				(gr_poly
					(pts
						(arc
							(start -0.1778 -0.2794)
							(mid -0.249642 -0.249642)
							(end -0.2794 -0.1778)
						)
						(arc
							(start -0.2794 0.1778)
							(mid -0.249642 0.249642)
							(end -0.1778 0.2794)
						)
						(arc
							(start 0.1778 0.2794)
							(mid 0.249642 0.249642)
							(end 0.2794 0.1778)
						)
						(arc
							(start 0.2794 -0.1778)
							(mid 0.249642 -0.249642)
							(end 0.1778 -0.2794)
						)
					)
					(width 0)
					(fill yes)
				)
			)
		)
	)
	(footprint ""
		(layer "F.Cu")
		(at 14.5542 -214.757 180)
		(property "Reference" "Q219"
			(at 0 0 180)
			(layer "F.SilkS")
			(hide yes)
			(effects
				(font
					(size 1.27 1.27)
				)
			)
		)
		(property "Value" "2N7002K-2-GP"
			(at 0.127 -8.9662 180)
			(unlocked yes)
			(layer "F.Fab")
			(hide yes)
			(effects
				(font
					(size 1.016 1.016)
					(thickness 0.1524)
				)
			)
		)
		(property "Device Type" "SOT23DGS2D4H44"
			(at 0.127 -10.4902 180)
			(unlocked yes)
			(layer "F.Fab")
			(hide yes)
			(effects
				(font
					(size 1.016 1.016)
					(thickness 0.1524)
				)
			)
		)
		(duplicate_pad_numbers_are_jumpers no)
		(fp_line
			(start 1.651 1.778)
			(end 1.651 -1.778)
			(stroke
				(width 0.1524)
				(type default)
			)
			(layer "F.SilkS")
		)
		(fp_line
			(start 1.651 -1.778)
			(end -1.651 -1.778)
			(stroke
				(width 0.1524)
				(type default)
			)
			(layer "F.SilkS")
		)
		(fp_line
			(start -1.651 1.778)
			(end 1.651 1.778)
			(stroke
				(width 0.1524)
				(type default)
			)
			(layer "F.SilkS")
		)
		(fp_line
			(start -1.651 -1.778)
			(end -1.651 1.778)
			(stroke
				(width 0.1524)
				(type default)
			)
			(layer "F.SilkS")
		)
		(fp_poly
			(pts
				(xy -1.778 1.8796) (xy -1.778 -1.8796) (xy 1.778 -1.8796) (xy 1.778 1.8796)
			)
			(stroke
				(width 0)
				(type default)
			)
			(fill no)
			(layer "F.CrtYd")
		)
		(fp_poly
			(pts
				(xy -1.778 1.8796) (xy -1.778 -1.8796) (xy 1.778 -1.8796) (xy 1.778 1.8796)
			)
			(stroke
				(width 0)
				(type default)
			)
			(fill no)
			(layer "F.Fab")
		)
		(pad "D" smd custom
			(at 0 -0.9525 180)
			(size 0.1905 0.1905)
			(layers "F.Cu" "F.Mask" "F.Paste")
			(net "FLT_HDD0_N")
			(options
				(clearance outline)
				(anchor circle)
			)
			(primitives
				(gr_poly
					(pts
						(arc
							(start -0.1778 0.5715)
							(mid -0.321484 0.511984)
							(end -0.381 0.3683)
						)
						(arc
							(start -0.381 -0.3683)
							(mid -0.321484 -0.511984)
							(end -0.1778 -0.5715)
						)
						(arc
							(start 0.1778 -0.5715)
							(mid 0.321484 -0.511984)
							(end 0.381 -0.3683)
						)
						(arc
							(start 0.381 0.3683)
							(mid 0.321484 0.511984)
							(end 0.1778 0.5715)
						)
					)
					(width 0)
					(fill yes)
				)
			)
		)
		(pad "G" smd custom
			(at -0.98425 0.9525 180)
			(size 0.1905 0.1905)
			(layers "F.Cu" "F.Mask" "F.Paste")
			(net "DRIVE_B_0_FLT_LED")
			(options
				(clearance outline)
				(anchor circle)
			)
			(primitives
				(gr_poly
					(pts
						(arc
							(start -0.1778 0.5715)
							(mid -0.321484 0.511984)
							(end -0.381 0.3683)
						)
						(arc
							(start -0.381 -0.3683)
							(mid -0.321484 -0.511984)
							(end -0.1778 -0.5715)
						)
						(arc
							(start 0.1778 -0.5715)
							(mid 0.321484 -0.511984)
							(end 0.381 -0.3683)
						)
						(arc
							(start 0.381 0.3683)
							(mid 0.321484 0.511984)
							(end 0.1778 0.5715)
						)
					)
					(width 0)
					(fill yes)
				)
			)
		)
		(pad "S" smd custom
			(at 0.98425 0.9525 180)
			(size 0.1905 0.1905)
			(layers "F.Cu" "F.Mask" "F.Paste")
			(net "GND")
			(options
				(clearance outline)
				(anchor circle)
			)
			(primitives
				(gr_poly
					(pts
						(arc
							(start -0.1778 0.5715)
							(mid -0.321484 0.511984)
							(end -0.381 0.3683)
						)
						(arc
							(start -0.381 -0.3683)
							(mid -0.321484 -0.511984)
							(end -0.1778 -0.5715)
						)
						(arc
							(start 0.1778 -0.5715)
							(mid 0.321484 -0.511984)
							(end 0.381 -0.3683)
						)
						(arc
							(start 0.381 0.3683)
							(mid 0.321484 0.511984)
							(end 0.1778 0.5715)
						)
					)
					(width 0)
					(fill yes)
				)
			)
		)
	)
	(footprint ""
		(layer "F.Cu")
		(at 37.305996 -367.157 -90)
		(property "Reference" "D38"
			(at 0 0 270)
			(layer "F.SilkS")
			(hide yes)
			(effects
				(font
					(size 1.27 1.27)
				)
			)
		)
		(property "Value" "BAS16H-GP"
			(at 0 -5.5372 270)
			(unlocked yes)
			(layer "F.Fab")
			(hide yes)
			(effects
				(font
					(size 1.016 1.016)
					(thickness 0.1524)
				)
			)
		)
		(property "Device Type" "SOD123AKH48"
			(at 0 -7.0612 270)
			(unlocked yes)
			(layer "F.Fab")
			(hide yes)
			(effects
				(font
					(size 1.016 1.016)
					(thickness 0.1524)
				)
			)
		)
		(duplicate_pad_numbers_are_jumpers no)
		(fp_line
			(start 0.889 2.921)
			(end -0.889 2.921)
			(stroke
				(width 0.508)
				(type default)
			)
			(layer "F.SilkS")
		)
		(fp_line
			(start -1.016 2.667)
			(end 1.016 2.667)
			(stroke
				(width 0.1524)
				(type default)
			)
			(layer "F.SilkS")
		)
		(fp_line
			(start 1.016 2.667)
			(end 1.016 -2.667)
			(stroke
				(width 0.1524)
				(type default)
			)
			(layer "F.SilkS")
		)
		(fp_line
			(start -1.016 -2.667)
			(end -1.016 2.667)
			(stroke
				(width 0.1524)
				(type default)
			)
			(layer "F.SilkS")
		)
		(fp_line
			(start 1.016 -2.667)
			(end -1.016 -2.667)
			(stroke
				(width 0.1524)
				(type default)
			)
			(layer "F.SilkS")
		)
		(fp_rect
			(start -1.143 3.175)
			(end 1.143 -2.794)
			(stroke
				(width 0)
				(type default)
			)
			(fill no)
			(layer "F.CrtYd")
		)
		(fp_poly
			(pts
				(xy -1.143 -2.794) (xy 1.143 -2.794) (xy 1.143 3.175) (xy -1.143 3.175)
			)
			(stroke
				(width 0)
				(type default)
			)
			(fill no)
			(layer "F.Fab")
		)
		(pad "A" smd rect
			(at 0 -1.6891 270)
			(size 0.889 1.397)
			(layers "F.Cu" "F.Mask" "F.Paste")
			(net "FAN_0_TACH1")
		)
		(pad "K" smd rect
			(at 0 1.6891 270)
			(size 0.889 1.397)
			(layers "F.Cu" "F.Mask" "F.Paste")
			(net "P12V_IN")
		)
	)
	(footprint ""
		(layer "F.Cu")
		(at 143.002 -24.13 -90)
		(property "Reference" "C402"
			(at 0 0 270)
			(layer "F.SilkS")
			(hide yes)
			(effects
				(font
					(size 1.27 1.27)
				)
			)
		)
		(property "Value" "SCD033U25V2KX-GP"
			(at 1.1811 -2.7051 270)
			(unlocked yes)
			(layer "F.Fab")
			(hide yes)
			(effects
				(font
					(size 1.016 1.016)
					(thickness 0.1524)
				)
			)
		)
		(property "Device Type" "C402H22"
			(at 1.1811 -4.2291 270)
			(unlocked yes)
			(layer "F.Fab")
			(hide yes)
			(effects
				(font
					(size 1.016 1.016)
					(thickness 0.1524)
				)
			)
		)
		(duplicate_pad_numbers_are_jumpers no)
		(fp_rect
			(start -0.4318 0.9525)
			(end 0.4318 -0.9525)
			(stroke
				(width 0)
				(type default)
			)
			(fill no)
			(layer "F.CrtYd")
		)
		(fp_rect
			(start -0.4318 0.9525)
			(end 0.4318 -0.9525)
			(stroke
				(width 0)
				(type default)
			)
			(fill no)
			(layer "F.Fab")
		)
		(pad "1" smd custom
			(at 0 -0.4445 270)
			(size 0.1524 0.1524)
			(layers "F.Cu" "F.Mask" "F.Paste")
			(net "SW_HDD_P28")
			(options
				(clearance outline)
				(anchor circle)
			)
			(primitives
				(gr_poly
					(pts
						(arc
							(start 0.3048 -0.2032)
							(mid 0.275042 -0.275042)
							(end 0.2032 -0.3048)
						)
						(arc
							(start -0.2032 -0.3048)
							(mid -0.275042 -0.275042)
							(end -0.3048 -0.2032)
						)
						(arc
							(start -0.3048 0.2032)
							(mid -0.275042 0.275042)
							(end -0.2032 0.3048)
						)
						(arc
							(start 0.2032 0.3048)
							(mid 0.275042 0.275042)
							(end 0.3048 0.2032)
						)
					)
					(width 0)
					(fill yes)
				)
			)
		)
		(pad "2" smd custom
			(at 0 0.4445 270)
			(size 0.1524 0.1524)
			(layers "F.Cu" "F.Mask" "F.Paste")
			(net "GND")
			(options
				(clearance outline)
				(anchor circle)
			)
			(primitives
				(gr_poly
					(pts
						(arc
							(start 0.3048 -0.2032)
							(mid 0.275042 -0.275042)
							(end 0.2032 -0.3048)
						)
						(arc
							(start -0.2032 -0.3048)
							(mid -0.275042 -0.275042)
							(end -0.3048 -0.2032)
						)
						(arc
							(start -0.3048 0.2032)
							(mid -0.275042 0.275042)
							(end -0.2032 0.3048)
						)
						(arc
							(start 0.2032 0.3048)
							(mid 0.275042 0.275042)
							(end 0.3048 0.2032)
						)
					)
					(width 0)
					(fill yes)
				)
			)
		)
	)
	(footprint ""
		(layer "F.Cu")
		(at 425.228004 -367.157 -90)
		(property "Reference" "D44"
			(at 0 0 270)
			(layer "F.SilkS")
			(hide yes)
			(effects
				(font
					(size 1.27 1.27)
				)
			)
		)
		(property "Value" "BAS16H-GP"
			(at 0 -5.5372 270)
			(unlocked yes)
			(layer "F.Fab")
			(hide yes)
			(effects
				(font
					(size 1.016 1.016)
					(thickness 0.1524)
				)
			)
		)
		(property "Device Type" "SOD123AKH48"
			(at 0 -7.0612 270)
			(unlocked yes)
			(layer "F.Fab")
			(hide yes)
			(effects
				(font
					(size 1.016 1.016)
					(thickness 0.1524)
				)
			)
		)
		(duplicate_pad_numbers_are_jumpers no)
		(fp_line
			(start 0.889 2.921)
			(end -0.889 2.921)
			(stroke
				(width 0.508)
				(type default)
			)
			(layer "F.SilkS")
		)
		(fp_line
			(start -1.016 2.667)
			(end 1.016 2.667)
			(stroke
				(width 0.1524)
				(type default)
			)
			(layer "F.SilkS")
		)
		(fp_line
			(start 1.016 2.667)
			(end 1.016 -2.667)
			(stroke
				(width 0.1524)
				(type default)
			)
			(layer "F.SilkS")
		)
		(fp_line
			(start -1.016 -2.667)
			(end -1.016 2.667)
			(stroke
				(width 0.1524)
				(type default)
			)
			(layer "F.SilkS")
		)
		(fp_line
			(start 1.016 -2.667)
			(end -1.016 -2.667)
			(stroke
				(width 0.1524)
				(type default)
			)
			(layer "F.SilkS")
		)
		(fp_rect
			(start -1.143 3.175)
			(end 1.143 -2.794)
			(stroke
				(width 0)
				(type default)
			)
			(fill no)
			(layer "F.CrtYd")
		)
		(fp_poly
			(pts
				(xy -1.143 -2.794) (xy 1.143 -2.794) (xy 1.143 3.175) (xy -1.143 3.175)
			)
			(stroke
				(width 0)
				(type default)
			)
			(fill no)
			(layer "F.Fab")
		)
		(pad "A" smd rect
			(at 0 -1.6891 270)
			(size 0.889 1.397)
			(layers "F.Cu" "F.Mask" "F.Paste")
			(net "FAN_3_TACH1")
		)
		(pad "K" smd rect
			(at 0 1.6891 270)
			(size 0.889 1.397)
			(layers "F.Cu" "F.Mask" "F.Paste")
			(net "P12V_IN")
		)
	)
	(footprint ""
		(layer "F.Cu")
		(at 382.88595 -13.6271 180)
		(property "Reference" "VIA65"
			(at 0 0 180)
			(layer "F.SilkS")
			(hide yes)
			(effects
				(font
					(size 1.27 1.27)
				)
			)
		)
		(property "Value" "100OHM-8L-2D36MM-L18-GP"
			(at 3.8989 0.5715 180)
			(unlocked yes)
			(layer "F.Fab")
			(hide yes)
			(effects
				(font
					(size 1.016 1.016)
					(thickness 0.1524)
				)
			)
		)
		(property "Device Type" "VIA-PCIE-4P-414097"
			(at 3.8989 -0.9525 180)
			(unlocked yes)
			(layer "F.Fab")
			(hide yes)
			(effects
				(font
					(size 1.016 1.016)
					(thickness 0.1524)
				)
			)
		)
		(duplicate_pad_numbers_are_jumpers no)
		(fp_rect
			(start -2.0701 0.4826)
			(end 2.0701 -0.4826)
			(stroke
				(width 0)
				(type default)
			)
			(fill no)
			(layer "F.CrtYd")
		)
		(fp_rect
			(start -2.0701 0.4826)
			(end 2.0701 -0.4826)
			(stroke
				(width 0)
				(type default)
			)
			(fill no)
			(layer "F.Fab")
		)
		(pad "1" thru_hole circle
			(at -1.5875 0 180)
			(size 0.508 0.508)
			(drill 0.254)
			(layers "*.Cu" "*.Mask")
			(remove_unused_layers no)
			(net "GND")
			(clearance 0.2286)
			(thermal_gap 0.2286)
		)
		(pad "2" thru_hole circle
			(at -0.5715 0 180)
			(size 0.508 0.508)
			(drill 0.254)
			(layers "*.Cu" "*.Mask")
			(remove_unused_layers no)
			(net "PHY_SCC_B_TO_DRV_B_32_DP")
			(clearance 0.2286)
			(thermal_gap 0.2286)
		)
		(pad "3" thru_hole circle
			(at 0.5715 0 180)
			(size 0.508 0.508)
			(drill 0.254)
			(layers "*.Cu" "*.Mask")
			(remove_unused_layers no)
			(net "PHY_SCC_B_TO_DRV_B_32_DN")
			(clearance 0.2286)
			(thermal_gap 0.2286)
		)
		(pad "4" thru_hole circle
			(at 1.5875 0 180)
			(size 0.508 0.508)
			(drill 0.254)
			(layers "*.Cu" "*.Mask")
			(remove_unused_layers no)
			(net "GND")
			(clearance 0.2286)
			(thermal_gap 0.2286)
		)
	)
	(footprint ""
		(layer "F.Cu")
		(at 307.089048 -356.060756 90)
		(property "Reference" "R503"
			(at 0 0 90)
			(layer "F.SilkS")
			(hide yes)
			(effects
				(font
					(size 1.27 1.27)
				)
			)
		)
		(property "Value" "10KR2F-2-GP"
			(at 0.064008 -3.993896 90)
			(unlocked yes)
			(layer "F.Fab")
			(hide yes)
			(effects
				(font
					(size 1.016 1.016)
					(thickness 0.1524)
				)
			)
		)
		(property "Device Type" "R402H16"
			(at 0.064008 -5.517896 90)
			(unlocked yes)
			(layer "F.Fab")
			(hide yes)
			(effects
				(font
					(size 1.016 1.016)
					(thickness 0.1524)
				)
			)
		)
		(duplicate_pad_numbers_are_jumpers no)
		(fp_line
			(start 0.508 -0.9398)
			(end -0.508 -0.9398)
			(stroke
				(width 0.1524)
				(type default)
			)
			(layer "F.SilkS")
		)
		(fp_line
			(start -0.508 -0.9398)
			(end -0.508 0.9398)
			(stroke
				(width 0.1524)
				(type default)
			)
			(layer "F.SilkS")
		)
		(fp_rect
			(start -0.508 0.9398)
			(end 0.508 -0.9398)
			(stroke
				(width 0)
				(type default)
			)
			(fill no)
			(layer "F.CrtYd")
		)
		(fp_rect
			(start -0.508 0.9398)
			(end 0.508 -0.9398)
			(stroke
				(width 0)
				(type default)
			)
			(fill no)
			(layer "F.Fab")
		)
		(pad "1" smd custom
			(at 0 -0.4445 90)
			(size 0.1397 0.1397)
			(layers "F.Cu" "F.Mask" "F.Paste")
			(net "P3V3_IN")
			(options
				(clearance outline)
				(anchor circle)
			)
			(primitives
				(gr_poly
					(pts
						(arc
							(start -0.1778 -0.2794)
							(mid -0.249642 -0.249642)
							(end -0.2794 -0.1778)
						)
						(arc
							(start -0.2794 0.1778)
							(mid -0.249642 0.249642)
							(end -0.1778 0.2794)
						)
						(arc
							(start 0.1778 0.2794)
							(mid 0.249642 0.249642)
							(end 0.2794 0.1778)
						)
						(arc
							(start 0.2794 -0.1778)
							(mid 0.249642 -0.249642)
							(end 0.1778 -0.2794)
						)
					)
					(width 0)
					(fill yes)
				)
			)
		)
		(pad "2" smd custom
			(at 0 0.4445 90)
			(size 0.1397 0.1397)
			(layers "F.Cu" "F.Mask" "F.Paste")
			(net "FANTACH_B_OE_N")
			(options
				(clearance outline)
				(anchor circle)
			)
			(primitives
				(gr_poly
					(pts
						(arc
							(start -0.1778 -0.2794)
							(mid -0.249642 -0.249642)
							(end -0.2794 -0.1778)
						)
						(arc
							(start -0.2794 0.1778)
							(mid -0.249642 0.249642)
							(end -0.1778 0.2794)
						)
						(arc
							(start 0.1778 0.2794)
							(mid 0.249642 0.249642)
							(end 0.2794 0.1778)
						)
						(arc
							(start 0.2794 -0.1778)
							(mid 0.249642 -0.249642)
							(end 0.1778 -0.2794)
						)
					)
					(width 0)
					(fill yes)
				)
			)
		)
	)
	(footprint ""
		(layer "F.Cu")
		(at 420.200074 -143.91005 -90)
		(property "Reference" "HDDSAS21"
			(at 0 0 270)
			(layer "F.SilkS")
			(hide yes)
			(effects
				(font
					(size 1.27 1.27)
				)
			)
		)
		(property "Value" "SKT-SAS15P-14P-45-GP"
			(at -20.7645 -8.9789 270)
			(unlocked yes)
			(layer "F.Fab")
			(hide yes)
			(effects
				(font
					(size 1.016 1.016)
					(thickness 0.1524)
				)
			)
		)
		(property "Device Type" "10120818-001C-TRLF"
			(at -20.7645 -10.5029 270)
			(unlocked yes)
			(layer "F.Fab")
			(hide yes)
			(effects
				(font
					(size 1.016 1.016)
					(thickness 0.1524)
				)
			)
		)
		(duplicate_pad_numbers_are_jumpers no)
		(fp_line
			(start 1.651 4.2926)
			(end 1.651 3.0099)
			(stroke
				(width 0.1524)
				(type default)
			)
			(layer "F.SilkS")
		)
		(fp_line
			(start 8.509 4.2926)
			(end 1.651 4.2926)
			(stroke
				(width 0.1524)
				(type default)
			)
			(layer "F.SilkS")
		)
		(fp_line
			(start -23.4188 3.0099)
			(end -23.4188 -3.2512)
			(stroke
				(width 0.1524)
				(type default)
			)
			(layer "F.SilkS")
		)
		(fp_line
			(start 1.651 3.0099)
			(end -23.4188 3.0099)
			(stroke
				(width 0.1524)
				(type default)
			)
			(layer "F.SilkS")
		)
		(fp_line
			(start 8.509 3.0099)
			(end 8.509 4.2926)
			(stroke
				(width 0.1524)
				(type default)
			)
			(layer "F.SilkS")
		)
		(fp_line
			(start 23.4188 3.0099)
			(end 8.509 3.0099)
			(stroke
				(width 0.1524)
				(type default)
			)
			(layer "F.SilkS")
		)
		(fp_line
			(start -23.4188 -3.2512)
			(end 23.4188 -3.2512)
			(stroke
				(width 0.1524)
				(type default)
			)
			(layer "F.SilkS")
		)
		(fp_line
			(start 23.4188 -3.2512)
			(end 23.4188 3.0099)
			(stroke
				(width 0.1524)
				(type default)
			)
			(layer "F.SilkS")
		)
		(fp_line
			(start 15.5067 -3.3401)
			(end 16.2687 -3.3401)
			(stroke
				(width 0.3302)
				(type default)
			)
			(layer "F.SilkS")
		)
		(fp_poly
			(pts
				(xy 15.868904 -3.230372) (xy 16.503904 -3.865372) (xy 15.233904 -3.865372)
			)
			(stroke
				(width 0)
				(type default)
			)
			(fill yes)
			(layer "F.SilkS")
		)
		(fp_poly
			(pts
				(xy -22.8727 -2.7559) (xy 22.8727 -2.7559) (xy 22.8727 2.7559) (xy 8.255 2.7559) (xy 8.255 3.5179)
				(xy 1.905 3.5179) (xy 1.905 2.7559) (xy -22.8727 2.7559)
			)
			(stroke
				(width 0)
				(type default)
			)
			(fill no)
			(layer "F.CrtYd")
		)
		(fp_poly
			(pts
				(xy 1.397 4.5466) (xy 1.397 3.2639) (xy -23.6728 3.2639) (xy -23.6728 -3.5052) (xy 23.6728 -3.5052)
				(xy 23.6728 -0.00635) (xy 22.8727 -0.00635) (xy 22.8727 -2.7559) (xy -22.8727 -2.7559) (xy -22.8727 2.7559)
				(xy 1.905 2.7559) (xy 1.905 3.5179) (xy 8.255 3.5179) (xy 8.255 2.7559) (xy 22.8727 2.7559) (xy 22.8727 0.00635)
				(xy 23.6728 0.00635) (xy 23.6728 3.2639) (xy 8.763 3.2639) (xy 8.763 4.5466)
			)
			(stroke
				(width 0)
				(type default)
			)
			(fill no)
			(layer "F.CrtYd")
		)
		(fp_poly
			(pts
				(xy 1.397 4.5466) (xy 1.397 3.2639) (xy -23.6728 3.2639) (xy -23.6728 -3.5052) (xy 23.6728 -3.5052)
				(xy 23.6728 3.2639) (xy 8.763 3.2639) (xy 8.763 4.5466)
			)
			(stroke
				(width 0)
				(type default)
			)
			(fill no)
			(layer "F.Fab")
		)
		(pad "" np_thru_hole circle
			(at -18.874994 0 270)
			(size 0.254 0.254)
			(drill 1.3462)
			(layers "*.Cu" "*.Mask")
			(clearance 0.9017)
			(thermal_gap 0.9017)
		)
		(pad "" np_thru_hole circle
			(at 18.874994 0 270)
			(size 0.254 0.254)
			(drill 0.9398)
			(layers "*.Cu" "*.Mask")
			(clearance 0.6985)
			(thermal_gap 0.6985)
		)
		(pad "G1" smd rect
			(at 21.874988 0 270)
			(size 2.5908 2.5908)
			(layers "F.Cu" "F.Mask" "F.Paste")
			(net "GND")
		)
		(pad "G2" smd rect
			(at -21.874988 0 270)
			(size 2.5908 2.5908)
			(layers "F.Cu" "F.Mask" "F.Paste")
			(net "GND")
		)
		(pad "P1" smd rect
			(at 1.905 -1.82499 270)
			(size 0.6096 2.3622)
			(layers "F.Cu" "F.Mask" "F.Paste")
			(net "Net_1694")
		)
		(pad "P2" smd rect
			(at 0.635 -1.82499 270)
			(size 0.6096 2.3622)
			(layers "F.Cu" "F.Mask" "F.Paste")
			(net "Net_1695")
		)
		(pad "P3" smd rect
			(at -0.635 -1.82499 270)
			(size 0.6096 2.3622)
			(layers "F.Cu" "F.Mask" "F.Paste")
			(net "Net_1696")
		)
		(pad "P4" smd rect
			(at -1.905 -1.82499 270)
			(size 0.6096 2.3622)
			(layers "F.Cu" "F.Mask" "F.Paste")
			(net "GND")
		)
		(pad "P5" smd rect
			(at -3.175 -1.82499 270)
			(size 0.6096 2.3622)
			(layers "F.Cu" "F.Mask" "F.Paste")
			(net "HDD_PRSNT_21")
		)
		(pad "P6" smd rect
			(at -4.445 -1.82499 270)
			(size 0.6096 2.3622)
			(layers "F.Cu" "F.Mask" "F.Paste")
			(net "GND")
		)
		(pad "P7" smd rect
			(at -5.715 -1.82499 270)
			(size 0.6096 2.3622)
			(layers "F.Cu" "F.Mask" "F.Paste")
			(net "5V_PRE_21")
		)
		(pad "P8" smd rect
			(at -6.985 -1.82499 270)
			(size 0.6096 2.3622)
			(layers "F.Cu" "F.Mask" "F.Paste")
			(net "P5V_HDD21")
		)
		(pad "P9" smd rect
			(at -8.255 -1.82499 270)
			(size 0.6096 2.3622)
			(layers "F.Cu" "F.Mask" "F.Paste")
			(net "P5V_HDD21")
		)
		(pad "P10" smd rect
			(at -9.525 -1.82499 270)
			(size 0.6096 2.3622)
			(layers "F.Cu" "F.Mask" "F.Paste")
			(net "GND")
		)
		(pad "P11" smd rect
			(at -10.795 -1.82499 270)
			(size 0.6096 2.3622)
			(layers "F.Cu" "F.Mask" "F.Paste")
			(net "ACT_HDD_21")
		)
		(pad "P12" smd rect
			(at -12.065 -1.82499 270)
			(size 0.6096 2.3622)
			(layers "F.Cu" "F.Mask" "F.Paste")
			(net "GND")
		)
		(pad "P13" smd rect
			(at -13.335 -1.82499 270)
			(size 0.6096 2.3622)
			(layers "F.Cu" "F.Mask" "F.Paste")
			(net "12V_PRE_21")
		)
		(pad "P14" smd rect
			(at -14.605 -1.82499 270)
			(size 0.6096 2.3622)
			(layers "F.Cu" "F.Mask" "F.Paste")
			(net "P12V_HDD21")
		)
		(pad "P15" smd rect
			(at -15.875 -1.82499 270)
			(size 0.6096 2.3622)
			(layers "F.Cu" "F.Mask" "F.Paste")
			(net "P12V_HDD21")
		)
		(pad "S1" smd rect
			(at 15.875 -1.82499 270)
			(size 0.6096 2.3622)
			(layers "F.Cu" "F.Mask" "F.Paste")
			(net "GND")
		)
		(pad "S2" smd rect
			(at 14.605 -1.82499 270)
			(size 0.6096 2.3622)
			(layers "F.Cu" "F.Mask" "F.Paste")
			(net "SAS_HDD_RX_P21")
		)
		(pad "S3" smd rect
			(at 13.335 -1.82499 270)
			(size 0.6096 2.3622)
			(layers "F.Cu" "F.Mask" "F.Paste")
			(net "SAS_HDD_RX_N21")
		)
		(pad "S4" smd rect
			(at 12.065 -1.82499 270)
			(size 0.6096 2.3622)
			(layers "F.Cu" "F.Mask" "F.Paste")
			(net "GND")
		)
		(pad "S5" smd rect
			(at 10.795 -1.82499 270)
			(size 0.6096 2.3622)
			(layers "F.Cu" "F.Mask" "F.Paste")
			(net "PHY_DRV_B_TO_SCC_B_21_DN")
		)
		(pad "S6" smd rect
			(at 9.525 -1.82499 270)
			(size 0.6096 2.3622)
			(layers "F.Cu" "F.Mask" "F.Paste")
			(net "PHY_DRV_B_TO_SCC_B_21_DP")
		)
		(pad "S7" smd rect
			(at 8.255 -1.82499 270)
			(size 0.6096 2.3622)
			(layers "F.Cu" "F.Mask" "F.Paste")
			(net "GND")
		)
		(pad "S8" smd rect
			(at 7.480046 2.845054 270)
			(size 0.508 2.3622)
			(layers "F.Cu" "F.Mask" "F.Paste")
			(net "GND")
		)
		(pad "S9" smd rect
			(at 6.679946 2.845054 270)
			(size 0.508 2.3622)
			(layers "F.Cu" "F.Mask" "F.Paste")
			(net "Net_445")
		)
		(pad "S10" smd rect
			(at 5.8801 2.845054 270)
			(size 0.508 2.3622)
			(layers "F.Cu" "F.Mask" "F.Paste")
			(net "Net_337")
		)
		(pad "S11" smd rect
			(at 5.08 2.845054 270)
			(size 0.508 2.3622)
			(layers "F.Cu" "F.Mask" "F.Paste")
			(net "GND")
		)
		(pad "S12" smd rect
			(at 4.2799 2.845054 270)
			(size 0.508 2.3622)
			(layers "F.Cu" "F.Mask" "F.Paste")
			(net "Net_373")
		)
		(pad "S13" smd rect
			(at 3.480054 2.845054 270)
			(size 0.508 2.3622)
			(layers "F.Cu" "F.Mask" "F.Paste")
			(net "Net_409")
		)
		(pad "S14" smd rect
			(at 2.679954 2.845054 270)
			(size 0.508 2.3622)
			(layers "F.Cu" "F.Mask" "F.Paste")
			(net "GND")
		)
		(zone
			(layer "F.Cu")
			(hatch none 0.5)
			(connect_pads
				(clearance 0)
			)
			(min_thickness 0.25)
			(keepout
				(tracks allowed)
				(vias not_allowed)
				(pads allowed)
				(copperpour not_allowed)
				(footprints allowed)
			)
			(placement
				(enabled no)
				(sheetname "")
			)
			(fill
				(thermal_gap 0.5)
				(thermal_bridge_width 0.5)
				(island_removal_mode 0)
			)
			(polygon
				(pts
					(xy 423.857674 -160.64865) (xy 416.783774 -160.64865) (xy 416.783774 -167.58285) (xy 417.888674 -167.58285)
					(xy 417.888674 -163.46805) (xy 422.511474 -163.46805) (xy 422.511474 -167.58285) (xy 423.857674 -167.58285)
				)
			)
		)
		(zone
			(layer "F.Cu")
			(hatch none 0.5)
			(connect_pads
				(clearance 0)
			)
			(min_thickness 0.25)
			(keepout
				(tracks not_allowed)
				(vias allowed)
				(pads allowed)
				(copperpour not_allowed)
				(footprints allowed)
			)
			(placement
				(enabled no)
				(sheetname "")
			)
			(fill
				(thermal_gap 0.5)
				(thermal_bridge_width 0.5)
				(island_removal_mode 0)
			)
			(polygon
				(pts
					(xy 423.857674 -160.64865) (xy 416.783774 -160.64865) (xy 416.783774 -167.58285) (xy 417.888674 -167.58285)
					(xy 417.888674 -163.46805) (xy 422.511474 -163.46805) (xy 422.511474 -167.58285) (xy 423.857674 -167.58285)
				)
			)
		)
		(zone
			(layer "F.Cu")
			(hatch none 0.5)
			(connect_pads
				(clearance 0)
			)
			(min_thickness 0.25)
			(keepout
				(tracks not_allowed)
				(vias allowed)
				(pads allowed)
				(copperpour not_allowed)
				(footprints allowed)
			)
			(placement
				(enabled no)
				(sheetname "")
			)
			(fill
				(thermal_gap 0.5)
				(thermal_bridge_width 0.5)
				(island_removal_mode 0)
			)
			(polygon
				(pts
					(xy 423.857674 -127.17145) (xy 416.783774 -127.17145) (xy 416.783774 -120.23725) (xy 417.888674 -120.23725)
					(xy 417.888674 -124.35205) (xy 422.511474 -124.35205) (xy 422.511474 -120.23725) (xy 423.857674 -120.23725)
				)
			)
		)
		(zone
			(layer "F.Cu")
			(hatch none 0.5)
			(connect_pads
				(clearance 0)
			)
			(min_thickness 0.25)
			(keepout
				(tracks allowed)
				(vias not_allowed)
				(pads allowed)
				(copperpour not_allowed)
				(footprints allowed)
			)
			(placement
				(enabled no)
				(sheetname "")
			)
			(fill
				(thermal_gap 0.5)
				(thermal_bridge_width 0.5)
				(island_removal_mode 0)
			)
			(polygon
				(pts
					(xy 423.857674 -127.17145) (xy 416.783774 -127.17145) (xy 416.783774 -120.23725) (xy 417.888674 -120.23725)
					(xy 417.888674 -124.35205) (xy 422.511474 -124.35205) (xy 422.511474 -120.23725) (xy 423.857674 -120.23725)
				)
			)
		)
		(zone
			(layers "F.Cu" "B.Cu" "In1.Cu" "In2.Cu" "In3.Cu" "In4.Cu" "In5.Cu" "In6.Cu")
			(hatch none 0.5)
			(connect_pads
				(clearance 0)
			)
			(min_thickness 0.25)
			(keepout
				(tracks not_allowed)
				(vias allowed)
				(pads allowed)
				(copperpour not_allowed)
				(footprints allowed)
			)
			(placement
				(enabled no)
				(sheetname "")
			)
			(fill
				(thermal_gap 0.5)
				(thermal_bridge_width 0.5)
				(island_removal_mode 0)
			)
			(polygon
				(pts
					(arc
						(start 420.974774 -125.035056)
						(mid 419.425374 -125.035056)
						(end 420.974774 -125.035056)
					)
				)
			)
		)
		(zone
			(layers "F.Cu" "B.Cu" "In1.Cu" "In2.Cu" "In3.Cu" "In4.Cu" "In5.Cu" "In6.Cu")
			(hatch none 0.5)
			(connect_pads
				(clearance 0)
			)
			(min_thickness 0.25)
			(keepout
				(tracks not_allowed)
				(vias allowed)
				(pads allowed)
				(copperpour not_allowed)
				(footprints allowed)
			)
			(placement
				(enabled no)
				(sheetname "")
			)
			(fill
				(thermal_gap 0.5)
				(thermal_bridge_width 0.5)
				(island_removal_mode 0)
			)
			(polygon
				(pts
					(arc
						(start 421.177974 -162.785044)
						(mid 419.222174 -162.785044)
						(end 421.177974 -162.785044)
					)
				)
			)
		)
	)
	(footprint ""
		(layer "F.Cu")
		(at 141.478 -133.096 180)
		(property "Reference" "R454"
			(at 0 0 180)
			(layer "F.SilkS")
			(hide yes)
			(effects
				(font
					(size 1.27 1.27)
				)
			)
		)
		(property "Value" "200KR2F-L-GP"
			(at 0.064008 -3.993896 180)
			(unlocked yes)
			(layer "F.Fab")
			(hide yes)
			(effects
				(font
					(size 1.016 1.016)
					(thickness 0.1524)
				)
			)
		)
		(property "Device Type" "R402H16"
			(at 0.064008 -5.517896 180)
			(unlocked yes)
			(layer "F.Fab")
			(hide yes)
			(effects
				(font
					(size 1.016 1.016)
					(thickness 0.1524)
				)
			)
		)
		(duplicate_pad_numbers_are_jumpers no)
		(fp_line
			(start 0.508 -0.9398)
			(end -0.508 -0.9398)
			(stroke
				(width 0.1524)
				(type default)
			)
			(layer "F.SilkS")
		)
		(fp_line
			(start -0.508 -0.9398)
			(end -0.508 0.9398)
			(stroke
				(width 0.1524)
				(type default)
			)
			(layer "F.SilkS")
		)
		(fp_rect
			(start -0.508 0.9398)
			(end 0.508 -0.9398)
			(stroke
				(width 0)
				(type default)
			)
			(fill no)
			(layer "F.CrtYd")
		)
		(fp_rect
			(start -0.508 0.9398)
			(end 0.508 -0.9398)
			(stroke
				(width 0)
				(type default)
			)
			(fill no)
			(layer "F.Fab")
		)
		(pad "1" smd custom
			(at 0 -0.4445 180)
			(size 0.1397 0.1397)
			(layers "F.Cu" "F.Mask" "F.Paste")
			(net "SW_HDD_R16")
			(options
				(clearance outline)
				(anchor circle)
			)
			(primitives
				(gr_poly
					(pts
						(arc
							(start -0.1778 -0.2794)
							(mid -0.249642 -0.249642)
							(end -0.2794 -0.1778)
						)
						(arc
							(start -0.2794 0.1778)
							(mid -0.249642 0.249642)
							(end -0.1778 0.2794)
						)
						(arc
							(start 0.1778 0.2794)
							(mid 0.249642 0.249642)
							(end 0.2794 0.1778)
						)
						(arc
							(start 0.2794 -0.1778)
							(mid 0.249642 -0.249642)
							(end 0.1778 -0.2794)
						)
					)
					(width 0)
					(fill yes)
				)
			)
		)
		(pad "2" smd custom
			(at 0 0.4445 180)
			(size 0.1397 0.1397)
			(layers "F.Cu" "F.Mask" "F.Paste")
			(net "SW_HDD_N16")
			(options
				(clearance outline)
				(anchor circle)
			)
			(primitives
				(gr_poly
					(pts
						(arc
							(start -0.1778 -0.2794)
							(mid -0.249642 -0.249642)
							(end -0.2794 -0.1778)
						)
						(arc
							(start -0.2794 0.1778)
							(mid -0.249642 0.249642)
							(end -0.1778 0.2794)
						)
						(arc
							(start 0.1778 0.2794)
							(mid 0.249642 0.249642)
							(end 0.2794 0.1778)
						)
						(arc
							(start 0.2794 -0.1778)
							(mid 0.249642 -0.249642)
							(end 0.1778 -0.2794)
						)
					)
					(width 0)
					(fill yes)
				)
			)
		)
	)
	(footprint ""
		(layer "F.Cu")
		(at 460.4512 -9.7028 -90)
		(property "Reference" "TP3"
			(at 0 0 270)
			(layer "F.SilkS")
			(hide yes)
			(effects
				(font
					(size 1.27 1.27)
				)
			)
		)
		(property "Value" "*"
			(at -0.0508 -1.6764 270)
			(unlocked yes)
			(layer "F.Fab")
			(hide yes)
			(effects
				(font
					(size 1.016 1.016)
					(thickness 0.1524)
				)
			)
		)
		(property "Device Type" "TPAD32"
			(at -0.0508 -3.2004 270)
			(unlocked yes)
			(layer "F.Fab")
			(hide yes)
			(effects
				(font
					(size 1.016 1.016)
					(thickness 0.1524)
				)
			)
		)
		(duplicate_pad_numbers_are_jumpers no)
		(fp_poly
			(pts
				(arc
					(start 0 -0.4064)
					(mid 0 0.4064)
					(end 0 -0.4064)
				)
			)
			(stroke
				(width 0)
				(type default)
			)
			(fill no)
			(layer "F.CrtYd")
		)
		(fp_poly
			(pts
				(arc
					(start 0 -0.7112)
					(mid 0 0.7112)
					(end 0 -0.7112)
				)
			)
			(stroke
				(width 0)
				(type default)
			)
			(fill no)
			(layer "F.Fab")
		)
		(pad "1" smd circle
			(at 0 0 270)
			(size 0.8128 0.8128)
			(layers "F.Cu" "F.Mask" "F.Paste")
			(net "TEMP2_ALERT")
		)
	)
	(footprint ""
		(layer "F.Cu")
		(at 118.237 -14.605 90)
		(property "Reference" "R708"
			(at 0 0 90)
			(layer "F.SilkS")
			(hide yes)
			(effects
				(font
					(size 1.27 1.27)
				)
			)
		)
		(property "Value" "0R2J-2-GP"
			(at 0.064008 -3.993896 90)
			(unlocked yes)
			(layer "F.Fab")
			(hide yes)
			(effects
				(font
					(size 1.016 1.016)
					(thickness 0.1524)
				)
			)
		)
		(property "Device Type" "R402H16"
			(at 0.064008 -5.517896 90)
			(unlocked yes)
			(layer "F.Fab")
			(hide yes)
			(effects
				(font
					(size 1.016 1.016)
					(thickness 0.1524)
				)
			)
		)
		(duplicate_pad_numbers_are_jumpers no)
		(fp_line
			(start 0.508 -0.9398)
			(end -0.508 -0.9398)
			(stroke
				(width 0.1524)
				(type default)
			)
			(layer "F.SilkS")
		)
		(fp_line
			(start -0.508 -0.9398)
			(end -0.508 0.9398)
			(stroke
				(width 0.1524)
				(type default)
			)
			(layer "F.SilkS")
		)
		(fp_rect
			(start -0.508 0.9398)
			(end 0.508 -0.9398)
			(stroke
				(width 0)
				(type default)
			)
			(fill no)
			(layer "F.CrtYd")
		)
		(fp_rect
			(start -0.508 0.9398)
			(end 0.508 -0.9398)
			(stroke
				(width 0)
				(type default)
			)
			(fill no)
			(layer "F.Fab")
		)
		(pad "1" smd custom
			(at 0 -0.4445 90)
			(size 0.1397 0.1397)
			(layers "F.Cu" "F.Mask" "F.Paste")
			(net "SW_HDD_G27")
			(options
				(clearance outline)
				(anchor circle)
			)
			(primitives
				(gr_poly
					(pts
						(arc
							(start -0.1778 -0.2794)
							(mid -0.249642 -0.249642)
							(end -0.2794 -0.1778)
						)
						(arc
							(start -0.2794 0.1778)
							(mid -0.249642 0.249642)
							(end -0.1778 0.2794)
						)
						(arc
							(start 0.1778 0.2794)
							(mid 0.249642 0.249642)
							(end 0.2794 0.1778)
						)
						(arc
							(start 0.2794 -0.1778)
							(mid 0.249642 -0.249642)
							(end 0.1778 -0.2794)
						)
					)
					(width 0)
					(fill yes)
				)
			)
		)
		(pad "2" smd custom
			(at 0 0.4445 90)
			(size 0.1397 0.1397)
			(layers "F.Cu" "F.Mask" "F.Paste")
			(net "SW_HDD_R27")
			(options
				(clearance outline)
				(anchor circle)
			)
			(primitives
				(gr_poly
					(pts
						(arc
							(start -0.1778 -0.2794)
							(mid -0.249642 -0.249642)
							(end -0.2794 -0.1778)
						)
						(arc
							(start -0.2794 0.1778)
							(mid -0.249642 0.249642)
							(end -0.1778 0.2794)
						)
						(arc
							(start 0.1778 0.2794)
							(mid 0.249642 0.249642)
							(end 0.2794 0.1778)
						)
						(arc
							(start 0.2794 -0.1778)
							(mid 0.249642 -0.249642)
							(end 0.1778 -0.2794)
						)
					)
					(width 0)
					(fill yes)
				)
			)
		)
	)
	(footprint ""
		(layer "F.Cu")
		(at 479.384614 -14.660626 -90)
		(property "Reference" "C484"
			(at 0 0 270)
			(layer "F.SilkS")
			(hide yes)
			(effects
				(font
					(size 1.27 1.27)
				)
			)
		)
		(property "Value" "SCD01U16V1KX-GP"
			(at -2.8321 -1.7399 270)
			(unlocked yes)
			(layer "F.Fab")
			(hide yes)
			(effects
				(font
					(size 1.016 1.016)
					(thickness 0.1524)
				)
			)
		)
		(property "Device Type" "C0201H13"
			(at -2.8321 -3.2639 270)
			(unlocked yes)
			(layer "F.Fab")
			(hide yes)
			(effects
				(font
					(size 1.016 1.016)
					(thickness 0.1524)
				)
			)
		)
		(duplicate_pad_numbers_are_jumpers no)
		(fp_rect
			(start -0.2794 0.6477)
			(end 0.2794 -0.6477)
			(stroke
				(width 0)
				(type default)
			)
			(fill no)
			(layer "F.CrtYd")
		)
		(fp_rect
			(start -0.2794 0.6477)
			(end 0.2794 -0.6477)
			(stroke
				(width 0)
				(type default)
			)
			(fill no)
			(layer "F.Fab")
		)
		(pad "1" smd custom
			(at 0 -0.2794 270)
			(size 0.0762 0.0762)
			(layers "F.Cu" "F.Mask" "F.Paste")
			(net "SAS_HDD_RX_P35")
			(options
				(clearance outline)
				(anchor circle)
			)
			(primitives
				(gr_poly
					(pts
						(arc
							(start 0.1524 -0.127)
							(mid 0.137521 -0.162921)
							(end 0.1016 -0.1778)
						)
						(arc
							(start -0.1016 -0.1778)
							(mid -0.137521 -0.162921)
							(end -0.1524 -0.127)
						)
						(arc
							(start -0.1524 0.127)
							(mid -0.137521 0.162921)
							(end -0.1016 0.1778)
						)
						(arc
							(start 0.1016 0.1778)
							(mid 0.137521 0.162921)
							(end 0.1524 0.127)
						)
					)
					(width 0)
					(fill yes)
				)
			)
		)
		(pad "2" smd custom
			(at 0 0.2794 270)
			(size 0.0762 0.0762)
			(layers "F.Cu" "F.Mask" "F.Paste")
			(net "PHY_SCC_B_TO_DRV_B_35_DP")
			(options
				(clearance outline)
				(anchor circle)
			)
			(primitives
				(gr_poly
					(pts
						(arc
							(start 0.1524 -0.127)
							(mid 0.137521 -0.162921)
							(end 0.1016 -0.1778)
						)
						(arc
							(start -0.1016 -0.1778)
							(mid -0.137521 -0.162921)
							(end -0.1524 -0.127)
						)
						(arc
							(start -0.1524 0.127)
							(mid -0.137521 0.162921)
							(end -0.1016 0.1778)
						)
						(arc
							(start 0.1016 0.1778)
							(mid 0.137521 0.162921)
							(end 0.1524 0.127)
						)
					)
					(width 0)
					(fill yes)
				)
			)
		)
	)
	(footprint ""
		(layer "F.Cu")
		(at 50.419 -35.687 90)
		(property "Reference" "R646"
			(at 0 0 90)
			(layer "F.SilkS")
			(hide yes)
			(effects
				(font
					(size 1.27 1.27)
				)
			)
		)
		(property "Value" "2R6F-GP"
			(at -0.0508 -4.8514 90)
			(unlocked yes)
			(layer "F.Fab")
			(hide yes)
			(effects
				(font
					(size 1.016 1.016)
					(thickness 0.1524)
				)
			)
		)
		(property "Device Type" "R1206H26"
			(at 0 -6.3754 90)
			(unlocked yes)
			(layer "F.Fab")
			(hide yes)
			(effects
				(font
					(size 1.016 1.016)
					(thickness 0.1524)
				)
			)
		)
		(duplicate_pad_numbers_are_jumpers no)
		(fp_line
			(start 1.016 -2.2352)
			(end 1.016 2.2352)
			(stroke
				(width 0.1524)
				(type default)
			)
			(layer "F.SilkS")
		)
		(fp_line
			(start -1.016 -2.2352)
			(end 1.016 -2.2352)
			(stroke
				(width 0.1524)
				(type default)
			)
			(layer "F.SilkS")
		)
		(fp_line
			(start 1.016 2.2352)
			(end -1.016 2.2352)
			(stroke
				(width 0.1524)
				(type default)
			)
			(layer "F.SilkS")
		)
		(fp_line
			(start -1.016 2.2352)
			(end -1.016 -2.2352)
			(stroke
				(width 0.1524)
				(type default)
			)
			(layer "F.SilkS")
		)
		(fp_rect
			(start -1.0922 2.3114)
			(end 1.0922 -2.3114)
			(stroke
				(width 0)
				(type default)
			)
			(fill no)
			(layer "F.CrtYd")
		)
		(fp_poly
			(pts
				(xy -1.0922 -2.3114) (xy 1.0922 -2.3114) (xy 1.0922 2.3114) (xy -1.0922 2.3114)
			)
			(stroke
				(width 0)
				(type default)
			)
			(fill no)
			(layer "F.Fab")
		)
		(pad "1" smd rect
			(at 0 -1.397 90)
			(size 1.651 1.27)
			(layers "F.Cu" "F.Mask" "F.Paste")
			(net "P12V_HDD25")
		)
		(pad "2" smd rect
			(at 0 1.397 90)
			(size 1.651 1.27)
			(layers "F.Cu" "F.Mask" "F.Paste")
			(net "12V_PRE_25")
		)
	)
	(footprint ""
		(layer "F.Cu")
		(at 416.284664 -129.66065 -90)
		(property "Reference" "C302"
			(at 0 0 270)
			(layer "F.SilkS")
			(hide yes)
			(effects
				(font
					(size 1.27 1.27)
				)
			)
		)
		(property "Value" "SCD01U16V1KX-GP"
			(at -2.8321 -1.7399 270)
			(unlocked yes)
			(layer "F.Fab")
			(hide yes)
			(effects
				(font
					(size 1.016 1.016)
					(thickness 0.1524)
				)
			)
		)
		(property "Device Type" "C0201H13"
			(at -2.8321 -3.2639 270)
			(unlocked yes)
			(layer "F.Fab")
			(hide yes)
			(effects
				(font
					(size 1.016 1.016)
					(thickness 0.1524)
				)
			)
		)
		(duplicate_pad_numbers_are_jumpers no)
		(fp_rect
			(start -0.2794 0.6477)
			(end 0.2794 -0.6477)
			(stroke
				(width 0)
				(type default)
			)
			(fill no)
			(layer "F.CrtYd")
		)
		(fp_rect
			(start -0.2794 0.6477)
			(end 0.2794 -0.6477)
			(stroke
				(width 0)
				(type default)
			)
			(fill no)
			(layer "F.Fab")
		)
		(pad "1" smd custom
			(at 0 -0.2794 270)
			(size 0.0762 0.0762)
			(layers "F.Cu" "F.Mask" "F.Paste")
			(net "SAS_HDD_RX_P21")
			(options
				(clearance outline)
				(anchor circle)
			)
			(primitives
				(gr_poly
					(pts
						(arc
							(start 0.1524 -0.127)
							(mid 0.137521 -0.162921)
							(end 0.1016 -0.1778)
						)
						(arc
							(start -0.1016 -0.1778)
							(mid -0.137521 -0.162921)
							(end -0.1524 -0.127)
						)
						(arc
							(start -0.1524 0.127)
							(mid -0.137521 0.162921)
							(end -0.1016 0.1778)
						)
						(arc
							(start 0.1016 0.1778)
							(mid 0.137521 0.162921)
							(end 0.1524 0.127)
						)
					)
					(width 0)
					(fill yes)
				)
			)
		)
		(pad "2" smd custom
			(at 0 0.2794 270)
			(size 0.0762 0.0762)
			(layers "F.Cu" "F.Mask" "F.Paste")
			(net "PHY_SCC_B_TO_DRV_B_21_DP")
			(options
				(clearance outline)
				(anchor circle)
			)
			(primitives
				(gr_poly
					(pts
						(arc
							(start 0.1524 -0.127)
							(mid 0.137521 -0.162921)
							(end 0.1016 -0.1778)
						)
						(arc
							(start -0.1016 -0.1778)
							(mid -0.137521 -0.162921)
							(end -0.1524 -0.127)
						)
						(arc
							(start -0.1524 0.127)
							(mid -0.137521 0.162921)
							(end -0.1016 0.1778)
						)
						(arc
							(start 0.1016 0.1778)
							(mid 0.137521 0.162921)
							(end 0.1524 0.127)
						)
					)
					(width 0)
					(fill yes)
				)
			)
		)
	)
	(footprint ""
		(layer "F.Cu")
		(at 55.753 -45.466 180)
		(property "Reference" "C361"
			(at 0 0 180)
			(layer "F.SilkS")
			(hide yes)
			(effects
				(font
					(size 1.27 1.27)
				)
			)
		)
		(property "Value" "SC1U25V3KX-GP"
			(at 0 -2.8194 180)
			(unlocked yes)
			(layer "F.Fab")
			(hide yes)
			(effects
				(font
					(size 1.016 1.016)
					(thickness 0.1524)
				)
			)
		)
		(property "Device Type" "C603H36"
			(at 0 -4.3434 180)
			(unlocked yes)
			(layer "F.Fab")
			(hide yes)
			(effects
				(font
					(size 1.016 1.016)
					(thickness 0.1524)
				)
			)
		)
		(duplicate_pad_numbers_are_jumpers no)
		(fp_line
			(start 0.508 0)
			(end -0.508 0)
			(stroke
				(width 0.2032)
				(type default)
			)
			(layer "F.SilkS")
		)
		(fp_rect
			(start -0.5842 1.3335)
			(end 0.5842 -1.3335)
			(stroke
				(width 0)
				(type default)
			)
			(fill no)
			(layer "F.CrtYd")
		)
		(fp_rect
			(start -0.5842 1.3335)
			(end 0.5842 -1.3335)
			(stroke
				(width 0)
				(type default)
			)
			(fill no)
			(layer "F.Fab")
		)
		(pad "1" smd custom
			(at 0 -0.762 180)
			(size 0.2159 0.2159)
			(layers "F.Cu" "F.Mask" "F.Paste")
			(net "P12V_HDD25")
			(options
				(clearance outline)
				(anchor circle)
			)
			(primitives
				(gr_poly
					(pts
						(arc
							(start -0.3302 -0.4318)
							(mid -0.402042 -0.402042)
							(end -0.4318 -0.3302)
						)
						(arc
							(start -0.4318 0.3302)
							(mid -0.402042 0.402042)
							(end -0.3302 0.4318)
						)
						(arc
							(start 0.3302 0.4318)
							(mid 0.402042 0.402042)
							(end 0.4318 0.3302)
						)
						(arc
							(start 0.4318 -0.3302)
							(mid 0.402042 -0.402042)
							(end 0.3302 -0.4318)
						)
					)
					(width 0)
					(fill yes)
				)
			)
		)
		(pad "2" smd custom
			(at 0 0.762 180)
			(size 0.2159 0.2159)
			(layers "F.Cu" "F.Mask" "F.Paste")
			(net "GND")
			(options
				(clearance outline)
				(anchor circle)
			)
			(primitives
				(gr_poly
					(pts
						(arc
							(start -0.3302 -0.4318)
							(mid -0.402042 -0.402042)
							(end -0.4318 -0.3302)
						)
						(arc
							(start -0.4318 0.3302)
							(mid -0.402042 0.402042)
							(end -0.3302 0.4318)
						)
						(arc
							(start 0.3302 0.4318)
							(mid 0.402042 0.402042)
							(end 0.4318 0.3302)
						)
						(arc
							(start 0.4318 -0.3302)
							(mid 0.402042 -0.402042)
							(end 0.3302 -0.4318)
						)
					)
					(width 0)
					(fill yes)
				)
			)
		)
	)
	(footprint ""
		(layer "F.Cu")
		(at 14.732 -35.687 -90)
		(property "Reference" "C346"
			(at 0 0 270)
			(layer "F.SilkS")
			(hide yes)
			(effects
				(font
					(size 1.27 1.27)
				)
			)
		)
		(property "Value" "SC4D7U25V5KX-1-GP"
			(at -0.0762 -6.1214 270)
			(unlocked yes)
			(layer "F.Fab")
			(hide yes)
			(effects
				(font
					(size 1.016 1.016)
					(thickness 0.1524)
				)
			)
		)
		(property "Device Type" "C805H58"
			(at -0.0762 -8.1534 270)
			(unlocked yes)
			(layer "F.Fab")
			(hide yes)
			(effects
				(font
					(size 1.016 1.016)
					(thickness 0.1524)
				)
			)
		)
		(duplicate_pad_numbers_are_jumpers no)
		(fp_line
			(start 0.635 0)
			(end -0.635 0)
			(stroke
				(width 0.508)
				(type default)
			)
			(layer "F.SilkS")
		)
		(fp_rect
			(start -0.9652 1.778)
			(end 0.9652 -1.778)
			(stroke
				(width 0)
				(type default)
			)
			(fill no)
			(layer "F.CrtYd")
		)
		(fp_poly
			(pts
				(xy -0.9652 -1.778) (xy 0.9652 -1.778) (xy 0.9652 1.778) (xy -0.9652 1.778)
			)
			(stroke
				(width 0)
				(type default)
			)
			(fill no)
			(layer "F.Fab")
		)
		(pad "1" smd rect
			(at 0 -0.9652 270)
			(size 1.397 1.143)
			(layers "F.Cu" "F.Mask" "F.Paste")
			(net "P12V_HDD24")
		)
		(pad "2" smd rect
			(at 0 0.9652 270)
			(size 1.397 1.143)
			(layers "F.Cu" "F.Mask" "F.Paste")
			(net "GND")
		)
	)
	(footprint ""
		(layer "F.Cu")
		(at 172.593 -131.572 90)
		(property "Reference" "R475"
			(at 0 0 90)
			(layer "F.SilkS")
			(hide yes)
			(effects
				(font
					(size 1.27 1.27)
				)
			)
		)
		(property "Value" "4K7R2J-2-GP"
			(at 0.064008 -3.993896 90)
			(unlocked yes)
			(layer "F.Fab")
			(hide yes)
			(effects
				(font
					(size 1.016 1.016)
					(thickness 0.1524)
				)
			)
		)
		(property "Device Type" "R402H16"
			(at 0.064008 -5.517896 90)
			(unlocked yes)
			(layer "F.Fab")
			(hide yes)
			(effects
				(font
					(size 1.016 1.016)
					(thickness 0.1524)
				)
			)
		)
		(duplicate_pad_numbers_are_jumpers no)
		(fp_line
			(start 0.508 -0.9398)
			(end -0.508 -0.9398)
			(stroke
				(width 0.1524)
				(type default)
			)
			(layer "F.SilkS")
		)
		(fp_line
			(start -0.508 -0.9398)
			(end -0.508 0.9398)
			(stroke
				(width 0.1524)
				(type default)
			)
			(layer "F.SilkS")
		)
		(fp_rect
			(start -0.508 0.9398)
			(end 0.508 -0.9398)
			(stroke
				(width 0)
				(type default)
			)
			(fill no)
			(layer "F.CrtYd")
		)
		(fp_rect
			(start -0.508 0.9398)
			(end 0.508 -0.9398)
			(stroke
				(width 0)
				(type default)
			)
			(fill no)
			(layer "F.Fab")
		)
		(pad "1" smd custom
			(at 0 -0.4445 90)
			(size 0.1397 0.1397)
			(layers "F.Cu" "F.Mask" "F.Paste")
			(net "P12V_B")
			(options
				(clearance outline)
				(anchor circle)
			)
			(primitives
				(gr_poly
					(pts
						(arc
							(start -0.1778 -0.2794)
							(mid -0.249642 -0.249642)
							(end -0.2794 -0.1778)
						)
						(arc
							(start -0.2794 0.1778)
							(mid -0.249642 0.249642)
							(end -0.1778 0.2794)
						)
						(arc
							(start 0.1778 0.2794)
							(mid 0.249642 0.249642)
							(end 0.2794 0.1778)
						)
						(arc
							(start 0.2794 -0.1778)
							(mid 0.249642 -0.249642)
							(end 0.1778 -0.2794)
						)
					)
					(width 0)
					(fill yes)
				)
			)
		)
		(pad "2" smd custom
			(at 0 0.4445 90)
			(size 0.1397 0.1397)
			(layers "F.Cu" "F.Mask" "F.Paste")
			(net "SW_HDD_R17")
			(options
				(clearance outline)
				(anchor circle)
			)
			(primitives
				(gr_poly
					(pts
						(arc
							(start -0.1778 -0.2794)
							(mid -0.249642 -0.249642)
							(end -0.2794 -0.1778)
						)
						(arc
							(start -0.2794 0.1778)
							(mid -0.249642 0.249642)
							(end -0.1778 0.2794)
						)
						(arc
							(start 0.1778 0.2794)
							(mid 0.249642 0.249642)
							(end 0.2794 0.1778)
						)
						(arc
							(start 0.2794 -0.1778)
							(mid 0.249642 -0.249642)
							(end 0.1778 -0.2794)
						)
					)
					(width 0)
					(fill yes)
				)
			)
		)
	)
	(footprint ""
		(layer "F.Cu")
		(at 220.6752 -195.58 90)
		(property "Reference" "R30"
			(at 0 0 90)
			(layer "F.SilkS")
			(hide yes)
			(effects
				(font
					(size 1.27 1.27)
				)
			)
		)
		(property "Value" "0R2J-2-GP"
			(at 0.064008 -3.993896 90)
			(unlocked yes)
			(layer "F.Fab")
			(hide yes)
			(effects
				(font
					(size 1.016 1.016)
					(thickness 0.1524)
				)
			)
		)
		(property "Device Type" "R402H16"
			(at 0.064008 -5.517896 90)
			(unlocked yes)
			(layer "F.Fab")
			(hide yes)
			(effects
				(font
					(size 1.016 1.016)
					(thickness 0.1524)
				)
			)
		)
		(duplicate_pad_numbers_are_jumpers no)
		(fp_line
			(start 0.508 -0.9398)
			(end -0.508 -0.9398)
			(stroke
				(width 0.1524)
				(type default)
			)
			(layer "F.SilkS")
		)
		(fp_line
			(start -0.508 -0.9398)
			(end -0.508 0.9398)
			(stroke
				(width 0.1524)
				(type default)
			)
			(layer "F.SilkS")
		)
		(fp_rect
			(start -0.508 0.9398)
			(end 0.508 -0.9398)
			(stroke
				(width 0)
				(type default)
			)
			(fill no)
			(layer "F.CrtYd")
		)
		(fp_rect
			(start -0.508 0.9398)
			(end 0.508 -0.9398)
			(stroke
				(width 0)
				(type default)
			)
			(fill no)
			(layer "F.Fab")
		)
		(pad "1" smd custom
			(at 0 -0.4445 90)
			(size 0.1397 0.1397)
			(layers "F.Cu" "F.Mask" "F.Paste")
			(net "IO_EXP2_LED_SDA")
			(options
				(clearance outline)
				(anchor circle)
			)
			(primitives
				(gr_poly
					(pts
						(arc
							(start -0.1778 -0.2794)
							(mid -0.249642 -0.249642)
							(end -0.2794 -0.1778)
						)
						(arc
							(start -0.2794 0.1778)
							(mid -0.249642 0.249642)
							(end -0.1778 0.2794)
						)
						(arc
							(start 0.1778 0.2794)
							(mid 0.249642 0.249642)
							(end 0.2794 0.1778)
						)
						(arc
							(start 0.2794 -0.1778)
							(mid 0.249642 -0.249642)
							(end 0.1778 -0.2794)
						)
					)
					(width 0)
					(fill yes)
				)
			)
		)
		(pad "2" smd custom
			(at 0 0.4445 90)
			(size 0.1397 0.1397)
			(layers "F.Cu" "F.Mask" "F.Paste")
			(net "I2C_DRIVE_B_FLT_LED_SDA")
			(options
				(clearance outline)
				(anchor circle)
			)
			(primitives
				(gr_poly
					(pts
						(arc
							(start -0.1778 -0.2794)
							(mid -0.249642 -0.249642)
							(end -0.2794 -0.1778)
						)
						(arc
							(start -0.2794 0.1778)
							(mid -0.249642 0.249642)
							(end -0.1778 0.2794)
						)
						(arc
							(start 0.1778 0.2794)
							(mid 0.249642 0.249642)
							(end 0.2794 0.1778)
						)
						(arc
							(start 0.2794 -0.1778)
							(mid 0.249642 -0.249642)
							(end 0.1778 -0.2794)
						)
					)
					(width 0)
					(fill yes)
				)
			)
		)
	)
	(footprint ""
		(layer "F.Cu")
		(at 55.88 -275.463 180)
		(property "Reference" "C50"
			(at 0 0 180)
			(layer "F.SilkS")
			(hide yes)
			(effects
				(font
					(size 1.27 1.27)
				)
			)
		)
		(property "Value" "SC1U25V3KX-GP"
			(at 0 -2.8194 180)
			(unlocked yes)
			(layer "F.Fab")
			(hide yes)
			(effects
				(font
					(size 1.016 1.016)
					(thickness 0.1524)
				)
			)
		)
		(property "Device Type" "C603H36"
			(at 0 -4.3434 180)
			(unlocked yes)
			(layer "F.Fab")
			(hide yes)
			(effects
				(font
					(size 1.016 1.016)
					(thickness 0.1524)
				)
			)
		)
		(duplicate_pad_numbers_are_jumpers no)
		(fp_line
			(start 0.508 0)
			(end -0.508 0)
			(stroke
				(width 0.2032)
				(type default)
			)
			(layer "F.SilkS")
		)
		(fp_rect
			(start -0.5842 1.3335)
			(end 0.5842 -1.3335)
			(stroke
				(width 0)
				(type default)
			)
			(fill no)
			(layer "F.CrtYd")
		)
		(fp_rect
			(start -0.5842 1.3335)
			(end 0.5842 -1.3335)
			(stroke
				(width 0)
				(type default)
			)
			(fill no)
			(layer "F.Fab")
		)
		(pad "1" smd custom
			(at 0 -0.762 180)
			(size 0.2159 0.2159)
			(layers "F.Cu" "F.Mask" "F.Paste")
			(net "P12V_HDD1")
			(options
				(clearance outline)
				(anchor circle)
			)
			(primitives
				(gr_poly
					(pts
						(arc
							(start -0.3302 -0.4318)
							(mid -0.402042 -0.402042)
							(end -0.4318 -0.3302)
						)
						(arc
							(start -0.4318 0.3302)
							(mid -0.402042 0.402042)
							(end -0.3302 0.4318)
						)
						(arc
							(start 0.3302 0.4318)
							(mid 0.402042 0.402042)
							(end 0.4318 0.3302)
						)
						(arc
							(start 0.4318 -0.3302)
							(mid 0.402042 -0.402042)
							(end 0.3302 -0.4318)
						)
					)
					(width 0)
					(fill yes)
				)
			)
		)
		(pad "2" smd custom
			(at 0 0.762 180)
			(size 0.2159 0.2159)
			(layers "F.Cu" "F.Mask" "F.Paste")
			(net "GND")
			(options
				(clearance outline)
				(anchor circle)
			)
			(primitives
				(gr_poly
					(pts
						(arc
							(start -0.3302 -0.4318)
							(mid -0.402042 -0.402042)
							(end -0.4318 -0.3302)
						)
						(arc
							(start -0.4318 0.3302)
							(mid -0.402042 0.402042)
							(end -0.3302 0.4318)
						)
						(arc
							(start 0.3302 0.4318)
							(mid 0.402042 0.402042)
							(end 0.4318 0.3302)
						)
						(arc
							(start 0.4318 -0.3302)
							(mid 0.402042 -0.402042)
							(end 0.3302 -0.4318)
						)
					)
					(width 0)
					(fill yes)
				)
			)
		)
	)
	(footprint ""
		(layer "F.Cu")
		(at 50.038 -246.634)
		(property "Reference" "R187"
			(at 0 0 0)
			(layer "F.SilkS")
			(hide yes)
			(effects
				(font
					(size 1.27 1.27)
				)
			)
		)
		(property "Value" "0R2J-2-GP"
			(at 0.064008 -3.993896 0)
			(unlocked yes)
			(layer "F.Fab")
			(hide yes)
			(effects
				(font
					(size 1.016 1.016)
					(thickness 0.1524)
				)
			)
		)
		(property "Device Type" "R402H16"
			(at 0.064008 -5.517896 0)
			(unlocked yes)
			(layer "F.Fab")
			(hide yes)
			(effects
				(font
					(size 1.016 1.016)
					(thickness 0.1524)
				)
			)
		)
		(duplicate_pad_numbers_are_jumpers no)
		(fp_line
			(start -0.508 -0.9398)
			(end -0.508 0.9398)
			(stroke
				(width 0.1524)
				(type default)
			)
			(layer "F.SilkS")
		)
		(fp_line
			(start 0.508 -0.9398)
			(end -0.508 -0.9398)
			(stroke
				(width 0.1524)
				(type default)
			)
			(layer "F.SilkS")
		)
		(fp_rect
			(start -0.508 0.9398)
			(end 0.508 -0.9398)
			(stroke
				(width 0)
				(type default)
			)
			(fill no)
			(layer "F.CrtYd")
		)
		(fp_rect
			(start -0.508 0.9398)
			(end 0.508 -0.9398)
			(stroke
				(width 0)
				(type default)
			)
			(fill no)
			(layer "F.Fab")
		)
		(pad "1" smd custom
			(at 0 -0.4445)
			(size 0.1397 0.1397)
			(layers "F.Cu" "F.Mask" "F.Paste")
			(net "SW_HDD_G1")
			(options
				(clearance outline)
				(anchor circle)
			)
			(primitives
				(gr_poly
					(pts
						(arc
							(start -0.1778 -0.2794)
							(mid -0.249642 -0.249642)
							(end -0.2794 -0.1778)
						)
						(arc
							(start -0.2794 0.1778)
							(mid -0.249642 0.249642)
							(end -0.1778 0.2794)
						)
						(arc
							(start 0.1778 0.2794)
							(mid 0.249642 0.249642)
							(end 0.2794 0.1778)
						)
						(arc
							(start 0.2794 -0.1778)
							(mid 0.249642 -0.249642)
							(end 0.1778 -0.2794)
						)
					)
					(width 0)
					(fill yes)
				)
			)
		)
		(pad "2" smd custom
			(at 0 0.4445)
			(size 0.1397 0.1397)
			(layers "F.Cu" "F.Mask" "F.Paste")
			(net "SW_HDD_R1")
			(options
				(clearance outline)
				(anchor circle)
			)
			(primitives
				(gr_poly
					(pts
						(arc
							(start -0.1778 -0.2794)
							(mid -0.249642 -0.249642)
							(end -0.2794 -0.1778)
						)
						(arc
							(start -0.2794 0.1778)
							(mid -0.249642 0.249642)
							(end -0.1778 0.2794)
						)
						(arc
							(start 0.1778 0.2794)
							(mid 0.249642 0.249642)
							(end 0.2794 0.1778)
						)
						(arc
							(start 0.2794 -0.1778)
							(mid 0.249642 -0.249642)
							(end 0.1778 -0.2794)
						)
					)
					(width 0)
					(fill yes)
				)
			)
		)
	)
	(footprint ""
		(layer "F.Cu")
		(at 143.256 -99.314)
		(property "Reference" "R411"
			(at 0 0 0)
			(layer "F.SilkS")
			(hide yes)
			(effects
				(font
					(size 1.27 1.27)
				)
			)
		)
		(property "Value" "130R3F-GP"
			(at -0.0254 -2.5146 0)
			(unlocked yes)
			(layer "F.Fab")
			(hide yes)
			(effects
				(font
					(size 1.016 1.016)
					(thickness 0.1524)
				)
			)
		)
		(property "Device Type" "R603H22"
			(at -0.0254 -4.0386 0)
			(unlocked yes)
			(layer "F.Fab")
			(hide yes)
			(effects
				(font
					(size 1.016 1.016)
					(thickness 0.1524)
				)
			)
		)
		(duplicate_pad_numbers_are_jumpers no)
		(fp_line
			(start -0.4826 0)
			(end -0.2032 0)
			(stroke
				(width 0.2032)
				(type default)
			)
			(layer "F.SilkS")
		)
		(fp_line
			(start 0.2032 0)
			(end 0.4826 0)
			(stroke
				(width 0.2032)
				(type default)
			)
			(layer "F.SilkS")
		)
		(fp_rect
			(start -0.5842 1.3335)
			(end 0.5842 -1.3335)
			(stroke
				(width 0)
				(type default)
			)
			(fill no)
			(layer "F.CrtYd")
		)
		(fp_rect
			(start -0.5842 1.3335)
			(end 0.5842 -1.3335)
			(stroke
				(width 0)
				(type default)
			)
			(fill no)
			(layer "F.Fab")
		)
		(pad "1" smd custom
			(at 0 -0.762)
			(size 0.2159 0.2159)
			(layers "F.Cu" "F.Mask" "F.Paste")
			(net "P5V_B_2")
			(options
				(clearance outline)
				(anchor circle)
			)
			(primitives
				(gr_poly
					(pts
						(arc
							(start -0.3302 -0.4318)
							(mid -0.402042 -0.402042)
							(end -0.4318 -0.3302)
						)
						(arc
							(start -0.4318 0.3302)
							(mid -0.402042 0.402042)
							(end -0.3302 0.4318)
						)
						(arc
							(start 0.3302 0.4318)
							(mid 0.402042 0.402042)
							(end 0.4318 0.3302)
						)
						(arc
							(start 0.4318 -0.3302)
							(mid 0.402042 -0.402042)
							(end 0.3302 -0.4318)
						)
					)
					(width 0)
					(fill yes)
				)
			)
		)
		(pad "2" smd custom
			(at 0 0.762)
			(size 0.2159 0.2159)
			(layers "F.Cu" "F.Mask" "F.Paste")
			(net "FLT_HDD16")
			(options
				(clearance outline)
				(anchor circle)
			)
			(primitives
				(gr_poly
					(pts
						(arc
							(start -0.3302 -0.4318)
							(mid -0.402042 -0.402042)
							(end -0.4318 -0.3302)
						)
						(arc
							(start -0.4318 0.3302)
							(mid -0.402042 0.402042)
							(end -0.3302 0.4318)
						)
						(arc
							(start 0.3302 0.4318)
							(mid 0.402042 0.402042)
							(end 0.4318 0.3302)
						)
						(arc
							(start 0.4318 -0.3302)
							(mid 0.402042 -0.402042)
							(end 0.3302 -0.4318)
						)
					)
					(width 0)
					(fill yes)
				)
			)
		)
	)
	(footprint ""
		(layer "F.Cu")
		(at 351.336102 -13.6271 180)
		(property "Reference" "VIA63"
			(at 0 0 180)
			(layer "F.SilkS")
			(hide yes)
			(effects
				(font
					(size 1.27 1.27)
				)
			)
		)
		(property "Value" "100OHM-8L-2D36MM-L18-GP"
			(at 3.8989 0.5715 180)
			(unlocked yes)
			(layer "F.Fab")
			(hide yes)
			(effects
				(font
					(size 1.016 1.016)
					(thickness 0.1524)
				)
			)
		)
		(property "Device Type" "VIA-PCIE-4P-414097"
			(at 3.8989 -0.9525 180)
			(unlocked yes)
			(layer "F.Fab")
			(hide yes)
			(effects
				(font
					(size 1.016 1.016)
					(thickness 0.1524)
				)
			)
		)
		(duplicate_pad_numbers_are_jumpers no)
		(fp_rect
			(start -2.0701 0.4826)
			(end 2.0701 -0.4826)
			(stroke
				(width 0)
				(type default)
			)
			(fill no)
			(layer "F.CrtYd")
		)
		(fp_rect
			(start -2.0701 0.4826)
			(end 2.0701 -0.4826)
			(stroke
				(width 0)
				(type default)
			)
			(fill no)
			(layer "F.Fab")
		)
		(pad "1" thru_hole circle
			(at -1.5875 0 180)
			(size 0.508 0.508)
			(drill 0.254)
			(layers "*.Cu" "*.Mask")
			(remove_unused_layers no)
			(net "GND")
			(clearance 0.2286)
			(thermal_gap 0.2286)
		)
		(pad "2" thru_hole circle
			(at -0.5715 0 180)
			(size 0.508 0.508)
			(drill 0.254)
			(layers "*.Cu" "*.Mask")
			(remove_unused_layers no)
			(net "PHY_SCC_B_TO_DRV_B_31_DP")
			(clearance 0.2286)
			(thermal_gap 0.2286)
		)
		(pad "3" thru_hole circle
			(at 0.5715 0 180)
			(size 0.508 0.508)
			(drill 0.254)
			(layers "*.Cu" "*.Mask")
			(remove_unused_layers no)
			(net "PHY_SCC_B_TO_DRV_B_31_DN")
			(clearance 0.2286)
			(thermal_gap 0.2286)
		)
		(pad "4" thru_hole circle
			(at 1.5875 0 180)
			(size 0.508 0.508)
			(drill 0.254)
			(layers "*.Cu" "*.Mask")
			(remove_unused_layers no)
			(net "GND")
			(clearance 0.2286)
			(thermal_gap 0.2286)
		)
	)
	(footprint ""
		(layer "F.Cu")
		(at 161.8742 -32.8422 180)
		(property "Reference" "R718"
			(at 0 0 180)
			(layer "F.SilkS")
			(hide yes)
			(effects
				(font
					(size 1.27 1.27)
				)
			)
		)
		(property "Value" "220R3F-1-GP"
			(at -0.0254 -2.5146 180)
			(unlocked yes)
			(layer "F.Fab")
			(hide yes)
			(effects
				(font
					(size 1.016 1.016)
					(thickness 0.1524)
				)
			)
		)
		(property "Device Type" "R603H22"
			(at -0.0254 -4.0386 180)
			(unlocked yes)
			(layer "F.Fab")
			(hide yes)
			(effects
				(font
					(size 1.016 1.016)
					(thickness 0.1524)
				)
			)
		)
		(duplicate_pad_numbers_are_jumpers no)
		(fp_line
			(start 0.2032 0)
			(end 0.4826 0)
			(stroke
				(width 0.2032)
				(type default)
			)
			(layer "F.SilkS")
		)
		(fp_line
			(start -0.4826 0)
			(end -0.2032 0)
			(stroke
				(width 0.2032)
				(type default)
			)
			(layer "F.SilkS")
		)
		(fp_rect
			(start -0.5842 1.3335)
			(end 0.5842 -1.3335)
			(stroke
				(width 0)
				(type default)
			)
			(fill no)
			(layer "F.CrtYd")
		)
		(fp_rect
			(start -0.5842 1.3335)
			(end 0.5842 -1.3335)
			(stroke
				(width 0)
				(type default)
			)
			(fill no)
			(layer "F.Fab")
		)
		(pad "1" smd custom
			(at 0 -0.762 180)
			(size 0.2159 0.2159)
			(layers "F.Cu" "F.Mask" "F.Paste")
			(net "HDD_PRSNT_28")
			(options
				(clearance outline)
				(anchor circle)
			)
			(primitives
				(gr_poly
					(pts
						(arc
							(start -0.3302 -0.4318)
							(mid -0.402042 -0.402042)
							(end -0.4318 -0.3302)
						)
						(arc
							(start -0.4318 0.3302)
							(mid -0.402042 0.402042)
							(end -0.3302 0.4318)
						)
						(arc
							(start 0.3302 0.4318)
							(mid 0.402042 0.402042)
							(end 0.4318 0.3302)
						)
						(arc
							(start 0.4318 -0.3302)
							(mid 0.402042 -0.402042)
							(end 0.3302 -0.4318)
						)
					)
					(width 0)
					(fill yes)
				)
			)
		)
		(pad "2" smd custom
			(at 0 0.762 180)
			(size 0.2159 0.2159)
			(layers "F.Cu" "F.Mask" "F.Paste")
			(net "DRIVE_B_28_INS")
			(options
				(clearance outline)
				(anchor circle)
			)
			(primitives
				(gr_poly
					(pts
						(arc
							(start -0.3302 -0.4318)
							(mid -0.402042 -0.402042)
							(end -0.4318 -0.3302)
						)
						(arc
							(start -0.4318 0.3302)
							(mid -0.402042 0.402042)
							(end -0.3302 0.4318)
						)
						(arc
							(start 0.3302 0.4318)
							(mid 0.402042 0.402042)
							(end 0.4318 0.3302)
						)
						(arc
							(start 0.4318 -0.3302)
							(mid 0.402042 -0.402042)
							(end 0.3302 -0.4318)
						)
					)
					(width 0)
					(fill yes)
				)
			)
		)
	)
	(footprint ""
		(layer "F.Cu")
		(at 220.6752 -194.437 90)
		(property "Reference" "R33"
			(at 0 0 90)
			(layer "F.SilkS")
			(hide yes)
			(effects
				(font
					(size 1.27 1.27)
				)
			)
		)
		(property "Value" "0R2J-2-GP"
			(at 0.064008 -3.993896 90)
			(unlocked yes)
			(layer "F.Fab")
			(hide yes)
			(effects
				(font
					(size 1.016 1.016)
					(thickness 0.1524)
				)
			)
		)
		(property "Device Type" "R402H16"
			(at 0.064008 -5.517896 90)
			(unlocked yes)
			(layer "F.Fab")
			(hide yes)
			(effects
				(font
					(size 1.016 1.016)
					(thickness 0.1524)
				)
			)
		)
		(duplicate_pad_numbers_are_jumpers no)
		(fp_line
			(start 0.508 -0.9398)
			(end -0.508 -0.9398)
			(stroke
				(width 0.1524)
				(type default)
			)
			(layer "F.SilkS")
		)
		(fp_line
			(start -0.508 -0.9398)
			(end -0.508 0.9398)
			(stroke
				(width 0.1524)
				(type default)
			)
			(layer "F.SilkS")
		)
		(fp_rect
			(start -0.508 0.9398)
			(end 0.508 -0.9398)
			(stroke
				(width 0)
				(type default)
			)
			(fill no)
			(layer "F.CrtYd")
		)
		(fp_rect
			(start -0.508 0.9398)
			(end 0.508 -0.9398)
			(stroke
				(width 0)
				(type default)
			)
			(fill no)
			(layer "F.Fab")
		)
		(pad "1" smd custom
			(at 0 -0.4445 90)
			(size 0.1397 0.1397)
			(layers "F.Cu" "F.Mask" "F.Paste")
			(net "IO_EXP2_LED_SCL")
			(options
				(clearance outline)
				(anchor circle)
			)
			(primitives
				(gr_poly
					(pts
						(arc
							(start -0.1778 -0.2794)
							(mid -0.249642 -0.249642)
							(end -0.2794 -0.1778)
						)
						(arc
							(start -0.2794 0.1778)
							(mid -0.249642 0.249642)
							(end -0.1778 0.2794)
						)
						(arc
							(start 0.1778 0.2794)
							(mid 0.249642 0.249642)
							(end 0.2794 0.1778)
						)
						(arc
							(start 0.2794 -0.1778)
							(mid 0.249642 -0.249642)
							(end 0.1778 -0.2794)
						)
					)
					(width 0)
					(fill yes)
				)
			)
		)
		(pad "2" smd custom
			(at 0 0.4445 90)
			(size 0.1397 0.1397)
			(layers "F.Cu" "F.Mask" "F.Paste")
			(net "I2C_DRIVE_B_FLT_LED_SCL")
			(options
				(clearance outline)
				(anchor circle)
			)
			(primitives
				(gr_poly
					(pts
						(arc
							(start -0.1778 -0.2794)
							(mid -0.249642 -0.249642)
							(end -0.2794 -0.1778)
						)
						(arc
							(start -0.2794 0.1778)
							(mid -0.249642 0.249642)
							(end -0.1778 0.2794)
						)
						(arc
							(start 0.1778 0.2794)
							(mid 0.249642 0.249642)
							(end 0.2794 0.1778)
						)
						(arc
							(start 0.2794 -0.1778)
							(mid 0.249642 -0.249642)
							(end 0.1778 -0.2794)
						)
					)
					(width 0)
					(fill yes)
				)
			)
		)
	)
	(footprint ""
		(layer "F.Cu")
		(at 224.550224 -329.060556)
		(property "Reference" "C510"
			(at 0 0 0)
			(layer "F.SilkS")
			(hide yes)
			(effects
				(font
					(size 1.27 1.27)
				)
			)
		)
		(property "Value" "SC22U25V6KX-2-GP-U"
			(at -2.860802 -5.279644 0)
			(unlocked yes)
			(layer "F.Fab")
			(hide yes)
			(effects
				(font
					(size 1.016 1.016)
					(thickness 0.1524)
				)
			)
		)
		(property "Device Type" "C1206-TO0D3H75"
			(at -2.860802 -6.803644 0)
			(unlocked yes)
			(layer "F.Fab")
			(hide yes)
			(effects
				(font
					(size 1.016 1.016)
					(thickness 0.1524)
				)
			)
		)
		(duplicate_pad_numbers_are_jumpers no)
		(fp_line
			(start -1.3081 -2.3749)
			(end 1.3081 -2.3749)
			(stroke
				(width 0.1524)
				(type default)
			)
			(layer "F.SilkS")
		)
		(fp_line
			(start -1.3081 2.3749)
			(end -1.3081 -2.3749)
			(stroke
				(width 0.1524)
				(type default)
			)
			(layer "F.SilkS")
		)
		(fp_line
			(start 1.3081 -2.3749)
			(end 1.3081 2.3749)
			(stroke
				(width 0.1524)
				(type default)
			)
			(layer "F.SilkS")
		)
		(fp_line
			(start 1.3081 2.3749)
			(end -1.3081 2.3749)
			(stroke
				(width 0.1524)
				(type default)
			)
			(layer "F.SilkS")
		)
		(fp_rect
			(start -0.8001 1.6002)
			(end 0.8001 -1.6002)
			(stroke
				(width 0)
				(type default)
			)
			(fill no)
			(layer "F.CrtYd")
		)
		(fp_poly
			(pts
				(xy -1.5621 2.4511) (xy -1.5621 1.6002) (xy 0.8001 1.6002) (xy 0.8001 -1.6002) (xy -0.8001 -1.6002)
				(xy -0.8001 1.5875) (xy -1.5621 1.5875) (xy -1.5621 -2.4511) (xy 1.5621 -2.4511) (xy 1.5621 2.4511)
			)
			(stroke
				(width 0)
				(type default)
			)
			(fill no)
			(layer "F.CrtYd")
		)
		(fp_rect
			(start -1.5621 2.4511)
			(end 1.5621 -2.4511)
			(stroke
				(width 0)
				(type default)
			)
			(fill no)
			(layer "F.Fab")
		)
		(pad "1" smd rect
			(at 0 -1.392936)
			(size 2.1082 1.4478)
			(layers "F.Cu" "F.Mask" "F.Paste")
			(net "P12V_IN")
		)
		(pad "2" smd rect
			(at 0 1.392936)
			(size 2.1082 1.4478)
			(layers "F.Cu" "F.Mask" "F.Paste")
			(net "GND")
		)
	)
	(footprint ""
		(layer "F.Cu")
		(at 363.601 -128.651)
		(property "Reference" "R519"
			(at 0 0 0)
			(layer "F.SilkS")
			(hide yes)
			(effects
				(font
					(size 1.27 1.27)
				)
			)
		)
		(property "Value" "4K7R2F-GP"
			(at 0.064008 -3.993896 0)
			(unlocked yes)
			(layer "F.Fab")
			(hide yes)
			(effects
				(font
					(size 1.016 1.016)
					(thickness 0.1524)
				)
			)
		)
		(property "Device Type" "R402H16"
			(at 0.064008 -5.517896 0)
			(unlocked yes)
			(layer "F.Fab")
			(hide yes)
			(effects
				(font
					(size 1.016 1.016)
					(thickness 0.1524)
				)
			)
		)
		(duplicate_pad_numbers_are_jumpers no)
		(fp_line
			(start -0.508 -0.9398)
			(end -0.508 0.9398)
			(stroke
				(width 0.1524)
				(type default)
			)
			(layer "F.SilkS")
		)
		(fp_line
			(start 0.508 -0.9398)
			(end -0.508 -0.9398)
			(stroke
				(width 0.1524)
				(type default)
			)
			(layer "F.SilkS")
		)
		(fp_rect
			(start -0.508 0.9398)
			(end 0.508 -0.9398)
			(stroke
				(width 0)
				(type default)
			)
			(fill no)
			(layer "F.CrtYd")
		)
		(fp_rect
			(start -0.508 0.9398)
			(end 0.508 -0.9398)
			(stroke
				(width 0)
				(type default)
			)
			(fill no)
			(layer "F.Fab")
		)
		(pad "1" smd custom
			(at 0 -0.4445)
			(size 0.1397 0.1397)
			(layers "F.Cu" "F.Mask" "F.Paste")
			(net "SW_PWR_R_HDD19")
			(options
				(clearance outline)
				(anchor circle)
			)
			(primitives
				(gr_poly
					(pts
						(arc
							(start -0.1778 -0.2794)
							(mid -0.249642 -0.249642)
							(end -0.2794 -0.1778)
						)
						(arc
							(start -0.2794 0.1778)
							(mid -0.249642 0.249642)
							(end -0.1778 0.2794)
						)
						(arc
							(start 0.1778 0.2794)
							(mid 0.249642 0.249642)
							(end 0.2794 0.1778)
						)
						(arc
							(start 0.2794 -0.1778)
							(mid 0.249642 -0.249642)
							(end 0.1778 -0.2794)
						)
					)
					(width 0)
					(fill yes)
				)
			)
		)
		(pad "2" smd custom
			(at 0 0.4445)
			(size 0.1397 0.1397)
			(layers "F.Cu" "F.Mask" "F.Paste")
			(net "GND")
			(options
				(clearance outline)
				(anchor circle)
			)
			(primitives
				(gr_poly
					(pts
						(arc
							(start -0.1778 -0.2794)
							(mid -0.249642 -0.249642)
							(end -0.2794 -0.1778)
						)
						(arc
							(start -0.2794 0.1778)
							(mid -0.249642 0.249642)
							(end -0.1778 0.2794)
						)
						(arc
							(start 0.1778 0.2794)
							(mid 0.249642 0.249642)
							(end 0.2794 0.1778)
						)
						(arc
							(start 0.2794 -0.1778)
							(mid 0.249642 -0.249642)
							(end 0.1778 -0.2794)
						)
					)
					(width 0)
					(fill yes)
				)
			)
		)
	)
	(footprint ""
		(layer "F.Cu")
		(at 52.07 -249.555 180)
		(property "Reference" "Q3"
			(at 0 0 180)
			(layer "F.SilkS")
			(hide yes)
			(effects
				(font
					(size 1.27 1.27)
				)
			)
		)
		(property "Value" "2N7002KDW-GP"
			(at -2.3622 -8.2042 180)
			(unlocked yes)
			(layer "F.Fab")
			(hide yes)
			(effects
				(font
					(size 1.016 1.016)
					(thickness 0.1524)
				)
			)
		)
		(property "Device Type" "SOT-363H44"
			(at -2.3622 -10.1092 180)
			(unlocked yes)
			(layer "F.Fab")
			(hide yes)
			(effects
				(font
					(size 1.016 1.016)
					(thickness 0.1524)
				)
			)
		)
		(duplicate_pad_numbers_are_jumpers no)
		(fp_line
			(start 1.4478 1.7018)
			(end 1.4478 -1.7018)
			(stroke
				(width 0.1524)
				(type default)
			)
			(layer "F.SilkS")
		)
		(fp_line
			(start 1.4478 -1.7018)
			(end -1.4478 -1.7018)
			(stroke
				(width 0.1524)
				(type default)
			)
			(layer "F.SilkS")
		)
		(fp_line
			(start -1.27 1.524)
			(end -1.27 0.6604)
			(stroke
				(width 0.4826)
				(type default)
			)
			(layer "F.SilkS")
		)
		(fp_line
			(start -1.4478 1.7018)
			(end 1.4478 1.7018)
			(stroke
				(width 0.1524)
				(type default)
			)
			(layer "F.SilkS")
		)
		(fp_line
			(start -1.4478 -1.7018)
			(end -1.4478 1.7018)
			(stroke
				(width 0.1524)
				(type default)
			)
			(layer "F.SilkS")
		)
		(fp_poly
			(pts
				(xy -1.524 -1.778) (xy 1.524 -1.778) (xy 1.524 1.778) (xy -1.524 1.778)
			)
			(stroke
				(width 0)
				(type default)
			)
			(fill no)
			(layer "F.CrtYd")
		)
		(fp_poly
			(pts
				(xy -1.524 -1.778) (xy 1.524 -1.778) (xy 1.524 1.778) (xy -1.524 1.778)
			)
			(stroke
				(width 0)
				(type default)
			)
			(fill no)
			(layer "F.Fab")
		)
		(pad "1" smd rect
			(at -0.65024 0.9398 180)
			(size 0.4064 1.016)
			(layers "F.Cu" "F.Mask" "F.Paste")
			(net "GND")
		)
		(pad "2" smd rect
			(at 0 0.9398 180)
			(size 0.4064 1.016)
			(layers "F.Cu" "F.Mask" "F.Paste")
			(net "SW_PWR_R_HDD1")
		)
		(pad "3" smd rect
			(at 0.65024 0.9398 180)
			(size 0.4064 1.016)
			(layers "F.Cu" "F.Mask" "F.Paste")
			(net "SW_HDD_P1")
		)
		(pad "4" smd rect
			(at 0.65024 -0.9398 180)
			(size 0.4064 1.016)
			(layers "F.Cu" "F.Mask" "F.Paste")
			(net "GND")
		)
		(pad "5" smd rect
			(at 0 -0.9398 180)
			(size 0.4064 1.016)
			(layers "F.Cu" "F.Mask" "F.Paste")
			(net "SW_HDD_G1")
		)
		(pad "6" smd rect
			(at -0.65024 -0.9398 180)
			(size 0.4064 1.016)
			(layers "F.Cu" "F.Mask" "F.Paste")
			(net "SW_HDD_R1")
		)
	)
	(footprint ""
		(layer "F.Cu")
		(at 407.1366 -33.782 90)
		(property "Reference" "C455"
			(at 0 0 90)
			(layer "F.SilkS")
			(hide yes)
			(effects
				(font
					(size 1.27 1.27)
				)
			)
		)
		(property "Value" "SCD033U25V2KX-GP"
			(at 1.1811 -2.7051 90)
			(unlocked yes)
			(layer "F.Fab")
			(hide yes)
			(effects
				(font
					(size 1.016 1.016)
					(thickness 0.1524)
				)
			)
		)
		(property "Device Type" "C402H22"
			(at 1.1811 -4.2291 90)
			(unlocked yes)
			(layer "F.Fab")
			(hide yes)
			(effects
				(font
					(size 1.016 1.016)
					(thickness 0.1524)
				)
			)
		)
		(duplicate_pad_numbers_are_jumpers no)
		(fp_rect
			(start -0.4318 0.9525)
			(end 0.4318 -0.9525)
			(stroke
				(width 0)
				(type default)
			)
			(fill no)
			(layer "F.CrtYd")
		)
		(fp_rect
			(start -0.4318 0.9525)
			(end 0.4318 -0.9525)
			(stroke
				(width 0)
				(type default)
			)
			(fill no)
			(layer "F.Fab")
		)
		(pad "1" smd custom
			(at 0 -0.4445 90)
			(size 0.1524 0.1524)
			(layers "F.Cu" "F.Mask" "F.Paste")
			(net "P12V_B")
			(options
				(clearance outline)
				(anchor circle)
			)
			(primitives
				(gr_poly
					(pts
						(arc
							(start 0.3048 -0.2032)
							(mid 0.275042 -0.275042)
							(end 0.2032 -0.3048)
						)
						(arc
							(start -0.2032 -0.3048)
							(mid -0.275042 -0.275042)
							(end -0.3048 -0.2032)
						)
						(arc
							(start -0.3048 0.2032)
							(mid -0.275042 0.275042)
							(end -0.2032 0.3048)
						)
						(arc
							(start 0.2032 0.3048)
							(mid 0.275042 0.275042)
							(end 0.3048 0.2032)
						)
					)
					(width 0)
					(fill yes)
				)
			)
		)
		(pad "2" smd custom
			(at 0 0.4445 90)
			(size 0.1524 0.1524)
			(layers "F.Cu" "F.Mask" "F.Paste")
			(net "SW_HDD_N32")
			(options
				(clearance outline)
				(anchor circle)
			)
			(primitives
				(gr_poly
					(pts
						(arc
							(start 0.3048 -0.2032)
							(mid 0.275042 -0.275042)
							(end 0.2032 -0.3048)
						)
						(arc
							(start -0.2032 -0.3048)
							(mid -0.275042 -0.275042)
							(end -0.3048 -0.2032)
						)
						(arc
							(start -0.3048 0.2032)
							(mid -0.275042 0.275042)
							(end -0.2032 0.3048)
						)
						(arc
							(start 0.2032 0.3048)
							(mid 0.275042 0.275042)
							(end 0.3048 0.2032)
						)
					)
					(width 0)
					(fill yes)
				)
			)
		)
	)
	(footprint ""
		(layer "F.Cu")
		(at 245.745 -311.912)
		(property "Reference" "R1094"
			(at 0 0 0)
			(layer "F.SilkS")
			(hide yes)
			(effects
				(font
					(size 1.27 1.27)
				)
			)
		)
		(property "Value" "0R2J-2-GP"
			(at 0.064008 -3.993896 0)
			(unlocked yes)
			(layer "F.Fab")
			(hide yes)
			(effects
				(font
					(size 1.016 1.016)
					(thickness 0.1524)
				)
			)
		)
		(property "Device Type" "R402H16"
			(at 0.064008 -5.517896 0)
			(unlocked yes)
			(layer "F.Fab")
			(hide yes)
			(effects
				(font
					(size 1.016 1.016)
					(thickness 0.1524)
				)
			)
		)
		(duplicate_pad_numbers_are_jumpers no)
		(fp_line
			(start -0.508 -0.9398)
			(end -0.508 0.9398)
			(stroke
				(width 0.1524)
				(type default)
			)
			(layer "F.SilkS")
		)
		(fp_line
			(start 0.508 -0.9398)
			(end -0.508 -0.9398)
			(stroke
				(width 0.1524)
				(type default)
			)
			(layer "F.SilkS")
		)
		(fp_rect
			(start -0.508 0.9398)
			(end 0.508 -0.9398)
			(stroke
				(width 0)
				(type default)
			)
			(fill no)
			(layer "F.CrtYd")
		)
		(fp_rect
			(start -0.508 0.9398)
			(end 0.508 -0.9398)
			(stroke
				(width 0)
				(type default)
			)
			(fill no)
			(layer "F.Fab")
		)
		(pad "1" smd custom
			(at 0 -0.4445)
			(size 0.1397 0.1397)
			(layers "F.Cu" "F.Mask" "F.Paste")
			(net "GND")
			(options
				(clearance outline)
				(anchor circle)
			)
			(primitives
				(gr_poly
					(pts
						(arc
							(start -0.1778 -0.2794)
							(mid -0.249642 -0.249642)
							(end -0.2794 -0.1778)
						)
						(arc
							(start -0.2794 0.1778)
							(mid -0.249642 0.249642)
							(end -0.1778 0.2794)
						)
						(arc
							(start 0.1778 0.2794)
							(mid 0.249642 0.249642)
							(end 0.2794 0.1778)
						)
						(arc
							(start 0.2794 -0.1778)
							(mid 0.249642 -0.249642)
							(end 0.1778 -0.2794)
						)
					)
					(width 0)
					(fill yes)
				)
			)
		)
		(pad "2" smd custom
			(at 0 0.4445)
			(size 0.1397 0.1397)
			(layers "F.Cu" "F.Mask" "F.Paste")
			(net "MAX31790_A_FREQ_ST")
			(options
				(clearance outline)
				(anchor circle)
			)
			(primitives
				(gr_poly
					(pts
						(arc
							(start -0.1778 -0.2794)
							(mid -0.249642 -0.249642)
							(end -0.2794 -0.1778)
						)
						(arc
							(start -0.2794 0.1778)
							(mid -0.249642 0.249642)
							(end -0.1778 0.2794)
						)
						(arc
							(start 0.1778 0.2794)
							(mid 0.249642 0.249642)
							(end 0.2794 0.1778)
						)
						(arc
							(start 0.2794 -0.1778)
							(mid 0.249642 -0.249642)
							(end 0.1778 -0.2794)
						)
					)
					(width 0)
					(fill yes)
				)
			)
		)
	)
	(footprint ""
		(layer "F.Cu")
		(at 117.1194 -131.2926 -90)
		(property "Reference" "R425"
			(at 0 0 270)
			(layer "F.SilkS")
			(hide yes)
			(effects
				(font
					(size 1.27 1.27)
				)
			)
		)
		(property "Value" "0R2J-2-GP"
			(at 0.064008 -3.993896 270)
			(unlocked yes)
			(layer "F.Fab")
			(hide yes)
			(effects
				(font
					(size 1.016 1.016)
					(thickness 0.1524)
				)
			)
		)
		(property "Device Type" "R402H16"
			(at 0.064008 -5.517896 270)
			(unlocked yes)
			(layer "F.Fab")
			(hide yes)
			(effects
				(font
					(size 1.016 1.016)
					(thickness 0.1524)
				)
			)
		)
		(duplicate_pad_numbers_are_jumpers no)
		(fp_line
			(start -0.508 -0.9398)
			(end -0.508 0.9398)
			(stroke
				(width 0.1524)
				(type default)
			)
			(layer "F.SilkS")
		)
		(fp_line
			(start 0.508 -0.9398)
			(end -0.508 -0.9398)
			(stroke
				(width 0.1524)
				(type default)
			)
			(layer "F.SilkS")
		)
		(fp_rect
			(start -0.508 0.9398)
			(end 0.508 -0.9398)
			(stroke
				(width 0)
				(type default)
			)
			(fill no)
			(layer "F.CrtYd")
		)
		(fp_rect
			(start -0.508 0.9398)
			(end 0.508 -0.9398)
			(stroke
				(width 0)
				(type default)
			)
			(fill no)
			(layer "F.Fab")
		)
		(pad "1" smd custom
			(at 0 -0.4445 270)
			(size 0.1397 0.1397)
			(layers "F.Cu" "F.Mask" "F.Paste")
			(net "DRIVE_B_15_PWR")
			(options
				(clearance outline)
				(anchor circle)
			)
			(primitives
				(gr_poly
					(pts
						(arc
							(start -0.1778 -0.2794)
							(mid -0.249642 -0.249642)
							(end -0.2794 -0.1778)
						)
						(arc
							(start -0.2794 0.1778)
							(mid -0.249642 0.249642)
							(end -0.1778 0.2794)
						)
						(arc
							(start 0.1778 0.2794)
							(mid 0.249642 0.249642)
							(end 0.2794 0.1778)
						)
						(arc
							(start 0.2794 -0.1778)
							(mid 0.249642 -0.249642)
							(end 0.1778 -0.2794)
						)
					)
					(width 0)
					(fill yes)
				)
			)
		)
		(pad "2" smd custom
			(at 0 0.4445 270)
			(size 0.1397 0.1397)
			(layers "F.Cu" "F.Mask" "F.Paste")
			(net "SW_PWR_R_HDD15")
			(options
				(clearance outline)
				(anchor circle)
			)
			(primitives
				(gr_poly
					(pts
						(arc
							(start -0.1778 -0.2794)
							(mid -0.249642 -0.249642)
							(end -0.2794 -0.1778)
						)
						(arc
							(start -0.2794 0.1778)
							(mid -0.249642 0.249642)
							(end -0.1778 0.2794)
						)
						(arc
							(start 0.1778 0.2794)
							(mid 0.249642 0.249642)
							(end 0.2794 0.1778)
						)
						(arc
							(start 0.2794 -0.1778)
							(mid 0.249642 -0.249642)
							(end 0.1778 -0.2794)
						)
					)
					(width 0)
					(fill yes)
				)
			)
		)
	)
	(footprint ""
		(layer "F.Cu")
		(at 48.387 -253.111 90)
		(property "Reference" "R179"
			(at 0 0 90)
			(layer "F.SilkS")
			(hide yes)
			(effects
				(font
					(size 1.27 1.27)
				)
			)
		)
		(property "Value" "4K7R2J-2-GP"
			(at 0.064008 -3.993896 90)
			(unlocked yes)
			(layer "F.Fab")
			(hide yes)
			(effects
				(font
					(size 1.016 1.016)
					(thickness 0.1524)
				)
			)
		)
		(property "Device Type" "R402H16"
			(at 0.064008 -5.517896 90)
			(unlocked yes)
			(layer "F.Fab")
			(hide yes)
			(effects
				(font
					(size 1.016 1.016)
					(thickness 0.1524)
				)
			)
		)
		(duplicate_pad_numbers_are_jumpers no)
		(fp_line
			(start 0.508 -0.9398)
			(end -0.508 -0.9398)
			(stroke
				(width 0.1524)
				(type default)
			)
			(layer "F.SilkS")
		)
		(fp_line
			(start -0.508 -0.9398)
			(end -0.508 0.9398)
			(stroke
				(width 0.1524)
				(type default)
			)
			(layer "F.SilkS")
		)
		(fp_rect
			(start -0.508 0.9398)
			(end 0.508 -0.9398)
			(stroke
				(width 0)
				(type default)
			)
			(fill no)
			(layer "F.CrtYd")
		)
		(fp_rect
			(start -0.508 0.9398)
			(end 0.508 -0.9398)
			(stroke
				(width 0)
				(type default)
			)
			(fill no)
			(layer "F.Fab")
		)
		(pad "1" smd custom
			(at 0 -0.4445 90)
			(size 0.1397 0.1397)
			(layers "F.Cu" "F.Mask" "F.Paste")
			(net "P12V_B")
			(options
				(clearance outline)
				(anchor circle)
			)
			(primitives
				(gr_poly
					(pts
						(arc
							(start -0.1778 -0.2794)
							(mid -0.249642 -0.249642)
							(end -0.2794 -0.1778)
						)
						(arc
							(start -0.2794 0.1778)
							(mid -0.249642 0.249642)
							(end -0.1778 0.2794)
						)
						(arc
							(start 0.1778 0.2794)
							(mid 0.249642 0.249642)
							(end 0.2794 0.1778)
						)
						(arc
							(start 0.2794 -0.1778)
							(mid 0.249642 -0.249642)
							(end 0.1778 -0.2794)
						)
					)
					(width 0)
					(fill yes)
				)
			)
		)
		(pad "2" smd custom
			(at 0 0.4445 90)
			(size 0.1397 0.1397)
			(layers "F.Cu" "F.Mask" "F.Paste")
			(net "SW_HDD_P1")
			(options
				(clearance outline)
				(anchor circle)
			)
			(primitives
				(gr_poly
					(pts
						(arc
							(start -0.1778 -0.2794)
							(mid -0.249642 -0.249642)
							(end -0.2794 -0.1778)
						)
						(arc
							(start -0.2794 0.1778)
							(mid -0.249642 0.249642)
							(end -0.1778 0.2794)
						)
						(arc
							(start 0.1778 0.2794)
							(mid 0.249642 0.249642)
							(end 0.2794 0.1778)
						)
						(arc
							(start 0.2794 -0.1778)
							(mid 0.249642 -0.249642)
							(end 0.1778 -0.2794)
						)
					)
					(width 0)
					(fill yes)
				)
			)
		)
	)
	(footprint ""
		(layer "F.Cu")
		(at 459.359 -243.586 180)
		(property "Reference" "R324"
			(at 0 0 180)
			(layer "F.SilkS")
			(hide yes)
			(effects
				(font
					(size 1.27 1.27)
				)
			)
		)
		(property "Value" "1KR2F-3-GP"
			(at 0.064008 -3.993896 180)
			(unlocked yes)
			(layer "F.Fab")
			(hide yes)
			(effects
				(font
					(size 1.016 1.016)
					(thickness 0.1524)
				)
			)
		)
		(property "Device Type" "R402H16"
			(at 0.064008 -5.517896 180)
			(unlocked yes)
			(layer "F.Fab")
			(hide yes)
			(effects
				(font
					(size 1.016 1.016)
					(thickness 0.1524)
				)
			)
		)
		(duplicate_pad_numbers_are_jumpers no)
		(fp_line
			(start 0.508 -0.9398)
			(end -0.508 -0.9398)
			(stroke
				(width 0.1524)
				(type default)
			)
			(layer "F.SilkS")
		)
		(fp_line
			(start -0.508 -0.9398)
			(end -0.508 0.9398)
			(stroke
				(width 0.1524)
				(type default)
			)
			(layer "F.SilkS")
		)
		(fp_rect
			(start -0.508 0.9398)
			(end 0.508 -0.9398)
			(stroke
				(width 0)
				(type default)
			)
			(fill no)
			(layer "F.CrtYd")
		)
		(fp_rect
			(start -0.508 0.9398)
			(end 0.508 -0.9398)
			(stroke
				(width 0)
				(type default)
			)
			(fill no)
			(layer "F.Fab")
		)
		(pad "1" smd custom
			(at 0 -0.4445 180)
			(size 0.1397 0.1397)
			(layers "F.Cu" "F.Mask" "F.Paste")
			(net "P3V3_STBY_B")
			(options
				(clearance outline)
				(anchor circle)
			)
			(primitives
				(gr_poly
					(pts
						(arc
							(start -0.1778 -0.2794)
							(mid -0.249642 -0.249642)
							(end -0.2794 -0.1778)
						)
						(arc
							(start -0.2794 0.1778)
							(mid -0.249642 0.249642)
							(end -0.1778 0.2794)
						)
						(arc
							(start 0.1778 0.2794)
							(mid 0.249642 0.249642)
							(end 0.2794 0.1778)
						)
						(arc
							(start 0.2794 -0.1778)
							(mid 0.249642 -0.249642)
							(end 0.1778 -0.2794)
						)
					)
					(width 0)
					(fill yes)
				)
			)
		)
		(pad "2" smd custom
			(at 0 0.4445 180)
			(size 0.1397 0.1397)
			(layers "F.Cu" "F.Mask" "F.Paste")
			(net "SW_PWR_R_HDD10")
			(options
				(clearance outline)
				(anchor circle)
			)
			(primitives
				(gr_poly
					(pts
						(arc
							(start -0.1778 -0.2794)
							(mid -0.249642 -0.249642)
							(end -0.2794 -0.1778)
						)
						(arc
							(start -0.2794 0.1778)
							(mid -0.249642 0.249642)
							(end -0.1778 0.2794)
						)
						(arc
							(start 0.1778 0.2794)
							(mid 0.249642 0.249642)
							(end 0.2794 0.1778)
						)
						(arc
							(start 0.2794 -0.1778)
							(mid 0.249642 -0.249642)
							(end 0.1778 -0.2794)
						)
					)
					(width 0)
					(fill yes)
				)
			)
		)
	)
	(footprint ""
		(layer "F.Cu")
		(at 79.883 -23.114 90)
		(property "Reference" "R675"
			(at 0 0 90)
			(layer "F.SilkS")
			(hide yes)
			(effects
				(font
					(size 1.27 1.27)
				)
			)
		)
		(property "Value" "4K7R2J-2-GP"
			(at 0.064008 -3.993896 90)
			(unlocked yes)
			(layer "F.Fab")
			(hide yes)
			(effects
				(font
					(size 1.016 1.016)
					(thickness 0.1524)
				)
			)
		)
		(property "Device Type" "R402H16"
			(at 0.064008 -5.517896 90)
			(unlocked yes)
			(layer "F.Fab")
			(hide yes)
			(effects
				(font
					(size 1.016 1.016)
					(thickness 0.1524)
				)
			)
		)
		(duplicate_pad_numbers_are_jumpers no)
		(fp_line
			(start 0.508 -0.9398)
			(end -0.508 -0.9398)
			(stroke
				(width 0.1524)
				(type default)
			)
			(layer "F.SilkS")
		)
		(fp_line
			(start -0.508 -0.9398)
			(end -0.508 0.9398)
			(stroke
				(width 0.1524)
				(type default)
			)
			(layer "F.SilkS")
		)
		(fp_rect
			(start -0.508 0.9398)
			(end 0.508 -0.9398)
			(stroke
				(width 0)
				(type default)
			)
			(fill no)
			(layer "F.CrtYd")
		)
		(fp_rect
			(start -0.508 0.9398)
			(end 0.508 -0.9398)
			(stroke
				(width 0)
				(type default)
			)
			(fill no)
			(layer "F.Fab")
		)
		(pad "1" smd custom
			(at 0 -0.4445 90)
			(size 0.1397 0.1397)
			(layers "F.Cu" "F.Mask" "F.Paste")
			(net "P12V_B")
			(options
				(clearance outline)
				(anchor circle)
			)
			(primitives
				(gr_poly
					(pts
						(arc
							(start -0.1778 -0.2794)
							(mid -0.249642 -0.249642)
							(end -0.2794 -0.1778)
						)
						(arc
							(start -0.2794 0.1778)
							(mid -0.249642 0.249642)
							(end -0.1778 0.2794)
						)
						(arc
							(start 0.1778 0.2794)
							(mid 0.249642 0.249642)
							(end 0.2794 0.1778)
						)
						(arc
							(start 0.2794 -0.1778)
							(mid 0.249642 -0.249642)
							(end 0.1778 -0.2794)
						)
					)
					(width 0)
					(fill yes)
				)
			)
		)
		(pad "2" smd custom
			(at 0 0.4445 90)
			(size 0.1397 0.1397)
			(layers "F.Cu" "F.Mask" "F.Paste")
			(net "SW_HDD_P26")
			(options
				(clearance outline)
				(anchor circle)
			)
			(primitives
				(gr_poly
					(pts
						(arc
							(start -0.1778 -0.2794)
							(mid -0.249642 -0.249642)
							(end -0.2794 -0.1778)
						)
						(arc
							(start -0.2794 0.1778)
							(mid -0.249642 0.249642)
							(end -0.1778 0.2794)
						)
						(arc
							(start 0.1778 0.2794)
							(mid 0.249642 0.249642)
							(end 0.2794 0.1778)
						)
						(arc
							(start 0.2794 -0.1778)
							(mid 0.249642 -0.249642)
							(end 0.1778 -0.2794)
						)
					)
					(width 0)
					(fill yes)
				)
			)
		)
	)
	(footprint ""
		(layer "F.Cu")
		(at 251.941838 -229.48011 90)
		(property "Reference" "R133"
			(at 0 0 90)
			(layer "F.SilkS")
			(hide yes)
			(effects
				(font
					(size 1.27 1.27)
				)
			)
		)
		(property "Value" "7K32R2F-GP"
			(at 0.064008 -3.993896 90)
			(unlocked yes)
			(layer "F.Fab")
			(hide yes)
			(effects
				(font
					(size 1.016 1.016)
					(thickness 0.1524)
				)
			)
		)
		(property "Device Type" "R402H16"
			(at 0.064008 -5.517896 90)
			(unlocked yes)
			(layer "F.Fab")
			(hide yes)
			(effects
				(font
					(size 1.016 1.016)
					(thickness 0.1524)
				)
			)
		)
		(duplicate_pad_numbers_are_jumpers no)
		(fp_line
			(start 0.508 -0.9398)
			(end -0.508 -0.9398)
			(stroke
				(width 0.1524)
				(type default)
			)
			(layer "F.SilkS")
		)
		(fp_line
			(start -0.508 -0.9398)
			(end -0.508 0.9398)
			(stroke
				(width 0.1524)
				(type default)
			)
			(layer "F.SilkS")
		)
		(fp_rect
			(start -0.508 0.9398)
			(end 0.508 -0.9398)
			(stroke
				(width 0)
				(type default)
			)
			(fill no)
			(layer "F.CrtYd")
		)
		(fp_rect
			(start -0.508 0.9398)
			(end 0.508 -0.9398)
			(stroke
				(width 0)
				(type default)
			)
			(fill no)
			(layer "F.Fab")
		)
		(pad "1" smd custom
			(at 0 -0.4445 90)
			(size 0.1397 0.1397)
			(layers "F.Cu" "F.Mask" "F.Paste")
			(net "P3V3_STBY_B")
			(options
				(clearance outline)
				(anchor circle)
			)
			(primitives
				(gr_poly
					(pts
						(arc
							(start -0.1778 -0.2794)
							(mid -0.249642 -0.249642)
							(end -0.2794 -0.1778)
						)
						(arc
							(start -0.2794 0.1778)
							(mid -0.249642 0.249642)
							(end -0.1778 0.2794)
						)
						(arc
							(start 0.1778 0.2794)
							(mid 0.249642 0.249642)
							(end 0.2794 0.1778)
						)
						(arc
							(start 0.2794 -0.1778)
							(mid 0.249642 -0.249642)
							(end 0.1778 -0.2794)
						)
					)
					(width 0)
					(fill yes)
				)
			)
		)
		(pad "2" smd custom
			(at 0 0.4445 90)
			(size 0.1397 0.1397)
			(layers "F.Cu" "F.Mask" "F.Paste")
			(net "P3V3_SENSE")
			(options
				(clearance outline)
				(anchor circle)
			)
			(primitives
				(gr_poly
					(pts
						(arc
							(start -0.1778 -0.2794)
							(mid -0.249642 -0.249642)
							(end -0.2794 -0.1778)
						)
						(arc
							(start -0.2794 0.1778)
							(mid -0.249642 0.249642)
							(end -0.1778 0.2794)
						)
						(arc
							(start 0.1778 0.2794)
							(mid 0.249642 0.249642)
							(end 0.2794 0.1778)
						)
						(arc
							(start 0.2794 -0.1778)
							(mid 0.249642 -0.249642)
							(end 0.1778 -0.2794)
						)
					)
					(width 0)
					(fill yes)
				)
			)
		)
	)
	(footprint ""
		(layer "F.Cu")
		(at 413.866076 -39.705026)
		(property "Reference" "TP186"
			(at 0 0 0)
			(layer "F.SilkS")
			(hide yes)
			(effects
				(font
					(size 1.27 1.27)
				)
			)
		)
		(property "Value" "*"
			(at -0.0508 -1.6764 0)
			(unlocked yes)
			(layer "F.Fab")
			(hide yes)
			(effects
				(font
					(size 1.016 1.016)
					(thickness 0.1524)
				)
			)
		)
		(property "Device Type" "TPAD32"
			(at -0.0508 -3.2004 0)
			(unlocked yes)
			(layer "F.Fab")
			(hide yes)
			(effects
				(font
					(size 1.016 1.016)
					(thickness 0.1524)
				)
			)
		)
		(duplicate_pad_numbers_are_jumpers no)
		(fp_poly
			(pts
				(arc
					(start 0.4064 0)
					(mid -0.4064 0)
					(end 0.4064 0)
				)
			)
			(stroke
				(width 0)
				(type default)
			)
			(fill no)
			(layer "F.CrtYd")
		)
		(fp_poly
			(pts
				(arc
					(start 0.7112 0)
					(mid -0.7112 0)
					(end 0.7112 0)
				)
			)
			(stroke
				(width 0)
				(type default)
			)
			(fill no)
			(layer "F.Fab")
		)
		(pad "1" smd circle
			(at 0 0)
			(size 0.8128 0.8128)
			(layers "F.Cu" "F.Mask" "F.Paste")
			(net "ACT_HDD_33")
		)
	)
	(footprint ""
		(layer "F.Cu")
		(at 363.855 -266.827 180)
		(property "Reference" "C122"
			(at 0 0 180)
			(layer "F.SilkS")
			(hide yes)
			(effects
				(font
					(size 1.27 1.27)
				)
			)
		)
		(property "Value" "SC10U16V6KX-2GP"
			(at -0.0762 -5.1308 180)
			(unlocked yes)
			(layer "F.Fab")
			(hide yes)
			(effects
				(font
					(size 1.016 1.016)
					(thickness 0.1524)
				)
			)
		)
		(property "Device Type" "C1206H71"
			(at -0.127 -6.6548 180)
			(unlocked yes)
			(layer "F.Fab")
			(hide yes)
			(effects
				(font
					(size 1.016 1.016)
					(thickness 0.1524)
				)
			)
		)
		(duplicate_pad_numbers_are_jumpers no)
		(fp_line
			(start 1.016 2.2352)
			(end -1.016 2.2352)
			(stroke
				(width 0.1524)
				(type default)
			)
			(layer "F.SilkS")
		)
		(fp_line
			(start 1.016 0.8382)
			(end 1.016 2.2352)
			(stroke
				(width 0.1524)
				(type default)
			)
			(layer "F.SilkS")
		)
		(fp_line
			(start 1.016 -2.2352)
			(end 1.016 -0.8382)
			(stroke
				(width 0.1524)
				(type default)
			)
			(layer "F.SilkS")
		)
		(fp_line
			(start -1.016 2.2352)
			(end -1.016 0.8382)
			(stroke
				(width 0.1524)
				(type default)
			)
			(layer "F.SilkS")
		)
		(fp_line
			(start -1.016 -0.8382)
			(end -1.016 -2.2352)
			(stroke
				(width 0.1524)
				(type default)
			)
			(layer "F.SilkS")
		)
		(fp_line
			(start -1.016 -2.2352)
			(end 1.016 -2.2352)
			(stroke
				(width 0.1524)
				(type default)
			)
			(layer "F.SilkS")
		)
		(fp_rect
			(start -1.0922 2.3114)
			(end 1.0922 -2.3114)
			(stroke
				(width 0)
				(type default)
			)
			(fill no)
			(layer "F.CrtYd")
		)
		(fp_poly
			(pts
				(xy 1.0922 -2.3114) (xy 1.0922 2.3114) (xy -1.0922 2.3114) (xy -1.0922 -2.3114)
			)
			(stroke
				(width 0)
				(type default)
			)
			(fill no)
			(layer "F.Fab")
		)
		(pad "1" smd rect
			(at 0 -1.397 180)
			(size 1.651 1.27)
			(layers "F.Cu" "F.Mask" "F.Paste")
			(net "P5V_HDD7")
		)
		(pad "2" smd rect
			(at 0 1.397 180)
			(size 1.651 1.27)
			(layers "F.Cu" "F.Mask" "F.Paste")
			(net "GND")
		)
	)
	(footprint ""
		(layer "F.Cu")
		(at 158.663386 -15.219426 90)
		(property "Reference" "C392"
			(at 0 0 90)
			(layer "F.SilkS")
			(hide yes)
			(effects
				(font
					(size 1.27 1.27)
				)
			)
		)
		(property "Value" "SCD01U16V1KX-GP"
			(at -2.8321 -1.7399 90)
			(unlocked yes)
			(layer "F.Fab")
			(hide yes)
			(effects
				(font
					(size 1.016 1.016)
					(thickness 0.1524)
				)
			)
		)
		(property "Device Type" "C0201H13"
			(at -2.8321 -3.2639 90)
			(unlocked yes)
			(layer "F.Fab")
			(hide yes)
			(effects
				(font
					(size 1.016 1.016)
					(thickness 0.1524)
				)
			)
		)
		(duplicate_pad_numbers_are_jumpers no)
		(fp_rect
			(start -0.2794 0.6477)
			(end 0.2794 -0.6477)
			(stroke
				(width 0)
				(type default)
			)
			(fill no)
			(layer "F.CrtYd")
		)
		(fp_rect
			(start -0.2794 0.6477)
			(end 0.2794 -0.6477)
			(stroke
				(width 0)
				(type default)
			)
			(fill no)
			(layer "F.Fab")
		)
		(pad "1" smd custom
			(at 0 -0.2794 90)
			(size 0.0762 0.0762)
			(layers "F.Cu" "F.Mask" "F.Paste")
			(net "SAS_HDD_RX_N28")
			(options
				(clearance outline)
				(anchor circle)
			)
			(primitives
				(gr_poly
					(pts
						(arc
							(start 0.1524 -0.127)
							(mid 0.137521 -0.162921)
							(end 0.1016 -0.1778)
						)
						(arc
							(start -0.1016 -0.1778)
							(mid -0.137521 -0.162921)
							(end -0.1524 -0.127)
						)
						(arc
							(start -0.1524 0.127)
							(mid -0.137521 0.162921)
							(end -0.1016 0.1778)
						)
						(arc
							(start 0.1016 0.1778)
							(mid 0.137521 0.162921)
							(end 0.1524 0.127)
						)
					)
					(width 0)
					(fill yes)
				)
			)
		)
		(pad "2" smd custom
			(at 0 0.2794 90)
			(size 0.0762 0.0762)
			(layers "F.Cu" "F.Mask" "F.Paste")
			(net "PHY_SCC_B_TO_DRV_B_28_DN")
			(options
				(clearance outline)
				(anchor circle)
			)
			(primitives
				(gr_poly
					(pts
						(arc
							(start 0.1524 -0.127)
							(mid 0.137521 -0.162921)
							(end 0.1016 -0.1778)
						)
						(arc
							(start -0.1016 -0.1778)
							(mid -0.137521 -0.162921)
							(end -0.1524 -0.127)
						)
						(arc
							(start -0.1524 0.127)
							(mid -0.137521 0.162921)
							(end -0.1016 0.1778)
						)
						(arc
							(start 0.1016 0.1778)
							(mid 0.137521 0.162921)
							(end 0.1524 0.127)
						)
					)
					(width 0)
					(fill yes)
				)
			)
		)
	)
	(footprint ""
		(layer "F.Cu")
		(at 247.965468 -223.393 180)
		(property "Reference" "R108"
			(at 0 0 180)
			(layer "F.SilkS")
			(hide yes)
			(effects
				(font
					(size 1.27 1.27)
				)
			)
		)
		(property "Value" "4K7R2F-GP"
			(at 0.064008 -3.993896 180)
			(unlocked yes)
			(layer "F.Fab")
			(hide yes)
			(effects
				(font
					(size 1.016 1.016)
					(thickness 0.1524)
				)
			)
		)
		(property "Device Type" "R402H16"
			(at 0.064008 -5.517896 180)
			(unlocked yes)
			(layer "F.Fab")
			(hide yes)
			(effects
				(font
					(size 1.016 1.016)
					(thickness 0.1524)
				)
			)
		)
		(duplicate_pad_numbers_are_jumpers no)
		(fp_line
			(start 0.508 -0.9398)
			(end -0.508 -0.9398)
			(stroke
				(width 0.1524)
				(type default)
			)
			(layer "F.SilkS")
		)
		(fp_line
			(start -0.508 -0.9398)
			(end -0.508 0.9398)
			(stroke
				(width 0.1524)
				(type default)
			)
			(layer "F.SilkS")
		)
		(fp_rect
			(start -0.508 0.9398)
			(end 0.508 -0.9398)
			(stroke
				(width 0)
				(type default)
			)
			(fill no)
			(layer "F.CrtYd")
		)
		(fp_rect
			(start -0.508 0.9398)
			(end 0.508 -0.9398)
			(stroke
				(width 0)
				(type default)
			)
			(fill no)
			(layer "F.Fab")
		)
		(pad "1" smd custom
			(at 0 -0.4445 180)
			(size 0.1397 0.1397)
			(layers "F.Cu" "F.Mask" "F.Paste")
			(net "EEPROM_A2")
			(options
				(clearance outline)
				(anchor circle)
			)
			(primitives
				(gr_poly
					(pts
						(arc
							(start -0.1778 -0.2794)
							(mid -0.249642 -0.249642)
							(end -0.2794 -0.1778)
						)
						(arc
							(start -0.2794 0.1778)
							(mid -0.249642 0.249642)
							(end -0.1778 0.2794)
						)
						(arc
							(start 0.1778 0.2794)
							(mid 0.249642 0.249642)
							(end 0.2794 0.1778)
						)
						(arc
							(start 0.2794 -0.1778)
							(mid 0.249642 -0.249642)
							(end 0.1778 -0.2794)
						)
					)
					(width 0)
					(fill yes)
				)
			)
		)
		(pad "2" smd custom
			(at 0 0.4445 180)
			(size 0.1397 0.1397)
			(layers "F.Cu" "F.Mask" "F.Paste")
			(net "GND")
			(options
				(clearance outline)
				(anchor circle)
			)
			(primitives
				(gr_poly
					(pts
						(arc
							(start -0.1778 -0.2794)
							(mid -0.249642 -0.249642)
							(end -0.2794 -0.1778)
						)
						(arc
							(start -0.2794 0.1778)
							(mid -0.249642 0.249642)
							(end -0.1778 0.2794)
						)
						(arc
							(start 0.1778 0.2794)
							(mid 0.249642 0.249642)
							(end 0.2794 0.1778)
						)
						(arc
							(start 0.2794 -0.1778)
							(mid 0.249642 -0.249642)
							(end 0.1778 -0.2794)
						)
					)
					(width 0)
					(fill yes)
				)
			)
		)
	)
	(footprint ""
		(layer "F.Cu")
		(at 149.987 -33.274)
		(property "Reference" "R713"
			(at 0 0 0)
			(layer "F.SilkS")
			(hide yes)
			(effects
				(font
					(size 1.27 1.27)
				)
			)
		)
		(property "Value" "2R6F-GP"
			(at -0.0508 -4.8514 0)
			(unlocked yes)
			(layer "F.Fab")
			(hide yes)
			(effects
				(font
					(size 1.016 1.016)
					(thickness 0.1524)
				)
			)
		)
		(property "Device Type" "R1206H26"
			(at 0 -6.3754 0)
			(unlocked yes)
			(layer "F.Fab")
			(hide yes)
			(effects
				(font
					(size 1.016 1.016)
					(thickness 0.1524)
				)
			)
		)
		(duplicate_pad_numbers_are_jumpers no)
		(fp_line
			(start -1.016 -2.2352)
			(end 1.016 -2.2352)
			(stroke
				(width 0.1524)
				(type default)
			)
			(layer "F.SilkS")
		)
		(fp_line
			(start -1.016 2.2352)
			(end -1.016 -2.2352)
			(stroke
				(width 0.1524)
				(type default)
			)
			(layer "F.SilkS")
		)
		(fp_line
			(start 1.016 -2.2352)
			(end 1.016 2.2352)
			(stroke
				(width 0.1524)
				(type default)
			)
			(layer "F.SilkS")
		)
		(fp_line
			(start 1.016 2.2352)
			(end -1.016 2.2352)
			(stroke
				(width 0.1524)
				(type default)
			)
			(layer "F.SilkS")
		)
		(fp_rect
			(start -1.0922 2.3114)
			(end 1.0922 -2.3114)
			(stroke
				(width 0)
				(type default)
			)
			(fill no)
			(layer "F.CrtYd")
		)
		(fp_poly
			(pts
				(xy -1.0922 -2.3114) (xy 1.0922 -2.3114) (xy 1.0922 2.3114) (xy -1.0922 2.3114)
			)
			(stroke
				(width 0)
				(type default)
			)
			(fill no)
			(layer "F.Fab")
		)
		(pad "1" smd rect
			(at 0 -1.397)
			(size 1.651 1.27)
			(layers "F.Cu" "F.Mask" "F.Paste")
			(net "P5V_HDD28")
		)
		(pad "2" smd rect
			(at 0 1.397)
			(size 1.651 1.27)
			(layers "F.Cu" "F.Mask" "F.Paste")
			(net "5V_PRE_28")
		)
	)
	(footprint ""
		(layer "F.Cu")
		(at 248.285 -306.07 -90)
		(property "Reference" "R1087"
			(at 0 0 270)
			(layer "F.SilkS")
			(hide yes)
			(effects
				(font
					(size 1.27 1.27)
				)
			)
		)
		(property "Value" "4K7R2F-GP"
			(at 0.064008 -3.993896 270)
			(unlocked yes)
			(layer "F.Fab")
			(hide yes)
			(effects
				(font
					(size 1.016 1.016)
					(thickness 0.1524)
				)
			)
		)
		(property "Device Type" "R402H16"
			(at 0.064008 -5.517896 270)
			(unlocked yes)
			(layer "F.Fab")
			(hide yes)
			(effects
				(font
					(size 1.016 1.016)
					(thickness 0.1524)
				)
			)
		)
		(duplicate_pad_numbers_are_jumpers no)
		(fp_line
			(start -0.508 -0.9398)
			(end -0.508 0.9398)
			(stroke
				(width 0.1524)
				(type default)
			)
			(layer "F.SilkS")
		)
		(fp_line
			(start 0.508 -0.9398)
			(end -0.508 -0.9398)
			(stroke
				(width 0.1524)
				(type default)
			)
			(layer "F.SilkS")
		)
		(fp_rect
			(start -0.508 0.9398)
			(end 0.508 -0.9398)
			(stroke
				(width 0)
				(type default)
			)
			(fill no)
			(layer "F.CrtYd")
		)
		(fp_rect
			(start -0.508 0.9398)
			(end 0.508 -0.9398)
			(stroke
				(width 0)
				(type default)
			)
			(fill no)
			(layer "F.Fab")
		)
		(pad "1" smd custom
			(at 0 -0.4445 270)
			(size 0.1397 0.1397)
			(layers "F.Cu" "F.Mask" "F.Paste")
			(net "P3V3_STBY_A")
			(options
				(clearance outline)
				(anchor circle)
			)
			(primitives
				(gr_poly
					(pts
						(arc
							(start -0.1778 -0.2794)
							(mid -0.249642 -0.249642)
							(end -0.2794 -0.1778)
						)
						(arc
							(start -0.2794 0.1778)
							(mid -0.249642 0.249642)
							(end -0.1778 0.2794)
						)
						(arc
							(start 0.1778 0.2794)
							(mid 0.249642 0.249642)
							(end 0.2794 0.1778)
						)
						(arc
							(start 0.2794 -0.1778)
							(mid 0.249642 -0.249642)
							(end 0.1778 -0.2794)
						)
					)
					(width 0)
					(fill yes)
				)
			)
		)
		(pad "2" smd custom
			(at 0 0.4445 270)
			(size 0.1397 0.1397)
			(layers "F.Cu" "F.Mask" "F.Paste")
			(net "MAX31790_A_FAIL")
			(options
				(clearance outline)
				(anchor circle)
			)
			(primitives
				(gr_poly
					(pts
						(arc
							(start -0.1778 -0.2794)
							(mid -0.249642 -0.249642)
							(end -0.2794 -0.1778)
						)
						(arc
							(start -0.2794 0.1778)
							(mid -0.249642 0.249642)
							(end -0.1778 0.2794)
						)
						(arc
							(start 0.1778 0.2794)
							(mid 0.249642 0.249642)
							(end 0.2794 0.1778)
						)
						(arc
							(start 0.2794 -0.1778)
							(mid 0.249642 -0.249642)
							(end 0.1778 -0.2794)
						)
					)
					(width 0)
					(fill yes)
				)
			)
		)
	)
	(footprint ""
		(layer "F.Cu")
		(at 180.1368 -246.2784 -90)
		(property "Reference" "R246"
			(at 0 0 270)
			(layer "F.SilkS")
			(hide yes)
			(effects
				(font
					(size 1.27 1.27)
				)
			)
		)
		(property "Value" "0R2J-2-GP"
			(at 0.064008 -3.993896 270)
			(unlocked yes)
			(layer "F.Fab")
			(hide yes)
			(effects
				(font
					(size 1.016 1.016)
					(thickness 0.1524)
				)
			)
		)
		(property "Device Type" "R402H16"
			(at 0.064008 -5.517896 270)
			(unlocked yes)
			(layer "F.Fab")
			(hide yes)
			(effects
				(font
					(size 1.016 1.016)
					(thickness 0.1524)
				)
			)
		)
		(duplicate_pad_numbers_are_jumpers no)
		(fp_line
			(start -0.508 -0.9398)
			(end -0.508 0.9398)
			(stroke
				(width 0.1524)
				(type default)
			)
			(layer "F.SilkS")
		)
		(fp_line
			(start 0.508 -0.9398)
			(end -0.508 -0.9398)
			(stroke
				(width 0.1524)
				(type default)
			)
			(layer "F.SilkS")
		)
		(fp_rect
			(start -0.508 0.9398)
			(end 0.508 -0.9398)
			(stroke
				(width 0)
				(type default)
			)
			(fill no)
			(layer "F.CrtYd")
		)
		(fp_rect
			(start -0.508 0.9398)
			(end 0.508 -0.9398)
			(stroke
				(width 0)
				(type default)
			)
			(fill no)
			(layer "F.Fab")
		)
		(pad "1" smd custom
			(at 0 -0.4445 270)
			(size 0.1397 0.1397)
			(layers "F.Cu" "F.Mask" "F.Paste")
			(net "DRIVE_B_5_PWR")
			(options
				(clearance outline)
				(anchor circle)
			)
			(primitives
				(gr_poly
					(pts
						(arc
							(start -0.1778 -0.2794)
							(mid -0.249642 -0.249642)
							(end -0.2794 -0.1778)
						)
						(arc
							(start -0.2794 0.1778)
							(mid -0.249642 0.249642)
							(end -0.1778 0.2794)
						)
						(arc
							(start 0.1778 0.2794)
							(mid 0.249642 0.249642)
							(end 0.2794 0.1778)
						)
						(arc
							(start 0.2794 -0.1778)
							(mid 0.249642 -0.249642)
							(end 0.1778 -0.2794)
						)
					)
					(width 0)
					(fill yes)
				)
			)
		)
		(pad "2" smd custom
			(at 0 0.4445 270)
			(size 0.1397 0.1397)
			(layers "F.Cu" "F.Mask" "F.Paste")
			(net "SW_PWR_R_HDD5")
			(options
				(clearance outline)
				(anchor circle)
			)
			(primitives
				(gr_poly
					(pts
						(arc
							(start -0.1778 -0.2794)
							(mid -0.249642 -0.249642)
							(end -0.2794 -0.1778)
						)
						(arc
							(start -0.2794 0.1778)
							(mid -0.249642 0.249642)
							(end -0.1778 0.2794)
						)
						(arc
							(start 0.1778 0.2794)
							(mid 0.249642 0.249642)
							(end 0.2794 0.1778)
						)
						(arc
							(start 0.2794 -0.1778)
							(mid 0.249642 -0.249642)
							(end 0.1778 -0.2794)
						)
					)
					(width 0)
					(fill yes)
				)
			)
		)
	)
	(footprint ""
		(layer "F.Cu")
		(at 458.47 -266.827 180)
		(property "Reference" "C161"
			(at 0 0 180)
			(layer "F.SilkS")
			(hide yes)
			(effects
				(font
					(size 1.27 1.27)
				)
			)
		)
		(property "Value" "SC10U16V6KX-2GP"
			(at -0.0762 -5.1308 180)
			(unlocked yes)
			(layer "F.Fab")
			(hide yes)
			(effects
				(font
					(size 1.016 1.016)
					(thickness 0.1524)
				)
			)
		)
		(property "Device Type" "C1206H71"
			(at -0.127 -6.6548 180)
			(unlocked yes)
			(layer "F.Fab")
			(hide yes)
			(effects
				(font
					(size 1.016 1.016)
					(thickness 0.1524)
				)
			)
		)
		(duplicate_pad_numbers_are_jumpers no)
		(fp_line
			(start 1.016 2.2352)
			(end -1.016 2.2352)
			(stroke
				(width 0.1524)
				(type default)
			)
			(layer "F.SilkS")
		)
		(fp_line
			(start 1.016 0.8382)
			(end 1.016 2.2352)
			(stroke
				(width 0.1524)
				(type default)
			)
			(layer "F.SilkS")
		)
		(fp_line
			(start 1.016 -2.2352)
			(end 1.016 -0.8382)
			(stroke
				(width 0.1524)
				(type default)
			)
			(layer "F.SilkS")
		)
		(fp_line
			(start -1.016 2.2352)
			(end -1.016 0.8382)
			(stroke
				(width 0.1524)
				(type default)
			)
			(layer "F.SilkS")
		)
		(fp_line
			(start -1.016 -0.8382)
			(end -1.016 -2.2352)
			(stroke
				(width 0.1524)
				(type default)
			)
			(layer "F.SilkS")
		)
		(fp_line
			(start -1.016 -2.2352)
			(end 1.016 -2.2352)
			(stroke
				(width 0.1524)
				(type default)
			)
			(layer "F.SilkS")
		)
		(fp_rect
			(start -1.0922 2.3114)
			(end 1.0922 -2.3114)
			(stroke
				(width 0)
				(type default)
			)
			(fill no)
			(layer "F.CrtYd")
		)
		(fp_poly
			(pts
				(xy 1.0922 -2.3114) (xy 1.0922 2.3114) (xy -1.0922 2.3114) (xy -1.0922 -2.3114)
			)
			(stroke
				(width 0)
				(type default)
			)
			(fill no)
			(layer "F.Fab")
		)
		(pad "1" smd rect
			(at 0 -1.397 180)
			(size 1.651 1.27)
			(layers "F.Cu" "F.Mask" "F.Paste")
			(net "P5V_HDD10")
		)
		(pad "2" smd rect
			(at 0 1.397 180)
			(size 1.651 1.27)
			(layers "F.Cu" "F.Mask" "F.Paste")
			(net "GND")
		)
	)
	(footprint ""
		(layer "F.Cu")
		(at 14.859 -140.462 90)
		(property "Reference" "C195"
			(at 0 0 90)
			(layer "F.SilkS")
			(hide yes)
			(effects
				(font
					(size 1.27 1.27)
				)
			)
		)
		(property "Value" "SCD033U25V2KX-GP"
			(at 1.1811 -2.7051 90)
			(unlocked yes)
			(layer "F.Fab")
			(hide yes)
			(effects
				(font
					(size 1.016 1.016)
					(thickness 0.1524)
				)
			)
		)
		(property "Device Type" "C402H22"
			(at 1.1811 -4.2291 90)
			(unlocked yes)
			(layer "F.Fab")
			(hide yes)
			(effects
				(font
					(size 1.016 1.016)
					(thickness 0.1524)
				)
			)
		)
		(duplicate_pad_numbers_are_jumpers no)
		(fp_rect
			(start -0.4318 0.9525)
			(end 0.4318 -0.9525)
			(stroke
				(width 0)
				(type default)
			)
			(fill no)
			(layer "F.CrtYd")
		)
		(fp_rect
			(start -0.4318 0.9525)
			(end 0.4318 -0.9525)
			(stroke
				(width 0)
				(type default)
			)
			(fill no)
			(layer "F.Fab")
		)
		(pad "1" smd custom
			(at 0 -0.4445 90)
			(size 0.1524 0.1524)
			(layers "F.Cu" "F.Mask" "F.Paste")
			(net "P12V_B")
			(options
				(clearance outline)
				(anchor circle)
			)
			(primitives
				(gr_poly
					(pts
						(arc
							(start 0.3048 -0.2032)
							(mid 0.275042 -0.275042)
							(end 0.2032 -0.3048)
						)
						(arc
							(start -0.2032 -0.3048)
							(mid -0.275042 -0.275042)
							(end -0.3048 -0.2032)
						)
						(arc
							(start -0.3048 0.2032)
							(mid -0.275042 0.275042)
							(end -0.2032 0.3048)
						)
						(arc
							(start 0.2032 0.3048)
							(mid 0.275042 0.275042)
							(end 0.3048 0.2032)
						)
					)
					(width 0)
					(fill yes)
				)
			)
		)
		(pad "2" smd custom
			(at 0 0.4445 90)
			(size 0.1524 0.1524)
			(layers "F.Cu" "F.Mask" "F.Paste")
			(net "SW_HDD_N12")
			(options
				(clearance outline)
				(anchor circle)
			)
			(primitives
				(gr_poly
					(pts
						(arc
							(start 0.3048 -0.2032)
							(mid 0.275042 -0.275042)
							(end 0.2032 -0.3048)
						)
						(arc
							(start -0.2032 -0.3048)
							(mid -0.275042 -0.275042)
							(end -0.3048 -0.2032)
						)
						(arc
							(start -0.3048 0.2032)
							(mid -0.275042 0.275042)
							(end -0.2032 0.3048)
						)
						(arc
							(start 0.2032 0.3048)
							(mid 0.275042 0.275042)
							(end 0.3048 0.2032)
						)
					)
					(width 0)
					(fill yes)
				)
			)
		)
	)
	(footprint ""
		(layer "F.Cu")
		(at 329.278996 -364.998 180)
		(property "Reference" "R948"
			(at 0 0 180)
			(layer "F.SilkS")
			(hide yes)
			(effects
				(font
					(size 1.27 1.27)
				)
			)
		)
		(property "Value" "4K7R2F-GP"
			(at 0.064008 -3.993896 180)
			(unlocked yes)
			(layer "F.Fab")
			(hide yes)
			(effects
				(font
					(size 1.016 1.016)
					(thickness 0.1524)
				)
			)
		)
		(property "Device Type" "R402H16"
			(at 0.064008 -5.517896 180)
			(unlocked yes)
			(layer "F.Fab")
			(hide yes)
			(effects
				(font
					(size 1.016 1.016)
					(thickness 0.1524)
				)
			)
		)
		(duplicate_pad_numbers_are_jumpers no)
		(fp_line
			(start 0.508 -0.9398)
			(end -0.508 -0.9398)
			(stroke
				(width 0.1524)
				(type default)
			)
			(layer "F.SilkS")
		)
		(fp_line
			(start -0.508 -0.9398)
			(end -0.508 0.9398)
			(stroke
				(width 0.1524)
				(type default)
			)
			(layer "F.SilkS")
		)
		(fp_rect
			(start -0.508 0.9398)
			(end 0.508 -0.9398)
			(stroke
				(width 0)
				(type default)
			)
			(fill no)
			(layer "F.CrtYd")
		)
		(fp_rect
			(start -0.508 0.9398)
			(end 0.508 -0.9398)
			(stroke
				(width 0)
				(type default)
			)
			(fill no)
			(layer "F.Fab")
		)
		(pad "1" smd custom
			(at 0 -0.4445 180)
			(size 0.1397 0.1397)
			(layers "F.Cu" "F.Mask" "F.Paste")
			(net "P12V_IN")
			(options
				(clearance outline)
				(anchor circle)
			)
			(primitives
				(gr_poly
					(pts
						(arc
							(start -0.1778 -0.2794)
							(mid -0.249642 -0.249642)
							(end -0.2794 -0.1778)
						)
						(arc
							(start -0.2794 0.1778)
							(mid -0.249642 0.249642)
							(end -0.1778 0.2794)
						)
						(arc
							(start 0.1778 0.2794)
							(mid 0.249642 0.249642)
							(end 0.2794 0.1778)
						)
						(arc
							(start 0.2794 -0.1778)
							(mid 0.249642 -0.249642)
							(end 0.1778 -0.2794)
						)
					)
					(width 0)
					(fill yes)
				)
			)
		)
		(pad "2" smd custom
			(at 0 0.4445 180)
			(size 0.1397 0.1397)
			(layers "F.Cu" "F.Mask" "F.Paste")
			(net "FAN_2_TACH1")
			(options
				(clearance outline)
				(anchor circle)
			)
			(primitives
				(gr_poly
					(pts
						(arc
							(start -0.1778 -0.2794)
							(mid -0.249642 -0.249642)
							(end -0.2794 -0.1778)
						)
						(arc
							(start -0.2794 0.1778)
							(mid -0.249642 0.249642)
							(end -0.1778 0.2794)
						)
						(arc
							(start 0.1778 0.2794)
							(mid 0.249642 0.249642)
							(end 0.2794 0.1778)
						)
						(arc
							(start 0.2794 -0.1778)
							(mid 0.249642 -0.249642)
							(end 0.1778 -0.2794)
						)
					)
					(width 0)
					(fill yes)
				)
			)
		)
	)
	(footprint ""
		(layer "F.Cu")
		(at 395.351 -23.368 180)
		(property "Reference" "Q165"
			(at 0 0 180)
			(layer "F.SilkS")
			(hide yes)
			(effects
				(font
					(size 1.27 1.27)
				)
			)
		)
		(property "Value" "AO4406AL-GP"
			(at -3.707384 -1.5367 180)
			(unlocked yes)
			(layer "F.Fab")
			(hide yes)
			(effects
				(font
					(size 1.016 1.016)
					(thickness 0.1524)
				)
			)
		)
		(property "Device Type" "SOIC8H69"
			(at -3.707384 -3.0607 180)
			(unlocked yes)
			(layer "F.Fab")
			(hide yes)
			(effects
				(font
					(size 1.016 1.016)
					(thickness 0.1524)
				)
			)
		)
		(duplicate_pad_numbers_are_jumpers no)
		(fp_line
			(start 2.1336 1.4224)
			(end 2.1336 -1.4224)
			(stroke
				(width 0.1524)
				(type default)
			)
			(layer "F.SilkS")
		)
		(fp_line
			(start 2.1336 -1.4224)
			(end -2.7432 -1.4224)
			(stroke
				(width 0.1524)
				(type default)
			)
			(layer "F.SilkS")
		)
		(fp_line
			(start -2.1844 -0.0508)
			(end -2.7178 0.508)
			(stroke
				(width 0.1524)
				(type default)
			)
			(layer "F.SilkS")
		)
		(fp_line
			(start -2.6289 3.4417)
			(end -2.6289 1.4732)
			(stroke
				(width 0.381)
				(type default)
			)
			(layer "F.SilkS")
		)
		(fp_line
			(start -2.7178 -0.508)
			(end -2.1844 -0.0508)
			(stroke
				(width 0.1524)
				(type default)
			)
			(layer "F.SilkS")
		)
		(fp_line
			(start -2.7432 1.4224)
			(end 2.1336 1.4224)
			(stroke
				(width 0.1524)
				(type default)
			)
			(layer "F.SilkS")
		)
		(fp_line
			(start -2.7432 1.4224)
			(end -2.6416 1.4224)
			(stroke
				(width 0.1524)
				(type default)
			)
			(layer "F.SilkS")
		)
		(fp_line
			(start -2.7432 -1.4224)
			(end -2.7432 1.4224)
			(stroke
				(width 0.1524)
				(type default)
			)
			(layer "F.SilkS")
		)
		(fp_poly
			(pts
				(xy -2.2098 -1.4224) (xy -2.2098 1.4224) (xy 2.2098 1.4224) (xy 2.2098 -1.4224)
			)
			(stroke
				(width 0)
				(type default)
			)
			(fill yes)
			(layer "F.SilkS")
		)
		(fp_rect
			(start -2.450084 2.999994)
			(end 2.450084 -2.999994)
			(stroke
				(width 0)
				(type default)
			)
			(fill no)
			(layer "F.CrtYd")
		)
		(fp_poly
			(pts
				(xy -2.8194 3.6322) (xy -2.8194 -3.6322) (xy 2.8194 -3.6322) (xy 2.8194 1.18364) (xy 2.450084 1.18364)
				(xy 2.450084 -2.999994) (xy -2.450084 -2.999994) (xy -2.450084 2.999994) (xy 2.450084 2.999994)
				(xy 2.450084 1.18618) (xy 2.8194 1.18618) (xy 2.8194 3.6322)
			)
			(stroke
				(width 0)
				(type default)
			)
			(fill no)
			(layer "F.CrtYd")
		)
		(fp_rect
			(start -2.8194 3.6322)
			(end 2.8194 -3.6322)
			(stroke
				(width 0)
				(type default)
			)
			(fill no)
			(layer "F.Fab")
		)
		(pad "1" smd rect
			(at -1.905 2.54 180)
			(size 0.635 1.651)
			(layers "F.Cu" "F.Mask" "F.Paste")
			(net "P5V_HDD32")
		)
		(pad "2" smd rect
			(at -0.635 2.54 180)
			(size 0.635 1.651)
			(layers "F.Cu" "F.Mask" "F.Paste")
			(net "P5V_HDD32")
		)
		(pad "3" smd rect
			(at 0.635 2.54 180)
			(size 0.635 1.651)
			(layers "F.Cu" "F.Mask" "F.Paste")
			(net "P5V_HDD32")
		)
		(pad "4" smd rect
			(at 1.905 2.54 180)
			(size 0.635 1.651)
			(layers "F.Cu" "F.Mask" "F.Paste")
			(net "SW_HDD_P32")
		)
		(pad "5" smd rect
			(at 1.905 -2.54 180)
			(size 0.635 1.651)
			(layers "F.Cu" "F.Mask" "F.Paste")
			(net "P5V_B_4")
		)
		(pad "6" smd rect
			(at 0.635 -2.54 180)
			(size 0.635 1.651)
			(layers "F.Cu" "F.Mask" "F.Paste")
			(net "P5V_B_4")
		)
		(pad "7" smd rect
			(at -0.635 -2.54 180)
			(size 0.635 1.651)
			(layers "F.Cu" "F.Mask" "F.Paste")
			(net "P5V_B_4")
		)
		(pad "8" smd rect
			(at -1.905 -2.54 180)
			(size 0.635 1.651)
			(layers "F.Cu" "F.Mask" "F.Paste")
			(net "P5V_B_4")
		)
	)
	(footprint ""
		(layer "F.Cu")
		(at 386.41655 -17.4371)
		(property "Reference" "VIA66"
			(at 0 0 0)
			(layer "F.SilkS")
			(hide yes)
			(effects
				(font
					(size 1.27 1.27)
				)
			)
		)
		(property "Value" "100OHM-8L-2D36MM-L16-GP"
			(at -3.4036 -0.4572 0)
			(unlocked yes)
			(layer "F.Fab")
			(hide yes)
			(effects
				(font
					(size 1.016 1.016)
					(thickness 0.1524)
				)
			)
		)
		(property "Device Type" "VIA-PCIE-4P-427097"
			(at -3.4036 -1.9812 0)
			(unlocked yes)
			(layer "F.Fab")
			(hide yes)
			(effects
				(font
					(size 1.016 1.016)
					(thickness 0.1524)
				)
			)
		)
		(duplicate_pad_numbers_are_jumpers no)
		(fp_rect
			(start -2.1336 0.4826)
			(end 2.1336 -0.4826)
			(stroke
				(width 0)
				(type default)
			)
			(fill no)
			(layer "F.CrtYd")
		)
		(fp_rect
			(start -2.1336 0.4826)
			(end 2.1336 -0.4826)
			(stroke
				(width 0)
				(type default)
			)
			(fill no)
			(layer "F.Fab")
		)
		(pad "1" thru_hole circle
			(at -1.651 0)
			(size 0.508 0.508)
			(drill 0.254)
			(layers "*.Cu" "*.Mask")
			(remove_unused_layers no)
			(net "GND")
			(clearance 0.2286)
			(thermal_gap 0.2286)
		)
		(pad "2" thru_hole circle
			(at -0.635 0)
			(size 0.508 0.508)
			(drill 0.254)
			(layers "*.Cu" "*.Mask")
			(remove_unused_layers no)
			(net "PHY_DRV_B_TO_SCC_B_32_DP")
			(clearance 0.2286)
			(thermal_gap 0.2286)
		)
		(pad "3" thru_hole circle
			(at 0.635 0)
			(size 0.508 0.508)
			(drill 0.254)
			(layers "*.Cu" "*.Mask")
			(remove_unused_layers no)
			(net "PHY_DRV_B_TO_SCC_B_32_DN")
			(clearance 0.2286)
			(thermal_gap 0.2286)
		)
		(pad "4" thru_hole circle
			(at 1.651 0)
			(size 0.508 0.508)
			(drill 0.254)
			(layers "*.Cu" "*.Mask")
			(remove_unused_layers no)
			(net "GND")
			(clearance 0.2286)
			(thermal_gap 0.2286)
		)
	)
	(footprint ""
		(layer "F.Cu")
		(at 80.900016 -65.39992)
		(property "Reference" "LED15"
			(at 0 0 0)
			(layer "F.SilkS")
			(hide yes)
			(effects
				(font
					(size 1.27 1.27)
				)
			)
		)
		(property "Value" "LED-BY-19-GP"
			(at -2.132076 1.414018 0)
			(unlocked yes)
			(layer "F.Fab")
			(hide yes)
			(effects
				(font
					(size 1.016 1.016)
					(thickness 0.1524)
				)
			)
		)
		(property "Device Type" "LED-1615-4PH26"
			(at -2.132076 -0.109982 0)
			(unlocked yes)
			(layer "F.Fab")
			(hide yes)
			(effects
				(font
					(size 1.016 1.016)
					(thickness 0.1524)
				)
			)
		)
		(duplicate_pad_numbers_are_jumpers no)
		(fp_line
			(start -1.2954 0.254)
			(end -1.2954 1.6002)
			(stroke
				(width 0.508)
				(type default)
			)
			(layer "F.SilkS")
		)
		(fp_line
			(start -1.2954 1.6002)
			(end 1.2954 1.6002)
			(stroke
				(width 0.508)
				(type default)
			)
			(layer "F.SilkS")
		)
		(fp_line
			(start -1.1176 -1.4224)
			(end 1.1176 -1.4224)
			(stroke
				(width 0.1524)
				(type default)
			)
			(layer "F.SilkS")
		)
		(fp_line
			(start -1.1176 1.4224)
			(end -1.1176 -1.4224)
			(stroke
				(width 0.1524)
				(type default)
			)
			(layer "F.SilkS")
		)
		(fp_line
			(start 1.1176 -1.4224)
			(end 1.1176 1.4224)
			(stroke
				(width 0.1524)
				(type default)
			)
			(layer "F.SilkS")
		)
		(fp_line
			(start 1.1176 1.4224)
			(end -1.1176 1.4224)
			(stroke
				(width 0.1524)
				(type default)
			)
			(layer "F.SilkS")
		)
		(fp_line
			(start 1.2954 1.6002)
			(end 1.2954 0.254)
			(stroke
				(width 0.508)
				(type default)
			)
			(layer "F.SilkS")
		)
		(fp_rect
			(start -0.7493 0.8001)
			(end 0.7493 -0.8001)
			(stroke
				(width 0)
				(type default)
			)
			(fill no)
			(layer "F.CrtYd")
		)
		(fp_poly
			(pts
				(xy -1.3716 1.6764) (xy -1.3716 -1.6764) (xy 1.3716 -1.6764) (xy 1.3716 0.0635) (xy 0.7493 0.0635)
				(xy 0.7493 -0.8001) (xy -0.7493 -0.8001) (xy -0.7493 0.8001) (xy 0.7493 0.8001) (xy 0.7493 0.0762)
				(xy 1.3716 0.0762) (xy 1.3716 1.6764)
			)
			(stroke
				(width 0)
				(type default)
			)
			(fill no)
			(layer "F.CrtYd")
		)
		(fp_rect
			(start -1.3716 1.6764)
			(end 1.3716 -1.6764)
			(stroke
				(width 0)
				(type default)
			)
			(fill no)
			(layer "F.Fab")
		)
		(pad "1" smd rect
			(at 0.50038 -0.73025)
			(size 0.7112 0.8636)
			(layers "F.Cu" "F.Mask" "F.Paste")
			(net "DRV_ACT_14")
		)
		(pad "2" smd rect
			(at -0.50038 -0.73025)
			(size 0.7112 0.8636)
			(layers "F.Cu" "F.Mask" "F.Paste")
			(net "FLT_HDD14")
		)
		(pad "3" smd rect
			(at 0.50038 0.73025)
			(size 0.7112 0.8636)
			(layers "F.Cu" "F.Mask" "F.Paste")
			(net "DRV_ACT_14_N")
		)
		(pad "4" smd rect
			(at -0.50038 0.73025)
			(size 0.7112 0.8636)
			(layers "F.Cu" "F.Mask" "F.Paste")
			(net "FLT_HDD14_N")
		)
	)
	(footprint ""
		(layer "F.Cu")
		(at 127.761746 -368.282728 180)
		(property "Reference" "R151"
			(at 0 0 180)
			(layer "F.SilkS")
			(hide yes)
			(effects
				(font
					(size 1.27 1.27)
				)
			)
		)
		(property "Value" "300KR2F-GP"
			(at 0.064008 -3.993896 180)
			(unlocked yes)
			(layer "F.Fab")
			(hide yes)
			(effects
				(font
					(size 1.016 1.016)
					(thickness 0.1524)
				)
			)
		)
		(property "Device Type" "R402H16"
			(at 0.064008 -5.517896 180)
			(unlocked yes)
			(layer "F.Fab")
			(hide yes)
			(effects
				(font
					(size 1.016 1.016)
					(thickness 0.1524)
				)
			)
		)
		(duplicate_pad_numbers_are_jumpers no)
		(fp_line
			(start 0.508 -0.9398)
			(end -0.508 -0.9398)
			(stroke
				(width 0.1524)
				(type default)
			)
			(layer "F.SilkS")
		)
		(fp_line
			(start -0.508 -0.9398)
			(end -0.508 0.9398)
			(stroke
				(width 0.1524)
				(type default)
			)
			(layer "F.SilkS")
		)
		(fp_rect
			(start -0.508 0.9398)
			(end 0.508 -0.9398)
			(stroke
				(width 0)
				(type default)
			)
			(fill no)
			(layer "F.CrtYd")
		)
		(fp_rect
			(start -0.508 0.9398)
			(end 0.508 -0.9398)
			(stroke
				(width 0)
				(type default)
			)
			(fill no)
			(layer "F.Fab")
		)
		(pad "1" smd custom
			(at 0 -0.4445 180)
			(size 0.1397 0.1397)
			(layers "F.Cu" "F.Mask" "F.Paste")
			(net "GATE_FAN1_R")
			(options
				(clearance outline)
				(anchor circle)
			)
			(primitives
				(gr_poly
					(pts
						(arc
							(start -0.1778 -0.2794)
							(mid -0.249642 -0.249642)
							(end -0.2794 -0.1778)
						)
						(arc
							(start -0.2794 0.1778)
							(mid -0.249642 0.249642)
							(end -0.1778 0.2794)
						)
						(arc
							(start 0.1778 0.2794)
							(mid 0.249642 0.249642)
							(end 0.2794 0.1778)
						)
						(arc
							(start 0.2794 -0.1778)
							(mid 0.249642 -0.249642)
							(end 0.1778 -0.2794)
						)
					)
					(width 0)
					(fill yes)
				)
			)
		)
		(pad "2" smd custom
			(at 0 0.4445 180)
			(size 0.1397 0.1397)
			(layers "F.Cu" "F.Mask" "F.Paste")
			(net "P12V_IN")
			(options
				(clearance outline)
				(anchor circle)
			)
			(primitives
				(gr_poly
					(pts
						(arc
							(start -0.1778 -0.2794)
							(mid -0.249642 -0.249642)
							(end -0.2794 -0.1778)
						)
						(arc
							(start -0.2794 0.1778)
							(mid -0.249642 0.249642)
							(end -0.1778 0.2794)
						)
						(arc
							(start 0.1778 0.2794)
							(mid 0.249642 0.249642)
							(end 0.2794 0.1778)
						)
						(arc
							(start 0.2794 -0.1778)
							(mid 0.249642 -0.249642)
							(end 0.1778 -0.2794)
						)
					)
					(width 0)
					(fill yes)
				)
			)
		)
	)
	(footprint ""
		(layer "F.Cu")
		(at 163.90493 -366.120426 90)
		(property "Reference" "R1011"
			(at 0 0 90)
			(layer "F.SilkS")
			(hide yes)
			(effects
				(font
					(size 1.27 1.27)
				)
			)
		)
		(property "Value" "49K9R2F-L-GP"
			(at 0.064008 -3.993896 90)
			(unlocked yes)
			(layer "F.Fab")
			(hide yes)
			(effects
				(font
					(size 1.016 1.016)
					(thickness 0.1524)
				)
			)
		)
		(property "Device Type" "R402H16"
			(at 0.064008 -5.517896 90)
			(unlocked yes)
			(layer "F.Fab")
			(hide yes)
			(effects
				(font
					(size 1.016 1.016)
					(thickness 0.1524)
				)
			)
		)
		(duplicate_pad_numbers_are_jumpers no)
		(fp_line
			(start 0.508 -0.9398)
			(end -0.508 -0.9398)
			(stroke
				(width 0.1524)
				(type default)
			)
			(layer "F.SilkS")
		)
		(fp_line
			(start -0.508 -0.9398)
			(end -0.508 0.9398)
			(stroke
				(width 0.1524)
				(type default)
			)
			(layer "F.SilkS")
		)
		(fp_rect
			(start -0.508 0.9398)
			(end 0.508 -0.9398)
			(stroke
				(width 0)
				(type default)
			)
			(fill no)
			(layer "F.CrtYd")
		)
		(fp_rect
			(start -0.508 0.9398)
			(end 0.508 -0.9398)
			(stroke
				(width 0)
				(type default)
			)
			(fill no)
			(layer "F.Fab")
		)
		(pad "1" smd custom
			(at 0 -0.4445 90)
			(size 0.1397 0.1397)
			(layers "F.Cu" "F.Mask" "F.Paste")
			(net "P12V_CLIP")
			(options
				(clearance outline)
				(anchor circle)
			)
			(primitives
				(gr_poly
					(pts
						(arc
							(start -0.1778 -0.2794)
							(mid -0.249642 -0.249642)
							(end -0.2794 -0.1778)
						)
						(arc
							(start -0.2794 0.1778)
							(mid -0.249642 0.249642)
							(end -0.1778 0.2794)
						)
						(arc
							(start 0.1778 0.2794)
							(mid 0.249642 0.249642)
							(end 0.2794 0.1778)
						)
						(arc
							(start 0.2794 -0.1778)
							(mid 0.249642 -0.249642)
							(end 0.1778 -0.2794)
						)
					)
					(width 0)
					(fill yes)
				)
			)
		)
		(pad "2" smd custom
			(at 0 0.4445 90)
			(size 0.1397 0.1397)
			(layers "F.Cu" "F.Mask" "F.Paste")
			(net "MB0_CM_UV_R")
			(options
				(clearance outline)
				(anchor circle)
			)
			(primitives
				(gr_poly
					(pts
						(arc
							(start -0.1778 -0.2794)
							(mid -0.249642 -0.249642)
							(end -0.2794 -0.1778)
						)
						(arc
							(start -0.2794 0.1778)
							(mid -0.249642 0.249642)
							(end -0.1778 0.2794)
						)
						(arc
							(start 0.1778 0.2794)
							(mid 0.249642 0.249642)
							(end 0.2794 0.1778)
						)
						(arc
							(start 0.2794 -0.1778)
							(mid 0.249642 -0.249642)
							(end 0.1778 -0.2794)
						)
					)
					(width 0)
					(fill yes)
				)
			)
		)
	)
	(footprint ""
		(layer "F.Cu")
		(at 255.397 -230.886 180)
		(property "Reference" "R494"
			(at 0 0 180)
			(layer "F.SilkS")
			(hide yes)
			(effects
				(font
					(size 1.27 1.27)
				)
			)
		)
		(property "Value" "0R2J-2-GP"
			(at 0.064008 -3.993896 180)
			(unlocked yes)
			(layer "F.Fab")
			(hide yes)
			(effects
				(font
					(size 1.016 1.016)
					(thickness 0.1524)
				)
			)
		)
		(property "Device Type" "R402H16"
			(at 0.064008 -5.517896 180)
			(unlocked yes)
			(layer "F.Fab")
			(hide yes)
			(effects
				(font
					(size 1.016 1.016)
					(thickness 0.1524)
				)
			)
		)
		(duplicate_pad_numbers_are_jumpers no)
		(fp_line
			(start 0.508 -0.9398)
			(end -0.508 -0.9398)
			(stroke
				(width 0.1524)
				(type default)
			)
			(layer "F.SilkS")
		)
		(fp_line
			(start -0.508 -0.9398)
			(end -0.508 0.9398)
			(stroke
				(width 0.1524)
				(type default)
			)
			(layer "F.SilkS")
		)
		(fp_rect
			(start -0.508 0.9398)
			(end 0.508 -0.9398)
			(stroke
				(width 0)
				(type default)
			)
			(fill no)
			(layer "F.CrtYd")
		)
		(fp_rect
			(start -0.508 0.9398)
			(end 0.508 -0.9398)
			(stroke
				(width 0)
				(type default)
			)
			(fill no)
			(layer "F.Fab")
		)
		(pad "1" smd custom
			(at 0 -0.4445 180)
			(size 0.1397 0.1397)
			(layers "F.Cu" "F.Mask" "F.Paste")
			(net "SCC_FULL_PWR_EN_5V")
			(options
				(clearance outline)
				(anchor circle)
			)
			(primitives
				(gr_poly
					(pts
						(arc
							(start -0.1778 -0.2794)
							(mid -0.249642 -0.249642)
							(end -0.2794 -0.1778)
						)
						(arc
							(start -0.2794 0.1778)
							(mid -0.249642 0.249642)
							(end -0.1778 0.2794)
						)
						(arc
							(start 0.1778 0.2794)
							(mid 0.249642 0.249642)
							(end 0.2794 0.1778)
						)
						(arc
							(start 0.2794 -0.1778)
							(mid 0.249642 -0.249642)
							(end 0.1778 -0.2794)
						)
					)
					(width 0)
					(fill yes)
				)
			)
		)
		(pad "2" smd custom
			(at 0 0.4445 180)
			(size 0.1397 0.1397)
			(layers "F.Cu" "F.Mask" "F.Paste")
			(net "SCC_FULL_PWR_EN_5V_R")
			(options
				(clearance outline)
				(anchor circle)
			)
			(primitives
				(gr_poly
					(pts
						(arc
							(start -0.1778 -0.2794)
							(mid -0.249642 -0.249642)
							(end -0.2794 -0.1778)
						)
						(arc
							(start -0.2794 0.1778)
							(mid -0.249642 0.249642)
							(end -0.1778 0.2794)
						)
						(arc
							(start 0.1778 0.2794)
							(mid 0.249642 0.249642)
							(end 0.2794 0.1778)
						)
						(arc
							(start 0.2794 -0.1778)
							(mid 0.249642 -0.249642)
							(end 0.1778 -0.2794)
						)
					)
					(width 0)
					(fill yes)
				)
			)
		)
	)
	(footprint ""
		(layer "F.Cu")
		(at 475.107 -262.001 -90)
		(property "Reference" "C174"
			(at 0 0 270)
			(layer "F.SilkS")
			(hide yes)
			(effects
				(font
					(size 1.27 1.27)
				)
			)
		)
		(property "Value" "SC10U16V6KX-2GP"
			(at -0.0762 -5.1308 270)
			(unlocked yes)
			(layer "F.Fab")
			(hide yes)
			(effects
				(font
					(size 1.016 1.016)
					(thickness 0.1524)
				)
			)
		)
		(property "Device Type" "C1206H71"
			(at -0.127 -6.6548 270)
			(unlocked yes)
			(layer "F.Fab")
			(hide yes)
			(effects
				(font
					(size 1.016 1.016)
					(thickness 0.1524)
				)
			)
		)
		(duplicate_pad_numbers_are_jumpers no)
		(fp_line
			(start -1.016 2.2352)
			(end -1.016 0.8382)
			(stroke
				(width 0.1524)
				(type default)
			)
			(layer "F.SilkS")
		)
		(fp_line
			(start 1.016 2.2352)
			(end -1.016 2.2352)
			(stroke
				(width 0.1524)
				(type default)
			)
			(layer "F.SilkS")
		)
		(fp_line
			(start 1.016 0.8382)
			(end 1.016 2.2352)
			(stroke
				(width 0.1524)
				(type default)
			)
			(layer "F.SilkS")
		)
		(fp_line
			(start -1.016 -0.8382)
			(end -1.016 -2.2352)
			(stroke
				(width 0.1524)
				(type default)
			)
			(layer "F.SilkS")
		)
		(fp_line
			(start -1.016 -2.2352)
			(end 1.016 -2.2352)
			(stroke
				(width 0.1524)
				(type default)
			)
			(layer "F.SilkS")
		)
		(fp_line
			(start 1.016 -2.2352)
			(end 1.016 -0.8382)
			(stroke
				(width 0.1524)
				(type default)
			)
			(layer "F.SilkS")
		)
		(fp_rect
			(start -1.0922 2.3114)
			(end 1.0922 -2.3114)
			(stroke
				(width 0)
				(type default)
			)
			(fill no)
			(layer "F.CrtYd")
		)
		(fp_poly
			(pts
				(xy 1.0922 -2.3114) (xy 1.0922 2.3114) (xy -1.0922 2.3114) (xy -1.0922 -2.3114)
			)
			(stroke
				(width 0)
				(type default)
			)
			(fill no)
			(layer "F.Fab")
		)
		(pad "1" smd rect
			(at 0 -1.397 270)
			(size 1.651 1.27)
			(layers "F.Cu" "F.Mask" "F.Paste")
			(net "P5V_HDD11")
		)
		(pad "2" smd rect
			(at 0 1.397 270)
			(size 1.651 1.27)
			(layers "F.Cu" "F.Mask" "F.Paste")
			(net "GND")
		)
	)
	(footprint ""
		(layer "F.Cu")
		(at 428.117 -160.02 180)
		(property "Reference" "C308"
			(at 0 0 180)
			(layer "F.SilkS")
			(hide yes)
			(effects
				(font
					(size 1.27 1.27)
				)
			)
		)
		(property "Value" "SC4D7U25V5KX-1-GP"
			(at -0.0762 -6.1214 180)
			(unlocked yes)
			(layer "F.Fab")
			(hide yes)
			(effects
				(font
					(size 1.016 1.016)
					(thickness 0.1524)
				)
			)
		)
		(property "Device Type" "C805H58"
			(at -0.0762 -8.1534 180)
			(unlocked yes)
			(layer "F.Fab")
			(hide yes)
			(effects
				(font
					(size 1.016 1.016)
					(thickness 0.1524)
				)
			)
		)
		(duplicate_pad_numbers_are_jumpers no)
		(fp_line
			(start 0.635 0)
			(end -0.635 0)
			(stroke
				(width 0.508)
				(type default)
			)
			(layer "F.SilkS")
		)
		(fp_rect
			(start -0.9652 1.778)
			(end 0.9652 -1.778)
			(stroke
				(width 0)
				(type default)
			)
			(fill no)
			(layer "F.CrtYd")
		)
		(fp_poly
			(pts
				(xy -0.9652 -1.778) (xy 0.9652 -1.778) (xy 0.9652 1.778) (xy -0.9652 1.778)
			)
			(stroke
				(width 0)
				(type default)
			)
			(fill no)
			(layer "F.Fab")
		)
		(pad "1" smd rect
			(at 0 -0.9652 180)
			(size 1.397 1.143)
			(layers "F.Cu" "F.Mask" "F.Paste")
			(net "P12V_HDD21")
		)
		(pad "2" smd rect
			(at 0 0.9652 180)
			(size 1.397 1.143)
			(layers "F.Cu" "F.Mask" "F.Paste")
			(net "GND")
		)
	)
	(footprint ""
		(layer "F.Cu")
		(at 416.284664 -15.219426 -90)
		(property "Reference" "C457"
			(at 0 0 270)
			(layer "F.SilkS")
			(hide yes)
			(effects
				(font
					(size 1.27 1.27)
				)
			)
		)
		(property "Value" "SCD01U16V1KX-GP"
			(at -2.8321 -1.7399 270)
			(unlocked yes)
			(layer "F.Fab")
			(hide yes)
			(effects
				(font
					(size 1.016 1.016)
					(thickness 0.1524)
				)
			)
		)
		(property "Device Type" "C0201H13"
			(at -2.8321 -3.2639 270)
			(unlocked yes)
			(layer "F.Fab")
			(hide yes)
			(effects
				(font
					(size 1.016 1.016)
					(thickness 0.1524)
				)
			)
		)
		(duplicate_pad_numbers_are_jumpers no)
		(fp_rect
			(start -0.2794 0.6477)
			(end 0.2794 -0.6477)
			(stroke
				(width 0)
				(type default)
			)
			(fill no)
			(layer "F.CrtYd")
		)
		(fp_rect
			(start -0.2794 0.6477)
			(end 0.2794 -0.6477)
			(stroke
				(width 0)
				(type default)
			)
			(fill no)
			(layer "F.Fab")
		)
		(pad "1" smd custom
			(at 0 -0.2794 270)
			(size 0.0762 0.0762)
			(layers "F.Cu" "F.Mask" "F.Paste")
			(net "SAS_HDD_RX_N33")
			(options
				(clearance outline)
				(anchor circle)
			)
			(primitives
				(gr_poly
					(pts
						(arc
							(start 0.1524 -0.127)
							(mid 0.137521 -0.162921)
							(end 0.1016 -0.1778)
						)
						(arc
							(start -0.1016 -0.1778)
							(mid -0.137521 -0.162921)
							(end -0.1524 -0.127)
						)
						(arc
							(start -0.1524 0.127)
							(mid -0.137521 0.162921)
							(end -0.1016 0.1778)
						)
						(arc
							(start 0.1016 0.1778)
							(mid 0.137521 0.162921)
							(end 0.1524 0.127)
						)
					)
					(width 0)
					(fill yes)
				)
			)
		)
		(pad "2" smd custom
			(at 0 0.2794 270)
			(size 0.0762 0.0762)
			(layers "F.Cu" "F.Mask" "F.Paste")
			(net "PHY_SCC_B_TO_DRV_B_33_DN")
			(options
				(clearance outline)
				(anchor circle)
			)
			(primitives
				(gr_poly
					(pts
						(arc
							(start 0.1524 -0.127)
							(mid 0.137521 -0.162921)
							(end 0.1016 -0.1778)
						)
						(arc
							(start -0.1016 -0.1778)
							(mid -0.137521 -0.162921)
							(end -0.1524 -0.127)
						)
						(arc
							(start -0.1524 0.127)
							(mid -0.137521 0.162921)
							(end -0.1016 0.1778)
						)
						(arc
							(start 0.1016 0.1778)
							(mid 0.137521 0.162921)
							(end 0.1524 0.127)
						)
					)
					(width 0)
					(fill yes)
				)
			)
		)
	)
	(footprint ""
		(layer "F.Cu")
		(at 178.562 -11.4427 -90)
		(property "Reference" "R753"
			(at 0 0 270)
			(layer "F.SilkS")
			(hide yes)
			(effects
				(font
					(size 1.27 1.27)
				)
			)
		)
		(property "Value" "200KR2F-L-GP"
			(at 0.064008 -3.993896 270)
			(unlocked yes)
			(layer "F.Fab")
			(hide yes)
			(effects
				(font
					(size 1.016 1.016)
					(thickness 0.1524)
				)
			)
		)
		(property "Device Type" "R402H16"
			(at 0.064008 -5.517896 270)
			(unlocked yes)
			(layer "F.Fab")
			(hide yes)
			(effects
				(font
					(size 1.016 1.016)
					(thickness 0.1524)
				)
			)
		)
		(duplicate_pad_numbers_are_jumpers no)
		(fp_line
			(start -0.508 -0.9398)
			(end -0.508 0.9398)
			(stroke
				(width 0.1524)
				(type default)
			)
			(layer "F.SilkS")
		)
		(fp_line
			(start 0.508 -0.9398)
			(end -0.508 -0.9398)
			(stroke
				(width 0.1524)
				(type default)
			)
			(layer "F.SilkS")
		)
		(fp_rect
			(start -0.508 0.9398)
			(end 0.508 -0.9398)
			(stroke
				(width 0)
				(type default)
			)
			(fill no)
			(layer "F.CrtYd")
		)
		(fp_rect
			(start -0.508 0.9398)
			(end 0.508 -0.9398)
			(stroke
				(width 0)
				(type default)
			)
			(fill no)
			(layer "F.Fab")
		)
		(pad "1" smd custom
			(at 0 -0.4445 270)
			(size 0.1397 0.1397)
			(layers "F.Cu" "F.Mask" "F.Paste")
			(net "SW_HDD_R29")
			(options
				(clearance outline)
				(anchor circle)
			)
			(primitives
				(gr_poly
					(pts
						(arc
							(start -0.1778 -0.2794)
							(mid -0.249642 -0.249642)
							(end -0.2794 -0.1778)
						)
						(arc
							(start -0.2794 0.1778)
							(mid -0.249642 0.249642)
							(end -0.1778 0.2794)
						)
						(arc
							(start 0.1778 0.2794)
							(mid 0.249642 0.249642)
							(end 0.2794 0.1778)
						)
						(arc
							(start 0.2794 -0.1778)
							(mid 0.249642 -0.249642)
							(end 0.1778 -0.2794)
						)
					)
					(width 0)
					(fill yes)
				)
			)
		)
		(pad "2" smd custom
			(at 0 0.4445 270)
			(size 0.1397 0.1397)
			(layers "F.Cu" "F.Mask" "F.Paste")
			(net "SW_HDD_N29")
			(options
				(clearance outline)
				(anchor circle)
			)
			(primitives
				(gr_poly
					(pts
						(arc
							(start -0.1778 -0.2794)
							(mid -0.249642 -0.249642)
							(end -0.2794 -0.1778)
						)
						(arc
							(start -0.2794 0.1778)
							(mid -0.249642 0.249642)
							(end -0.1778 0.2794)
						)
						(arc
							(start 0.1778 0.2794)
							(mid 0.249642 0.249642)
							(end 0.2794 0.1778)
						)
						(arc
							(start 0.2794 -0.1778)
							(mid 0.249642 -0.249642)
							(end 0.1778 -0.2794)
						)
					)
					(width 0)
					(fill yes)
				)
			)
		)
	)
	(footprint ""
		(layer "F.Cu")
		(at 431.546 -131.826 180)
		(property "Reference" "R567"
			(at 0 0 180)
			(layer "F.SilkS")
			(hide yes)
			(effects
				(font
					(size 1.27 1.27)
				)
			)
		)
		(property "Value" "4K7R2J-2-GP"
			(at 0.064008 -3.993896 180)
			(unlocked yes)
			(layer "F.Fab")
			(hide yes)
			(effects
				(font
					(size 1.016 1.016)
					(thickness 0.1524)
				)
			)
		)
		(property "Device Type" "R402H16"
			(at 0.064008 -5.517896 180)
			(unlocked yes)
			(layer "F.Fab")
			(hide yes)
			(effects
				(font
					(size 1.016 1.016)
					(thickness 0.1524)
				)
			)
		)
		(duplicate_pad_numbers_are_jumpers no)
		(fp_line
			(start 0.508 -0.9398)
			(end -0.508 -0.9398)
			(stroke
				(width 0.1524)
				(type default)
			)
			(layer "F.SilkS")
		)
		(fp_line
			(start -0.508 -0.9398)
			(end -0.508 0.9398)
			(stroke
				(width 0.1524)
				(type default)
			)
			(layer "F.SilkS")
		)
		(fp_rect
			(start -0.508 0.9398)
			(end 0.508 -0.9398)
			(stroke
				(width 0)
				(type default)
			)
			(fill no)
			(layer "F.CrtYd")
		)
		(fp_rect
			(start -0.508 0.9398)
			(end 0.508 -0.9398)
			(stroke
				(width 0)
				(type default)
			)
			(fill no)
			(layer "F.Fab")
		)
		(pad "1" smd custom
			(at 0 -0.4445 180)
			(size 0.1397 0.1397)
			(layers "F.Cu" "F.Mask" "F.Paste")
			(net "P12V_B")
			(options
				(clearance outline)
				(anchor circle)
			)
			(primitives
				(gr_poly
					(pts
						(arc
							(start -0.1778 -0.2794)
							(mid -0.249642 -0.249642)
							(end -0.2794 -0.1778)
						)
						(arc
							(start -0.2794 0.1778)
							(mid -0.249642 0.249642)
							(end -0.1778 0.2794)
						)
						(arc
							(start 0.1778 0.2794)
							(mid 0.249642 0.249642)
							(end 0.2794 0.1778)
						)
						(arc
							(start 0.2794 -0.1778)
							(mid 0.249642 -0.249642)
							(end 0.1778 -0.2794)
						)
					)
					(width 0)
					(fill yes)
				)
			)
		)
		(pad "2" smd custom
			(at 0 0.4445 180)
			(size 0.1397 0.1397)
			(layers "F.Cu" "F.Mask" "F.Paste")
			(net "SW_HDD_R21")
			(options
				(clearance outline)
				(anchor circle)
			)
			(primitives
				(gr_poly
					(pts
						(arc
							(start -0.1778 -0.2794)
							(mid -0.249642 -0.249642)
							(end -0.2794 -0.1778)
						)
						(arc
							(start -0.2794 0.1778)
							(mid -0.249642 0.249642)
							(end -0.1778 0.2794)
						)
						(arc
							(start 0.1778 0.2794)
							(mid 0.249642 0.249642)
							(end 0.2794 0.1778)
						)
						(arc
							(start 0.2794 -0.1778)
							(mid 0.249642 -0.249642)
							(end 0.1778 -0.2794)
						)
					)
					(width 0)
					(fill yes)
				)
			)
		)
	)
	(footprint ""
		(layer "F.Cu")
		(at 172.593 -255.524 90)
		(property "Reference" "C104"
			(at 0 0 90)
			(layer "F.SilkS")
			(hide yes)
			(effects
				(font
					(size 1.27 1.27)
				)
			)
		)
		(property "Value" "SCD033U25V2KX-GP"
			(at 1.1811 -2.7051 90)
			(unlocked yes)
			(layer "F.Fab")
			(hide yes)
			(effects
				(font
					(size 1.016 1.016)
					(thickness 0.1524)
				)
			)
		)
		(property "Device Type" "C402H22"
			(at 1.1811 -4.2291 90)
			(unlocked yes)
			(layer "F.Fab")
			(hide yes)
			(effects
				(font
					(size 1.016 1.016)
					(thickness 0.1524)
				)
			)
		)
		(duplicate_pad_numbers_are_jumpers no)
		(fp_rect
			(start -0.4318 0.9525)
			(end 0.4318 -0.9525)
			(stroke
				(width 0)
				(type default)
			)
			(fill no)
			(layer "F.CrtYd")
		)
		(fp_rect
			(start -0.4318 0.9525)
			(end 0.4318 -0.9525)
			(stroke
				(width 0)
				(type default)
			)
			(fill no)
			(layer "F.Fab")
		)
		(pad "1" smd custom
			(at 0 -0.4445 90)
			(size 0.1524 0.1524)
			(layers "F.Cu" "F.Mask" "F.Paste")
			(net "P12V_B")
			(options
				(clearance outline)
				(anchor circle)
			)
			(primitives
				(gr_poly
					(pts
						(arc
							(start 0.3048 -0.2032)
							(mid 0.275042 -0.275042)
							(end 0.2032 -0.3048)
						)
						(arc
							(start -0.2032 -0.3048)
							(mid -0.275042 -0.275042)
							(end -0.3048 -0.2032)
						)
						(arc
							(start -0.3048 0.2032)
							(mid -0.275042 0.275042)
							(end -0.2032 0.3048)
						)
						(arc
							(start 0.2032 0.3048)
							(mid 0.275042 0.275042)
							(end 0.3048 0.2032)
						)
					)
					(width 0)
					(fill yes)
				)
			)
		)
		(pad "2" smd custom
			(at 0 0.4445 90)
			(size 0.1524 0.1524)
			(layers "F.Cu" "F.Mask" "F.Paste")
			(net "SW_HDD_N5")
			(options
				(clearance outline)
				(anchor circle)
			)
			(primitives
				(gr_poly
					(pts
						(arc
							(start 0.3048 -0.2032)
							(mid 0.275042 -0.275042)
							(end 0.2032 -0.3048)
						)
						(arc
							(start -0.2032 -0.3048)
							(mid -0.275042 -0.275042)
							(end -0.3048 -0.2032)
						)
						(arc
							(start -0.3048 0.2032)
							(mid -0.275042 0.275042)
							(end -0.2032 0.3048)
						)
						(arc
							(start 0.2032 0.3048)
							(mid 0.275042 0.275042)
							(end 0.3048 0.2032)
						)
					)
					(width 0)
					(fill yes)
				)
			)
		)
	)
	(footprint ""
		(layer "F.Cu")
		(at 122.849894 -258.910074 -90)
		(property "Reference" "HDDSAS3"
			(at 0 0 270)
			(layer "F.SilkS")
			(hide yes)
			(effects
				(font
					(size 1.27 1.27)
				)
			)
		)
		(property "Value" "SKT-SAS15P-14P-45-GP"
			(at -20.7645 -8.9789 270)
			(unlocked yes)
			(layer "F.Fab")
			(hide yes)
			(effects
				(font
					(size 1.016 1.016)
					(thickness 0.1524)
				)
			)
		)
		(property "Device Type" "10120818-001C-TRLF"
			(at -20.7645 -10.5029 270)
			(unlocked yes)
			(layer "F.Fab")
			(hide yes)
			(effects
				(font
					(size 1.016 1.016)
					(thickness 0.1524)
				)
			)
		)
		(duplicate_pad_numbers_are_jumpers no)
		(fp_line
			(start 1.651 4.2926)
			(end 1.651 3.0099)
			(stroke
				(width 0.1524)
				(type default)
			)
			(layer "F.SilkS")
		)
		(fp_line
			(start 8.509 4.2926)
			(end 1.651 4.2926)
			(stroke
				(width 0.1524)
				(type default)
			)
			(layer "F.SilkS")
		)
		(fp_line
			(start -23.4188 3.0099)
			(end -23.4188 -3.2512)
			(stroke
				(width 0.1524)
				(type default)
			)
			(layer "F.SilkS")
		)
		(fp_line
			(start 1.651 3.0099)
			(end -23.4188 3.0099)
			(stroke
				(width 0.1524)
				(type default)
			)
			(layer "F.SilkS")
		)
		(fp_line
			(start 8.509 3.0099)
			(end 8.509 4.2926)
			(stroke
				(width 0.1524)
				(type default)
			)
			(layer "F.SilkS")
		)
		(fp_line
			(start 23.4188 3.0099)
			(end 8.509 3.0099)
			(stroke
				(width 0.1524)
				(type default)
			)
			(layer "F.SilkS")
		)
		(fp_line
			(start -23.4188 -3.2512)
			(end 23.4188 -3.2512)
			(stroke
				(width 0.1524)
				(type default)
			)
			(layer "F.SilkS")
		)
		(fp_line
			(start 23.4188 -3.2512)
			(end 23.4188 3.0099)
			(stroke
				(width 0.1524)
				(type default)
			)
			(layer "F.SilkS")
		)
		(fp_line
			(start 15.5067 -3.3401)
			(end 16.2687 -3.3401)
			(stroke
				(width 0.3302)
				(type default)
			)
			(layer "F.SilkS")
		)
		(fp_poly
			(pts
				(xy 15.868904 -3.230372) (xy 16.503904 -3.865372) (xy 15.233904 -3.865372)
			)
			(stroke
				(width 0)
				(type default)
			)
			(fill yes)
			(layer "F.SilkS")
		)
		(fp_poly
			(pts
				(xy -22.8727 -2.7559) (xy 22.8727 -2.7559) (xy 22.8727 2.7559) (xy 8.255 2.7559) (xy 8.255 3.5179)
				(xy 1.905 3.5179) (xy 1.905 2.7559) (xy -22.8727 2.7559)
			)
			(stroke
				(width 0)
				(type default)
			)
			(fill no)
			(layer "F.CrtYd")
		)
		(fp_poly
			(pts
				(xy 1.397 4.5466) (xy 1.397 3.2639) (xy -23.6728 3.2639) (xy -23.6728 -3.5052) (xy 23.6728 -3.5052)
				(xy 23.6728 -0.00635) (xy 22.8727 -0.00635) (xy 22.8727 -2.7559) (xy -22.8727 -2.7559) (xy -22.8727 2.7559)
				(xy 1.905 2.7559) (xy 1.905 3.5179) (xy 8.255 3.5179) (xy 8.255 2.7559) (xy 22.8727 2.7559) (xy 22.8727 0.00635)
				(xy 23.6728 0.00635) (xy 23.6728 3.2639) (xy 8.763 3.2639) (xy 8.763 4.5466)
			)
			(stroke
				(width 0)
				(type default)
			)
			(fill no)
			(layer "F.CrtYd")
		)
		(fp_poly
			(pts
				(xy 1.397 4.5466) (xy 1.397 3.2639) (xy -23.6728 3.2639) (xy -23.6728 -3.5052) (xy 23.6728 -3.5052)
				(xy 23.6728 3.2639) (xy 8.763 3.2639) (xy 8.763 4.5466)
			)
			(stroke
				(width 0)
				(type default)
			)
			(fill no)
			(layer "F.Fab")
		)
		(pad "" np_thru_hole circle
			(at -18.874994 0 270)
			(size 0.254 0.254)
			(drill 1.3462)
			(layers "*.Cu" "*.Mask")
			(clearance 0.9017)
			(thermal_gap 0.9017)
		)
		(pad "" np_thru_hole circle
			(at 18.874994 0 270)
			(size 0.254 0.254)
			(drill 0.9398)
			(layers "*.Cu" "*.Mask")
			(clearance 0.6985)
			(thermal_gap 0.6985)
		)
		(pad "G1" smd rect
			(at 21.874988 0 270)
			(size 2.5908 2.5908)
			(layers "F.Cu" "F.Mask" "F.Paste")
			(net "GND")
		)
		(pad "G2" smd rect
			(at -21.874988 0 270)
			(size 2.5908 2.5908)
			(layers "F.Cu" "F.Mask" "F.Paste")
			(net "GND")
		)
		(pad "P1" smd rect
			(at 1.905 -1.82499 270)
			(size 0.6096 2.3622)
			(layers "F.Cu" "F.Mask" "F.Paste")
			(net "Net_1614")
		)
		(pad "P2" smd rect
			(at 0.635 -1.82499 270)
			(size 0.6096 2.3622)
			(layers "F.Cu" "F.Mask" "F.Paste")
			(net "Net_1615")
		)
		(pad "P3" smd rect
			(at -0.635 -1.82499 270)
			(size 0.6096 2.3622)
			(layers "F.Cu" "F.Mask" "F.Paste")
			(net "Net_1616")
		)
		(pad "P4" smd rect
			(at -1.905 -1.82499 270)
			(size 0.6096 2.3622)
			(layers "F.Cu" "F.Mask" "F.Paste")
			(net "GND")
		)
		(pad "P5" smd rect
			(at -3.175 -1.82499 270)
			(size 0.6096 2.3622)
			(layers "F.Cu" "F.Mask" "F.Paste")
			(net "HDD_PRSNT_3")
		)
		(pad "P6" smd rect
			(at -4.445 -1.82499 270)
			(size 0.6096 2.3622)
			(layers "F.Cu" "F.Mask" "F.Paste")
			(net "GND")
		)
		(pad "P7" smd rect
			(at -5.715 -1.82499 270)
			(size 0.6096 2.3622)
			(layers "F.Cu" "F.Mask" "F.Paste")
			(net "5V_PRE_3")
		)
		(pad "P8" smd rect
			(at -6.985 -1.82499 270)
			(size 0.6096 2.3622)
			(layers "F.Cu" "F.Mask" "F.Paste")
			(net "P5V_HDD3")
		)
		(pad "P9" smd rect
			(at -8.255 -1.82499 270)
			(size 0.6096 2.3622)
			(layers "F.Cu" "F.Mask" "F.Paste")
			(net "P5V_HDD3")
		)
		(pad "P10" smd rect
			(at -9.525 -1.82499 270)
			(size 0.6096 2.3622)
			(layers "F.Cu" "F.Mask" "F.Paste")
			(net "GND")
		)
		(pad "P11" smd rect
			(at -10.795 -1.82499 270)
			(size 0.6096 2.3622)
			(layers "F.Cu" "F.Mask" "F.Paste")
			(net "ACT_HDD_3")
		)
		(pad "P12" smd rect
			(at -12.065 -1.82499 270)
			(size 0.6096 2.3622)
			(layers "F.Cu" "F.Mask" "F.Paste")
			(net "GND")
		)
		(pad "P13" smd rect
			(at -13.335 -1.82499 270)
			(size 0.6096 2.3622)
			(layers "F.Cu" "F.Mask" "F.Paste")
			(net "12V_PRE_3")
		)
		(pad "P14" smd rect
			(at -14.605 -1.82499 270)
			(size 0.6096 2.3622)
			(layers "F.Cu" "F.Mask" "F.Paste")
			(net "P12V_HDD3")
		)
		(pad "P15" smd rect
			(at -15.875 -1.82499 270)
			(size 0.6096 2.3622)
			(layers "F.Cu" "F.Mask" "F.Paste")
			(net "P12V_HDD3")
		)
		(pad "S1" smd rect
			(at 15.875 -1.82499 270)
			(size 0.6096 2.3622)
			(layers "F.Cu" "F.Mask" "F.Paste")
			(net "GND")
		)
		(pad "S2" smd rect
			(at 14.605 -1.82499 270)
			(size 0.6096 2.3622)
			(layers "F.Cu" "F.Mask" "F.Paste")
			(net "SAS_HDD_RX_P3")
		)
		(pad "S3" smd rect
			(at 13.335 -1.82499 270)
			(size 0.6096 2.3622)
			(layers "F.Cu" "F.Mask" "F.Paste")
			(net "SAS_HDD_RX_N3")
		)
		(pad "S4" smd rect
			(at 12.065 -1.82499 270)
			(size 0.6096 2.3622)
			(layers "F.Cu" "F.Mask" "F.Paste")
			(net "GND")
		)
		(pad "S5" smd rect
			(at 10.795 -1.82499 270)
			(size 0.6096 2.3622)
			(layers "F.Cu" "F.Mask" "F.Paste")
			(net "PHY_DRV_B_TO_SCC_B_3_DN")
		)
		(pad "S6" smd rect
			(at 9.525 -1.82499 270)
			(size 0.6096 2.3622)
			(layers "F.Cu" "F.Mask" "F.Paste")
			(net "PHY_DRV_B_TO_SCC_B_3_DP")
		)
		(pad "S7" smd rect
			(at 8.255 -1.82499 270)
			(size 0.6096 2.3622)
			(layers "F.Cu" "F.Mask" "F.Paste")
			(net "GND")
		)
		(pad "S8" smd rect
			(at 7.480046 2.845054 270)
			(size 0.508 2.3622)
			(layers "F.Cu" "F.Mask" "F.Paste")
			(net "GND")
		)
		(pad "S9" smd rect
			(at 6.679946 2.845054 270)
			(size 0.508 2.3622)
			(layers "F.Cu" "F.Mask" "F.Paste")
			(net "Net_461")
		)
		(pad "S10" smd rect
			(at 5.8801 2.845054 270)
			(size 0.508 2.3622)
			(layers "F.Cu" "F.Mask" "F.Paste")
			(net "Net_353")
		)
		(pad "S11" smd rect
			(at 5.08 2.845054 270)
			(size 0.508 2.3622)
			(layers "F.Cu" "F.Mask" "F.Paste")
			(net "GND")
		)
		(pad "S12" smd rect
			(at 4.2799 2.845054 270)
			(size 0.508 2.3622)
			(layers "F.Cu" "F.Mask" "F.Paste")
			(net "Net_389")
		)
		(pad "S13" smd rect
			(at 3.480054 2.845054 270)
			(size 0.508 2.3622)
			(layers "F.Cu" "F.Mask" "F.Paste")
			(net "Net_425")
		)
		(pad "S14" smd rect
			(at 2.679954 2.845054 270)
			(size 0.508 2.3622)
			(layers "F.Cu" "F.Mask" "F.Paste")
			(net "GND")
		)
		(zone
			(layer "F.Cu")
			(hatch none 0.5)
			(connect_pads
				(clearance 0)
			)
			(min_thickness 0.25)
			(keepout
				(tracks not_allowed)
				(vias allowed)
				(pads allowed)
				(copperpour not_allowed)
				(footprints allowed)
			)
			(placement
				(enabled no)
				(sheetname "")
			)
			(fill
				(thermal_gap 0.5)
				(thermal_bridge_width 0.5)
				(island_removal_mode 0)
			)
			(polygon
				(pts
					(xy 126.507494 -275.648674) (xy 119.433594 -275.648674) (xy 119.433594 -282.582874) (xy 120.538494 -282.582874)
					(xy 120.538494 -278.468074) (xy 125.161294 -278.468074) (xy 125.161294 -282.582874) (xy 126.507494 -282.582874)
				)
			)
		)
		(zone
			(layer "F.Cu")
			(hatch none 0.5)
			(connect_pads
				(clearance 0)
			)
			(min_thickness 0.25)
			(keepout
				(tracks allowed)
				(vias not_allowed)
				(pads allowed)
				(copperpour not_allowed)
				(footprints allowed)
			)
			(placement
				(enabled no)
				(sheetname "")
			)
			(fill
				(thermal_gap 0.5)
				(thermal_bridge_width 0.5)
				(island_removal_mode 0)
			)
			(polygon
				(pts
					(xy 126.507494 -275.648674) (xy 119.433594 -275.648674) (xy 119.433594 -282.582874) (xy 120.538494 -282.582874)
					(xy 120.538494 -278.468074) (xy 125.161294 -278.468074) (xy 125.161294 -282.582874) (xy 126.507494 -282.582874)
				)
			)
		)
		(zone
			(layer "F.Cu")
			(hatch none 0.5)
			(connect_pads
				(clearance 0)
			)
			(min_thickness 0.25)
			(keepout
				(tracks not_allowed)
				(vias allowed)
				(pads allowed)
				(copperpour not_allowed)
				(footprints allowed)
			)
			(placement
				(enabled no)
				(sheetname "")
			)
			(fill
				(thermal_gap 0.5)
				(thermal_bridge_width 0.5)
				(island_removal_mode 0)
			)
			(polygon
				(pts
					(xy 126.507494 -242.171474) (xy 119.433594 -242.171474) (xy 119.433594 -235.237274) (xy 120.538494 -235.237274)
					(xy 120.538494 -239.352074) (xy 125.161294 -239.352074) (xy 125.161294 -235.237274) (xy 126.507494 -235.237274)
				)
			)
		)
		(zone
			(layer "F.Cu")
			(hatch none 0.5)
			(connect_pads
				(clearance 0)
			)
			(min_thickness 0.25)
			(keepout
				(tracks allowed)
				(vias not_allowed)
				(pads allowed)
				(copperpour not_allowed)
				(footprints allowed)
			)
			(placement
				(enabled no)
				(sheetname "")
			)
			(fill
				(thermal_gap 0.5)
				(thermal_bridge_width 0.5)
				(island_removal_mode 0)
			)
			(polygon
				(pts
					(xy 126.507494 -242.171474) (xy 119.433594 -242.171474) (xy 119.433594 -235.237274) (xy 120.538494 -235.237274)
					(xy 120.538494 -239.352074) (xy 125.161294 -239.352074) (xy 125.161294 -235.237274) (xy 126.507494 -235.237274)
				)
			)
		)
		(zone
			(layers "F.Cu" "B.Cu" "In1.Cu" "In2.Cu" "In3.Cu" "In4.Cu" "In5.Cu" "In6.Cu")
			(hatch none 0.5)
			(connect_pads
				(clearance 0)
			)
			(min_thickness 0.25)
			(keepout
				(tracks not_allowed)
				(vias allowed)
				(pads allowed)
				(copperpour not_allowed)
				(footprints allowed)
			)
			(placement
				(enabled no)
				(sheetname "")
			)
			(fill
				(thermal_gap 0.5)
				(thermal_bridge_width 0.5)
				(island_removal_mode 0)
			)
			(polygon
				(pts
					(arc
						(start 123.624594 -240.03508)
						(mid 122.075194 -240.03508)
						(end 123.624594 -240.03508)
					)
				)
			)
		)
		(zone
			(layers "F.Cu" "B.Cu" "In1.Cu" "In2.Cu" "In3.Cu" "In4.Cu" "In5.Cu" "In6.Cu")
			(hatch none 0.5)
			(connect_pads
				(clearance 0)
			)
			(min_thickness 0.25)
			(keepout
				(tracks not_allowed)
				(vias allowed)
				(pads allowed)
				(copperpour not_allowed)
				(footprints allowed)
			)
			(placement
				(enabled no)
				(sheetname "")
			)
			(fill
				(thermal_gap 0.5)
				(thermal_bridge_width 0.5)
				(island_removal_mode 0)
			)
			(polygon
				(pts
					(arc
						(start 123.827794 -277.785068)
						(mid 121.871994 -277.785068)
						(end 123.827794 -277.785068)
					)
				)
			)
		)
	)
	(footprint ""
		(layer "F.Cu")
		(at 280.4414 -349.3008 90)
		(property "Reference" "R1149"
			(at 0 0 90)
			(layer "F.SilkS")
			(hide yes)
			(effects
				(font
					(size 1.27 1.27)
				)
			)
		)
		(property "Value" "0R2J-2-GP"
			(at 0.064008 -3.993896 90)
			(unlocked yes)
			(layer "F.Fab")
			(hide yes)
			(effects
				(font
					(size 1.016 1.016)
					(thickness 0.1524)
				)
			)
		)
		(property "Device Type" "R402H16"
			(at 0.064008 -5.517896 90)
			(unlocked yes)
			(layer "F.Fab")
			(hide yes)
			(effects
				(font
					(size 1.016 1.016)
					(thickness 0.1524)
				)
			)
		)
		(duplicate_pad_numbers_are_jumpers no)
		(fp_line
			(start 0.508 -0.9398)
			(end -0.508 -0.9398)
			(stroke
				(width 0.1524)
				(type default)
			)
			(layer "F.SilkS")
		)
		(fp_line
			(start -0.508 -0.9398)
			(end -0.508 0.9398)
			(stroke
				(width 0.1524)
				(type default)
			)
			(layer "F.SilkS")
		)
		(fp_rect
			(start -0.508 0.9398)
			(end 0.508 -0.9398)
			(stroke
				(width 0)
				(type default)
			)
			(fill no)
			(layer "F.CrtYd")
		)
		(fp_rect
			(start -0.508 0.9398)
			(end 0.508 -0.9398)
			(stroke
				(width 0)
				(type default)
			)
			(fill no)
			(layer "F.Fab")
		)
		(pad "1" smd custom
			(at 0 -0.4445 90)
			(size 0.1397 0.1397)
			(layers "F.Cu" "F.Mask" "F.Paste")
			(net "P3V3_STBY_B")
			(options
				(clearance outline)
				(anchor circle)
			)
			(primitives
				(gr_poly
					(pts
						(arc
							(start -0.1778 -0.2794)
							(mid -0.249642 -0.249642)
							(end -0.2794 -0.1778)
						)
						(arc
							(start -0.2794 0.1778)
							(mid -0.249642 0.249642)
							(end -0.1778 0.2794)
						)
						(arc
							(start 0.1778 0.2794)
							(mid 0.249642 0.249642)
							(end 0.2794 0.1778)
						)
						(arc
							(start 0.2794 -0.1778)
							(mid 0.249642 -0.249642)
							(end 0.1778 -0.2794)
						)
					)
					(width 0)
					(fill yes)
				)
			)
		)
		(pad "2" smd custom
			(at 0 0.4445 90)
			(size 0.1397 0.1397)
			(layers "F.Cu" "F.Mask" "F.Paste")
			(net "MAX31790_B_PWM_ST1")
			(options
				(clearance outline)
				(anchor circle)
			)
			(primitives
				(gr_poly
					(pts
						(arc
							(start -0.1778 -0.2794)
							(mid -0.249642 -0.249642)
							(end -0.2794 -0.1778)
						)
						(arc
							(start -0.2794 0.1778)
							(mid -0.249642 0.249642)
							(end -0.1778 0.2794)
						)
						(arc
							(start 0.1778 0.2794)
							(mid 0.249642 0.249642)
							(end 0.2794 0.1778)
						)
						(arc
							(start 0.2794 -0.1778)
							(mid 0.249642 -0.249642)
							(end 0.1778 -0.2794)
						)
					)
					(width 0)
					(fill yes)
				)
			)
		)
	)
	(footprint ""
		(layer "F.Cu")
		(at 362.966 -160.02 180)
		(property "Reference" "C282"
			(at 0 0 180)
			(layer "F.SilkS")
			(hide yes)
			(effects
				(font
					(size 1.27 1.27)
				)
			)
		)
		(property "Value" "SC4D7U25V5KX-1-GP"
			(at -0.0762 -6.1214 180)
			(unlocked yes)
			(layer "F.Fab")
			(hide yes)
			(effects
				(font
					(size 1.016 1.016)
					(thickness 0.1524)
				)
			)
		)
		(property "Device Type" "C805H58"
			(at -0.0762 -8.1534 180)
			(unlocked yes)
			(layer "F.Fab")
			(hide yes)
			(effects
				(font
					(size 1.016 1.016)
					(thickness 0.1524)
				)
			)
		)
		(duplicate_pad_numbers_are_jumpers no)
		(fp_line
			(start 0.635 0)
			(end -0.635 0)
			(stroke
				(width 0.508)
				(type default)
			)
			(layer "F.SilkS")
		)
		(fp_rect
			(start -0.9652 1.778)
			(end 0.9652 -1.778)
			(stroke
				(width 0)
				(type default)
			)
			(fill no)
			(layer "F.CrtYd")
		)
		(fp_poly
			(pts
				(xy -0.9652 -1.778) (xy 0.9652 -1.778) (xy 0.9652 1.778) (xy -0.9652 1.778)
			)
			(stroke
				(width 0)
				(type default)
			)
			(fill no)
			(layer "F.Fab")
		)
		(pad "1" smd rect
			(at 0 -0.9652 180)
			(size 1.397 1.143)
			(layers "F.Cu" "F.Mask" "F.Paste")
			(net "P12V_HDD19")
		)
		(pad "2" smd rect
			(at 0 0.9652 180)
			(size 1.397 1.143)
			(layers "F.Cu" "F.Mask" "F.Paste")
			(net "GND")
		)
	)
	(footprint ""
		(layer "F.Cu")
		(at 473.202 -246.888 90)
		(property "Reference" "Q43"
			(at 0 0 90)
			(layer "F.SilkS")
			(hide yes)
			(effects
				(font
					(size 1.27 1.27)
				)
			)
		)
		(property "Value" "2N7002KDW-GP"
			(at -2.3622 -8.2042 90)
			(unlocked yes)
			(layer "F.Fab")
			(hide yes)
			(effects
				(font
					(size 1.016 1.016)
					(thickness 0.1524)
				)
			)
		)
		(property "Device Type" "SOT-363H44"
			(at -2.3622 -10.1092 90)
			(unlocked yes)
			(layer "F.Fab")
			(hide yes)
			(effects
				(font
					(size 1.016 1.016)
					(thickness 0.1524)
				)
			)
		)
		(duplicate_pad_numbers_are_jumpers no)
		(fp_line
			(start 1.4478 -1.7018)
			(end -1.4478 -1.7018)
			(stroke
				(width 0.1524)
				(type default)
			)
			(layer "F.SilkS")
		)
		(fp_line
			(start -1.4478 -1.7018)
			(end -1.4478 1.7018)
			(stroke
				(width 0.1524)
				(type default)
			)
			(layer "F.SilkS")
		)
		(fp_line
			(start -1.27 1.524)
			(end -1.27 0.6604)
			(stroke
				(width 0.4826)
				(type default)
			)
			(layer "F.SilkS")
		)
		(fp_line
			(start 1.4478 1.7018)
			(end 1.4478 -1.7018)
			(stroke
				(width 0.1524)
				(type default)
			)
			(layer "F.SilkS")
		)
		(fp_line
			(start -1.4478 1.7018)
			(end 1.4478 1.7018)
			(stroke
				(width 0.1524)
				(type default)
			)
			(layer "F.SilkS")
		)
		(fp_poly
			(pts
				(xy -1.524 -1.778) (xy 1.524 -1.778) (xy 1.524 1.778) (xy -1.524 1.778)
			)
			(stroke
				(width 0)
				(type default)
			)
			(fill no)
			(layer "F.CrtYd")
		)
		(fp_poly
			(pts
				(xy -1.524 -1.778) (xy 1.524 -1.778) (xy 1.524 1.778) (xy -1.524 1.778)
			)
			(stroke
				(width 0)
				(type default)
			)
			(fill no)
			(layer "F.Fab")
		)
		(pad "1" smd rect
			(at -0.65024 0.9398 90)
			(size 0.4064 1.016)
			(layers "F.Cu" "F.Mask" "F.Paste")
			(net "GND")
		)
		(pad "2" smd rect
			(at 0 0.9398 90)
			(size 0.4064 1.016)
			(layers "F.Cu" "F.Mask" "F.Paste")
			(net "SW_PWR_R_HDD11")
		)
		(pad "3" smd rect
			(at 0.65024 0.9398 90)
			(size 0.4064 1.016)
			(layers "F.Cu" "F.Mask" "F.Paste")
			(net "SW_HDD_P11")
		)
		(pad "4" smd rect
			(at 0.65024 -0.9398 90)
			(size 0.4064 1.016)
			(layers "F.Cu" "F.Mask" "F.Paste")
			(net "GND")
		)
		(pad "5" smd rect
			(at 0 -0.9398 90)
			(size 0.4064 1.016)
			(layers "F.Cu" "F.Mask" "F.Paste")
			(net "SW_HDD_G11")
		)
		(pad "6" smd rect
			(at -0.65024 -0.9398 90)
			(size 0.4064 1.016)
			(layers "F.Cu" "F.Mask" "F.Paste")
			(net "SW_HDD_R11")
		)
	)
	(footprint ""
		(layer "F.Cu")
		(at 50.999898 -379.899926 180)
		(property "Reference" "FAN1"
			(at 0 0 180)
			(layer "F.SilkS")
			(hide yes)
			(effects
				(font
					(size 1.27 1.27)
				)
			)
		)
		(property "Value" "MLX-CONN10D-7-GP"
			(at -15.641574 4.697984 180)
			(unlocked yes)
			(layer "F.Fab")
			(hide yes)
			(effects
				(font
					(size 1.016 1.016)
					(thickness 0.1524)
				)
			)
		)
		(property "Device Type" "15-24-6103"
			(at -15.641574 3.173984 180)
			(unlocked yes)
			(layer "F.Fab")
			(hide yes)
			(effects
				(font
					(size 1.016 1.016)
					(thickness 0.1524)
				)
			)
		)
		(duplicate_pad_numbers_are_jumpers no)
		(fp_line
			(start 14.0462 8.1534)
			(end -14.0462 8.1534)
			(stroke
				(width 0.1524)
				(type default)
			)
			(layer "F.SilkS")
		)
		(fp_line
			(start 14.0462 -6.4516)
			(end 14.0462 8.1534)
			(stroke
				(width 0.1524)
				(type default)
			)
			(layer "F.SilkS")
		)
		(fp_line
			(start 9.9314 -6.4516)
			(end 14.0462 -6.4516)
			(stroke
				(width 0.1524)
				(type default)
			)
			(layer "F.SilkS")
		)
		(fp_line
			(start 9.9314 -14.3256)
			(end 9.9314 -6.4516)
			(stroke
				(width 0.1524)
				(type default)
			)
			(layer "F.SilkS")
		)
		(fp_line
			(start -9.9314 -6.4516)
			(end -9.9314 -14.3256)
			(stroke
				(width 0.1524)
				(type default)
			)
			(layer "F.SilkS")
		)
		(fp_line
			(start -9.9314 -14.3256)
			(end 9.9314 -14.3256)
			(stroke
				(width 0.1524)
				(type default)
			)
			(layer "F.SilkS")
		)
		(fp_line
			(start -14.0462 8.1534)
			(end -14.0462 -6.4516)
			(stroke
				(width 0.1524)
				(type default)
			)
			(layer "F.SilkS")
		)
		(fp_line
			(start -14.0462 -6.4516)
			(end -9.9314 -6.4516)
			(stroke
				(width 0.1524)
				(type default)
			)
			(layer "F.SilkS")
		)
		(fp_circle
			(center 8.400034 -7.29996)
			(end 6.761734 -7.29996)
			(stroke
				(width 0.3048)
				(type default)
			)
			(fill no)
			(layer "F.SilkS")
		)
		(fp_circle
			(center 8.400034 -12.800076)
			(end 6.761734 -12.800076)
			(stroke
				(width 0.3048)
				(type default)
			)
			(fill no)
			(layer "F.SilkS")
		)
		(fp_circle
			(center 4.19989 -7.29996)
			(end 2.56159 -7.29996)
			(stroke
				(width 0.3048)
				(type default)
			)
			(fill no)
			(layer "F.SilkS")
		)
		(fp_circle
			(center 4.19989 -12.800076)
			(end 2.56159 -12.800076)
			(stroke
				(width 0.3048)
				(type default)
			)
			(fill no)
			(layer "F.SilkS")
		)
		(fp_circle
			(center 0 -7.29996)
			(end -1.6383 -7.29996)
			(stroke
				(width 0.3048)
				(type default)
			)
			(fill no)
			(layer "F.SilkS")
		)
		(fp_circle
			(center 0 -12.800076)
			(end -1.6383 -12.800076)
			(stroke
				(width 0.3048)
				(type default)
			)
			(fill no)
			(layer "F.SilkS")
		)
		(fp_circle
			(center -4.19989 -7.29996)
			(end -5.83819 -7.29996)
			(stroke
				(width 0.3048)
				(type default)
			)
			(fill no)
			(layer "F.SilkS")
		)
		(fp_circle
			(center -4.19989 -12.800076)
			(end -5.83819 -12.800076)
			(stroke
				(width 0.3048)
				(type default)
			)
			(fill no)
			(layer "F.SilkS")
		)
		(fp_circle
			(center -8.400034 -7.29996)
			(end -10.038334 -7.29996)
			(stroke
				(width 0.3048)
				(type default)
			)
			(fill no)
			(layer "F.SilkS")
		)
		(fp_circle
			(center -8.400034 -12.800076)
			(end -10.038334 -12.800076)
			(stroke
				(width 0.3048)
				(type default)
			)
			(fill no)
			(layer "F.SilkS")
		)
		(fp_poly
			(pts
				(xy -13.7922 7.8994) (xy -13.7922 -6.1976) (xy -9.2964 -6.1976) (xy -9.2964 -13.6906) (xy 9.2964 -13.6906)
				(xy 9.2964 -6.1976) (xy 13.7922 -6.1976) (xy 13.7922 7.8994)
			)
			(stroke
				(width 0)
				(type default)
			)
			(fill no)
			(layer "F.CrtYd")
		)
		(fp_poly
			(pts
				(xy -14.3002 8.4074) (xy -14.3002 -6.7056) (xy -10.1854 -6.7056) (xy -10.1854 -14.5796) (xy 10.1854 -14.5796)
				(xy 10.1854 -6.7056) (xy 14.3002 -6.7056) (xy 14.3002 -0.00635) (xy 13.7922 -0.00635) (xy 13.7922 -6.1976)
				(xy 9.2964 -6.1976) (xy 9.2964 -13.6906) (xy -9.2964 -13.6906) (xy -9.2964 -6.1976) (xy -13.7922 -6.1976)
				(xy -13.7922 7.8994) (xy 13.7922 7.8994) (xy 13.7922 0.00635) (xy 14.3002 0.00635) (xy 14.3002 8.4074)
			)
			(stroke
				(width 0)
				(type default)
			)
			(fill no)
			(layer "F.CrtYd")
		)
		(fp_poly
			(pts
				(xy -14.3002 8.4074) (xy -14.3002 -6.7056) (xy -10.1854 -6.7056) (xy -10.1854 -14.5796) (xy 10.1854 -14.5796)
				(xy 10.1854 -6.7056) (xy 14.3002 -6.7056) (xy 14.3002 8.4074)
			)
			(stroke
				(width 0)
				(type default)
			)
			(fill no)
			(layer "F.Fab")
		)
		(pad "" np_thru_hole circle
			(at -8.400034 0 180)
			(size 0.254 0.254)
			(drill 3.0226)
			(layers "*.Cu" "*.Mask")
			(clearance 1.7399)
			(thermal_gap 1.7399)
		)
		(pad "" np_thru_hole circle
			(at 8.400034 0 180)
			(size 0.254 0.254)
			(drill 3.0226)
			(layers "*.Cu" "*.Mask")
			(clearance 1.7399)
			(thermal_gap 1.7399)
		)
		(pad "1" thru_hole circle
			(at 8.400034 -7.29996 180)
			(size 2.5654 2.5654)
			(drill 1.8034)
			(layers "*.Cu" "*.Mask")
			(remove_unused_layers no)
			(net "FAN_0_TACH0")
			(clearance 0.127)
			(thermal_gap 0.127)
		)
		(pad "2" thru_hole circle
			(at 8.400034 -12.800076 180)
			(size 2.5654 2.5654)
			(drill 1.8034)
			(layers "*.Cu" "*.Mask")
			(remove_unused_layers no)
			(net "FAN_0_TACH1")
			(clearance 0.127)
			(thermal_gap 0.127)
		)
		(pad "3" thru_hole circle
			(at 4.19989 -7.29996 180)
			(size 2.5654 2.5654)
			(drill 1.8034)
			(layers "*.Cu" "*.Mask")
			(remove_unused_layers no)
			(net "FAN_0_PWM")
			(clearance 0.127)
			(thermal_gap 0.127)
		)
		(pad "4" thru_hole circle
			(at 4.19989 -12.800076 180)
			(size 2.5654 2.5654)
			(drill 1.8034)
			(layers "*.Cu" "*.Mask")
			(remove_unused_layers no)
			(net "FAN_0_PWM")
			(clearance 0.127)
			(thermal_gap 0.127)
		)
		(pad "5" thru_hole circle
			(at 0 -7.29996 180)
			(size 2.5654 2.5654)
			(drill 1.8034)
			(layers "*.Cu" "*.Mask")
			(remove_unused_layers no)
			(net "FAN_0_INS_N")
			(clearance 0.127)
			(thermal_gap 0.127)
		)
		(pad "6" thru_hole circle
			(at 0 -12.800076 180)
			(size 2.5654 2.5654)
			(drill 1.8034)
			(layers "*.Cu" "*.Mask")
			(remove_unused_layers no)
			(net "Net_1778")
			(clearance 0.127)
			(thermal_gap 0.127)
		)
		(pad "7" thru_hole circle
			(at -4.19989 -7.29996 180)
			(size 2.5654 2.5654)
			(drill 1.8034)
			(layers "*.Cu" "*.Mask")
			(remove_unused_layers no)
			(net "P12V_FAN0")
			(clearance 0.127)
			(thermal_gap 0.127)
		)
		(pad "8" thru_hole circle
			(at -4.19989 -12.800076 180)
			(size 2.5654 2.5654)
			(drill 1.8034)
			(layers "*.Cu" "*.Mask")
			(remove_unused_layers no)
			(net "P12V_FAN0")
			(clearance 0.127)
			(thermal_gap 0.127)
		)
		(pad "9" thru_hole circle
			(at -8.400034 -7.29996 180)
			(size 2.5654 2.5654)
			(drill 1.8034)
			(layers "*.Cu" "*.Mask")
			(remove_unused_layers no)
			(net "GND")
			(clearance 0.127)
			(thermal_gap 0.127)
		)
		(pad "10" thru_hole circle
			(at -8.400034 -12.800076 180)
			(size 2.5654 2.5654)
			(drill 1.8034)
			(layers "*.Cu" "*.Mask")
			(remove_unused_layers no)
			(net "GND")
			(clearance 0.127)
			(thermal_gap 0.127)
		)
		(zone
			(layers "F.Cu" "B.Cu" "In1.Cu" "In2.Cu" "In3.Cu" "In4.Cu" "In5.Cu" "In6.Cu")
			(hatch none 0.5)
			(connect_pads
				(clearance 0)
			)
			(min_thickness 0.25)
			(keepout
				(tracks not_allowed)
				(vias allowed)
				(pads allowed)
				(copperpour not_allowed)
				(footprints allowed)
			)
			(placement
				(enabled no)
				(sheetname "")
			)
			(fill
				(thermal_gap 0.5)
				(thermal_bridge_width 0.5)
				(island_removal_mode 0)
			)
			(polygon
				(pts
					(arc
						(start 44.415964 -379.899926)
						(mid 40.783764 -379.899926)
						(end 44.415964 -379.899926)
					)
				)
			)
		)
		(zone
			(layers "F.Cu" "B.Cu" "In1.Cu" "In2.Cu" "In3.Cu" "In4.Cu" "In5.Cu" "In6.Cu")
			(hatch none 0.5)
			(connect_pads
				(clearance 0)
			)
			(min_thickness 0.25)
			(keepout
				(tracks not_allowed)
				(vias allowed)
				(pads allowed)
				(copperpour not_allowed)
				(footprints allowed)
			)
			(placement
				(enabled no)
				(sheetname "")
			)
			(fill
				(thermal_gap 0.5)
				(thermal_bridge_width 0.5)
				(island_removal_mode 0)
			)
			(polygon
				(pts
					(arc
						(start 61.216032 -379.899926)
						(mid 57.583832 -379.899926)
						(end 61.216032 -379.899926)
					)
				)
			)
		)
	)
	(footprint ""
		(layer "F.Cu")
		(at 55.0164 -14.5796 90)
		(property "Reference" "R662"
			(at 0 0 90)
			(layer "F.SilkS")
			(hide yes)
			(effects
				(font
					(size 1.27 1.27)
				)
			)
		)
		(property "Value" "0R2J-2-GP"
			(at 0.064008 -3.993896 90)
			(unlocked yes)
			(layer "F.Fab")
			(hide yes)
			(effects
				(font
					(size 1.016 1.016)
					(thickness 0.1524)
				)
			)
		)
		(property "Device Type" "R402H16"
			(at 0.064008 -5.517896 90)
			(unlocked yes)
			(layer "F.Fab")
			(hide yes)
			(effects
				(font
					(size 1.016 1.016)
					(thickness 0.1524)
				)
			)
		)
		(duplicate_pad_numbers_are_jumpers no)
		(fp_line
			(start 0.508 -0.9398)
			(end -0.508 -0.9398)
			(stroke
				(width 0.1524)
				(type default)
			)
			(layer "F.SilkS")
		)
		(fp_line
			(start -0.508 -0.9398)
			(end -0.508 0.9398)
			(stroke
				(width 0.1524)
				(type default)
			)
			(layer "F.SilkS")
		)
		(fp_rect
			(start -0.508 0.9398)
			(end 0.508 -0.9398)
			(stroke
				(width 0)
				(type default)
			)
			(fill no)
			(layer "F.CrtYd")
		)
		(fp_rect
			(start -0.508 0.9398)
			(end 0.508 -0.9398)
			(stroke
				(width 0)
				(type default)
			)
			(fill no)
			(layer "F.Fab")
		)
		(pad "1" smd custom
			(at 0 -0.4445 90)
			(size 0.1397 0.1397)
			(layers "F.Cu" "F.Mask" "F.Paste")
			(net "SW_HDD_G25")
			(options
				(clearance outline)
				(anchor circle)
			)
			(primitives
				(gr_poly
					(pts
						(arc
							(start -0.1778 -0.2794)
							(mid -0.249642 -0.249642)
							(end -0.2794 -0.1778)
						)
						(arc
							(start -0.2794 0.1778)
							(mid -0.249642 0.249642)
							(end -0.1778 0.2794)
						)
						(arc
							(start 0.1778 0.2794)
							(mid 0.249642 0.249642)
							(end 0.2794 0.1778)
						)
						(arc
							(start 0.2794 -0.1778)
							(mid 0.249642 -0.249642)
							(end 0.1778 -0.2794)
						)
					)
					(width 0)
					(fill yes)
				)
			)
		)
		(pad "2" smd custom
			(at 0 0.4445 90)
			(size 0.1397 0.1397)
			(layers "F.Cu" "F.Mask" "F.Paste")
			(net "SW_HDD_R25")
			(options
				(clearance outline)
				(anchor circle)
			)
			(primitives
				(gr_poly
					(pts
						(arc
							(start -0.1778 -0.2794)
							(mid -0.249642 -0.249642)
							(end -0.2794 -0.1778)
						)
						(arc
							(start -0.2794 0.1778)
							(mid -0.249642 0.249642)
							(end -0.1778 0.2794)
						)
						(arc
							(start 0.1778 0.2794)
							(mid 0.249642 0.249642)
							(end 0.2794 0.1778)
						)
						(arc
							(start 0.2794 -0.1778)
							(mid 0.249642 -0.249642)
							(end 0.1778 -0.2794)
						)
					)
					(width 0)
					(fill yes)
				)
			)
		)
	)
	(footprint ""
		(layer "F.Cu")
		(at 248.285 -308.102 -90)
		(property "Reference" "R1167"
			(at 0 0 270)
			(layer "F.SilkS")
			(hide yes)
			(effects
				(font
					(size 1.27 1.27)
				)
			)
		)
		(property "Value" "0R2J-2-GP"
			(at 0.064008 -3.993896 270)
			(unlocked yes)
			(layer "F.Fab")
			(hide yes)
			(effects
				(font
					(size 1.016 1.016)
					(thickness 0.1524)
				)
			)
		)
		(property "Device Type" "R402H16"
			(at 0.064008 -5.517896 270)
			(unlocked yes)
			(layer "F.Fab")
			(hide yes)
			(effects
				(font
					(size 1.016 1.016)
					(thickness 0.1524)
				)
			)
		)
		(duplicate_pad_numbers_are_jumpers no)
		(fp_line
			(start -0.508 -0.9398)
			(end -0.508 0.9398)
			(stroke
				(width 0.1524)
				(type default)
			)
			(layer "F.SilkS")
		)
		(fp_line
			(start 0.508 -0.9398)
			(end -0.508 -0.9398)
			(stroke
				(width 0.1524)
				(type default)
			)
			(layer "F.SilkS")
		)
		(fp_rect
			(start -0.508 0.9398)
			(end 0.508 -0.9398)
			(stroke
				(width 0)
				(type default)
			)
			(fill no)
			(layer "F.CrtYd")
		)
		(fp_rect
			(start -0.508 0.9398)
			(end 0.508 -0.9398)
			(stroke
				(width 0)
				(type default)
			)
			(fill no)
			(layer "F.Fab")
		)
		(pad "1" smd custom
			(at 0 -0.4445 270)
			(size 0.1397 0.1397)
			(layers "F.Cu" "F.Mask" "F.Paste")
			(net "P3V3_STBY_A")
			(options
				(clearance outline)
				(anchor circle)
			)
			(primitives
				(gr_poly
					(pts
						(arc
							(start -0.1778 -0.2794)
							(mid -0.249642 -0.249642)
							(end -0.2794 -0.1778)
						)
						(arc
							(start -0.2794 0.1778)
							(mid -0.249642 0.249642)
							(end -0.1778 0.2794)
						)
						(arc
							(start 0.1778 0.2794)
							(mid 0.249642 0.249642)
							(end 0.2794 0.1778)
						)
						(arc
							(start 0.2794 -0.1778)
							(mid 0.249642 -0.249642)
							(end 0.1778 -0.2794)
						)
					)
					(width 0)
					(fill yes)
				)
			)
		)
		(pad "2" smd custom
			(at 0 0.4445 270)
			(size 0.1397 0.1397)
			(layers "F.Cu" "F.Mask" "F.Paste")
			(net "MAX31790_A_PWM_ST0")
			(options
				(clearance outline)
				(anchor circle)
			)
			(primitives
				(gr_poly
					(pts
						(arc
							(start -0.1778 -0.2794)
							(mid -0.249642 -0.249642)
							(end -0.2794 -0.1778)
						)
						(arc
							(start -0.2794 0.1778)
							(mid -0.249642 0.249642)
							(end -0.1778 0.2794)
						)
						(arc
							(start 0.1778 0.2794)
							(mid 0.249642 0.249642)
							(end 0.2794 0.1778)
						)
						(arc
							(start 0.2794 -0.1778)
							(mid 0.249642 -0.249642)
							(end 0.1778 -0.2794)
						)
					)
					(width 0)
					(fill yes)
				)
			)
		)
	)
	(footprint ""
		(layer "F.Cu")
		(at 473.0242 -7.1882 180)
		(property "Reference" "R891"
			(at 0 0 180)
			(layer "F.SilkS")
			(hide yes)
			(effects
				(font
					(size 1.27 1.27)
				)
			)
		)
		(property "Value" "200KR2F-L-GP"
			(at 0.064008 -3.993896 180)
			(unlocked yes)
			(layer "F.Fab")
			(hide yes)
			(effects
				(font
					(size 1.016 1.016)
					(thickness 0.1524)
				)
			)
		)
		(property "Device Type" "R402H16"
			(at 0.064008 -5.517896 180)
			(unlocked yes)
			(layer "F.Fab")
			(hide yes)
			(effects
				(font
					(size 1.016 1.016)
					(thickness 0.1524)
				)
			)
		)
		(duplicate_pad_numbers_are_jumpers no)
		(fp_line
			(start 0.508 -0.9398)
			(end -0.508 -0.9398)
			(stroke
				(width 0.1524)
				(type default)
			)
			(layer "F.SilkS")
		)
		(fp_line
			(start -0.508 -0.9398)
			(end -0.508 0.9398)
			(stroke
				(width 0.1524)
				(type default)
			)
			(layer "F.SilkS")
		)
		(fp_rect
			(start -0.508 0.9398)
			(end 0.508 -0.9398)
			(stroke
				(width 0)
				(type default)
			)
			(fill no)
			(layer "F.CrtYd")
		)
		(fp_rect
			(start -0.508 0.9398)
			(end 0.508 -0.9398)
			(stroke
				(width 0)
				(type default)
			)
			(fill no)
			(layer "F.Fab")
		)
		(pad "1" smd custom
			(at 0 -0.4445 180)
			(size 0.1397 0.1397)
			(layers "F.Cu" "F.Mask" "F.Paste")
			(net "SW_HDD_R35")
			(options
				(clearance outline)
				(anchor circle)
			)
			(primitives
				(gr_poly
					(pts
						(arc
							(start -0.1778 -0.2794)
							(mid -0.249642 -0.249642)
							(end -0.2794 -0.1778)
						)
						(arc
							(start -0.2794 0.1778)
							(mid -0.249642 0.249642)
							(end -0.1778 0.2794)
						)
						(arc
							(start 0.1778 0.2794)
							(mid 0.249642 0.249642)
							(end 0.2794 0.1778)
						)
						(arc
							(start 0.2794 -0.1778)
							(mid 0.249642 -0.249642)
							(end 0.1778 -0.2794)
						)
					)
					(width 0)
					(fill yes)
				)
			)
		)
		(pad "2" smd custom
			(at 0 0.4445 180)
			(size 0.1397 0.1397)
			(layers "F.Cu" "F.Mask" "F.Paste")
			(net "SW_HDD_N35")
			(options
				(clearance outline)
				(anchor circle)
			)
			(primitives
				(gr_poly
					(pts
						(arc
							(start -0.1778 -0.2794)
							(mid -0.249642 -0.249642)
							(end -0.2794 -0.1778)
						)
						(arc
							(start -0.2794 0.1778)
							(mid -0.249642 0.249642)
							(end -0.1778 0.2794)
						)
						(arc
							(start 0.1778 0.2794)
							(mid 0.249642 0.249642)
							(end 0.2794 0.1778)
						)
						(arc
							(start 0.2794 -0.1778)
							(mid 0.249642 -0.249642)
							(end 0.1778 -0.2794)
						)
					)
					(width 0)
					(fill yes)
				)
			)
		)
	)
	(footprint ""
		(layer "F.Cu")
		(at 241.386106 -352.755962 180)
		(property "Reference" "C563"
			(at 0 0 180)
			(layer "F.SilkS")
			(hide yes)
			(effects
				(font
					(size 1.27 1.27)
				)
			)
		)
		(property "Value" "SCD1U25V2KX-2-GP"
			(at 1.1811 -2.7051 180)
			(unlocked yes)
			(layer "F.Fab")
			(hide yes)
			(effects
				(font
					(size 1.016 1.016)
					(thickness 0.1524)
				)
			)
		)
		(property "Device Type" "C402H22"
			(at 1.1811 -4.2291 180)
			(unlocked yes)
			(layer "F.Fab")
			(hide yes)
			(effects
				(font
					(size 1.016 1.016)
					(thickness 0.1524)
				)
			)
		)
		(duplicate_pad_numbers_are_jumpers no)
		(fp_rect
			(start -0.4318 0.9525)
			(end 0.4318 -0.9525)
			(stroke
				(width 0)
				(type default)
			)
			(fill no)
			(layer "F.CrtYd")
		)
		(fp_rect
			(start -0.4318 0.9525)
			(end 0.4318 -0.9525)
			(stroke
				(width 0)
				(type default)
			)
			(fill no)
			(layer "F.Fab")
		)
		(pad "1" smd custom
			(at 0 -0.4445 180)
			(size 0.1524 0.1524)
			(layers "F.Cu" "F.Mask" "F.Paste")
			(net "P12V_IN")
			(options
				(clearance outline)
				(anchor circle)
			)
			(primitives
				(gr_poly
					(pts
						(arc
							(start 0.3048 -0.2032)
							(mid 0.275042 -0.275042)
							(end 0.2032 -0.3048)
						)
						(arc
							(start -0.2032 -0.3048)
							(mid -0.275042 -0.275042)
							(end -0.3048 -0.2032)
						)
						(arc
							(start -0.3048 0.2032)
							(mid -0.275042 0.275042)
							(end -0.2032 0.3048)
						)
						(arc
							(start 0.2032 0.3048)
							(mid 0.275042 0.275042)
							(end 0.3048 0.2032)
						)
					)
					(width 0)
					(fill yes)
				)
			)
		)
		(pad "2" smd custom
			(at 0 0.4445 180)
			(size 0.1524 0.1524)
			(layers "F.Cu" "F.Mask" "F.Paste")
			(net "GND")
			(options
				(clearance outline)
				(anchor circle)
			)
			(primitives
				(gr_poly
					(pts
						(arc
							(start 0.3048 -0.2032)
							(mid 0.275042 -0.275042)
							(end 0.2032 -0.3048)
						)
						(arc
							(start -0.2032 -0.3048)
							(mid -0.275042 -0.275042)
							(end -0.3048 -0.2032)
						)
						(arc
							(start -0.3048 0.2032)
							(mid -0.275042 0.275042)
							(end -0.2032 0.3048)
						)
						(arc
							(start 0.2032 0.3048)
							(mid 0.275042 0.275042)
							(end 0.3048 0.2032)
						)
					)
					(width 0)
					(fill yes)
				)
			)
		)
	)
	(footprint ""
		(layer "F.Cu")
		(at 14.859 -255.524 90)
		(property "Reference" "C507"
			(at 0 0 90)
			(layer "F.SilkS")
			(hide yes)
			(effects
				(font
					(size 1.27 1.27)
				)
			)
		)
		(property "Value" "SCD033U25V2KX-GP"
			(at 1.1811 -2.7051 90)
			(unlocked yes)
			(layer "F.Fab")
			(hide yes)
			(effects
				(font
					(size 1.016 1.016)
					(thickness 0.1524)
				)
			)
		)
		(property "Device Type" "C402H22"
			(at 1.1811 -4.2291 90)
			(unlocked yes)
			(layer "F.Fab")
			(hide yes)
			(effects
				(font
					(size 1.016 1.016)
					(thickness 0.1524)
				)
			)
		)
		(duplicate_pad_numbers_are_jumpers no)
		(fp_rect
			(start -0.4318 0.9525)
			(end 0.4318 -0.9525)
			(stroke
				(width 0)
				(type default)
			)
			(fill no)
			(layer "F.CrtYd")
		)
		(fp_rect
			(start -0.4318 0.9525)
			(end 0.4318 -0.9525)
			(stroke
				(width 0)
				(type default)
			)
			(fill no)
			(layer "F.Fab")
		)
		(pad "1" smd custom
			(at 0 -0.4445 90)
			(size 0.1524 0.1524)
			(layers "F.Cu" "F.Mask" "F.Paste")
			(net "P12V_B")
			(options
				(clearance outline)
				(anchor circle)
			)
			(primitives
				(gr_poly
					(pts
						(arc
							(start 0.3048 -0.2032)
							(mid 0.275042 -0.275042)
							(end 0.2032 -0.3048)
						)
						(arc
							(start -0.2032 -0.3048)
							(mid -0.275042 -0.275042)
							(end -0.3048 -0.2032)
						)
						(arc
							(start -0.3048 0.2032)
							(mid -0.275042 0.275042)
							(end -0.2032 0.3048)
						)
						(arc
							(start 0.2032 0.3048)
							(mid 0.275042 0.275042)
							(end 0.3048 0.2032)
						)
					)
					(width 0)
					(fill yes)
				)
			)
		)
		(pad "2" smd custom
			(at 0 0.4445 90)
			(size 0.1524 0.1524)
			(layers "F.Cu" "F.Mask" "F.Paste")
			(net "SW_HDD_N0")
			(options
				(clearance outline)
				(anchor circle)
			)
			(primitives
				(gr_poly
					(pts
						(arc
							(start 0.3048 -0.2032)
							(mid 0.275042 -0.275042)
							(end 0.2032 -0.3048)
						)
						(arc
							(start -0.2032 -0.3048)
							(mid -0.275042 -0.275042)
							(end -0.3048 -0.2032)
						)
						(arc
							(start -0.3048 0.2032)
							(mid -0.275042 0.275042)
							(end -0.2032 0.3048)
						)
						(arc
							(start 0.2032 0.3048)
							(mid 0.275042 0.275042)
							(end 0.3048 0.2032)
						)
					)
					(width 0)
					(fill yes)
				)
			)
		)
	)
	(footprint ""
		(layer "F.Cu")
		(at 192.035684 -244.990874 90)
		(property "Reference" "VIA11"
			(at 0 0 90)
			(layer "F.SilkS")
			(hide yes)
			(effects
				(font
					(size 1.27 1.27)
				)
			)
		)
		(property "Value" "100OHM-8L-2D36MM-L18-GP"
			(at 3.8989 0.5715 90)
			(unlocked yes)
			(layer "F.Fab")
			(hide yes)
			(effects
				(font
					(size 1.016 1.016)
					(thickness 0.1524)
				)
			)
		)
		(property "Device Type" "VIA-PCIE-4P-414097"
			(at 3.8989 -0.9525 90)
			(unlocked yes)
			(layer "F.Fab")
			(hide yes)
			(effects
				(font
					(size 1.016 1.016)
					(thickness 0.1524)
				)
			)
		)
		(duplicate_pad_numbers_are_jumpers no)
		(fp_rect
			(start -2.0701 0.4826)
			(end 2.0701 -0.4826)
			(stroke
				(width 0)
				(type default)
			)
			(fill no)
			(layer "F.CrtYd")
		)
		(fp_rect
			(start -2.0701 0.4826)
			(end 2.0701 -0.4826)
			(stroke
				(width 0)
				(type default)
			)
			(fill no)
			(layer "F.Fab")
		)
		(pad "1" thru_hole circle
			(at -1.5875 0 90)
			(size 0.508 0.508)
			(drill 0.254)
			(layers "*.Cu" "*.Mask")
			(remove_unused_layers no)
			(net "GND")
			(clearance 0.2286)
			(thermal_gap 0.2286)
		)
		(pad "2" thru_hole circle
			(at -0.5715 0 90)
			(size 0.508 0.508)
			(drill 0.254)
			(layers "*.Cu" "*.Mask")
			(remove_unused_layers no)
			(net "PHY_SCC_B_TO_DRV_B_5_DP")
			(clearance 0.2286)
			(thermal_gap 0.2286)
		)
		(pad "3" thru_hole circle
			(at 0.5715 0 90)
			(size 0.508 0.508)
			(drill 0.254)
			(layers "*.Cu" "*.Mask")
			(remove_unused_layers no)
			(net "PHY_SCC_B_TO_DRV_B_5_DN")
			(clearance 0.2286)
			(thermal_gap 0.2286)
		)
		(pad "4" thru_hole circle
			(at 1.5875 0 90)
			(size 0.508 0.508)
			(drill 0.254)
			(layers "*.Cu" "*.Mask")
			(remove_unused_layers no)
			(net "GND")
			(clearance 0.2286)
			(thermal_gap 0.2286)
		)
	)
	(footprint ""
		(layer "F.Cu")
		(at 298.6532 -332.9686 180)
		(property "Reference" "C21"
			(at 0 0 180)
			(layer "F.SilkS")
			(hide yes)
			(effects
				(font
					(size 1.27 1.27)
				)
			)
		)
		(property "Value" "SCD1U16V2KX-3GP"
			(at 1.1811 -2.7051 180)
			(unlocked yes)
			(layer "F.Fab")
			(hide yes)
			(effects
				(font
					(size 1.016 1.016)
					(thickness 0.1524)
				)
			)
		)
		(property "Device Type" "C402H22"
			(at 1.1811 -4.2291 180)
			(unlocked yes)
			(layer "F.Fab")
			(hide yes)
			(effects
				(font
					(size 1.016 1.016)
					(thickness 0.1524)
				)
			)
		)
		(duplicate_pad_numbers_are_jumpers no)
		(fp_rect
			(start -0.4318 0.9525)
			(end 0.4318 -0.9525)
			(stroke
				(width 0)
				(type default)
			)
			(fill no)
			(layer "F.CrtYd")
		)
		(fp_rect
			(start -0.4318 0.9525)
			(end 0.4318 -0.9525)
			(stroke
				(width 0)
				(type default)
			)
			(fill no)
			(layer "F.Fab")
		)
		(pad "1" smd custom
			(at 0 -0.4445 180)
			(size 0.1524 0.1524)
			(layers "F.Cu" "F.Mask" "F.Paste")
			(net "P3V3_IN")
			(options
				(clearance outline)
				(anchor circle)
			)
			(primitives
				(gr_poly
					(pts
						(arc
							(start 0.3048 -0.2032)
							(mid 0.275042 -0.275042)
							(end 0.2032 -0.3048)
						)
						(arc
							(start -0.2032 -0.3048)
							(mid -0.275042 -0.275042)
							(end -0.3048 -0.2032)
						)
						(arc
							(start -0.3048 0.2032)
							(mid -0.275042 0.275042)
							(end -0.2032 0.3048)
						)
						(arc
							(start 0.2032 0.3048)
							(mid 0.275042 0.275042)
							(end 0.3048 0.2032)
						)
					)
					(width 0)
					(fill yes)
				)
			)
		)
		(pad "2" smd custom
			(at 0 0.4445 180)
			(size 0.1524 0.1524)
			(layers "F.Cu" "F.Mask" "F.Paste")
			(net "GND")
			(options
				(clearance outline)
				(anchor circle)
			)
			(primitives
				(gr_poly
					(pts
						(arc
							(start 0.3048 -0.2032)
							(mid 0.275042 -0.275042)
							(end 0.2032 -0.3048)
						)
						(arc
							(start -0.2032 -0.3048)
							(mid -0.275042 -0.275042)
							(end -0.3048 -0.2032)
						)
						(arc
							(start -0.3048 0.2032)
							(mid -0.275042 0.275042)
							(end -0.2032 0.3048)
						)
						(arc
							(start 0.2032 0.3048)
							(mid 0.275042 0.275042)
							(end 0.3048 0.2032)
						)
					)
					(width 0)
					(fill yes)
				)
			)
		)
	)
	(footprint ""
		(layer "F.Cu")
		(at 426.1866 -250.5202 -90)
		(property "Reference" "C155"
			(at 0 0 270)
			(layer "F.SilkS")
			(hide yes)
			(effects
				(font
					(size 1.27 1.27)
				)
			)
		)
		(property "Value" "SCD033U25V2KX-GP"
			(at 1.1811 -2.7051 270)
			(unlocked yes)
			(layer "F.Fab")
			(hide yes)
			(effects
				(font
					(size 1.016 1.016)
					(thickness 0.1524)
				)
			)
		)
		(property "Device Type" "C402H22"
			(at 1.1811 -4.2291 270)
			(unlocked yes)
			(layer "F.Fab")
			(hide yes)
			(effects
				(font
					(size 1.016 1.016)
					(thickness 0.1524)
				)
			)
		)
		(duplicate_pad_numbers_are_jumpers no)
		(fp_rect
			(start -0.4318 0.9525)
			(end 0.4318 -0.9525)
			(stroke
				(width 0)
				(type default)
			)
			(fill no)
			(layer "F.CrtYd")
		)
		(fp_rect
			(start -0.4318 0.9525)
			(end 0.4318 -0.9525)
			(stroke
				(width 0)
				(type default)
			)
			(fill no)
			(layer "F.Fab")
		)
		(pad "1" smd custom
			(at 0 -0.4445 270)
			(size 0.1524 0.1524)
			(layers "F.Cu" "F.Mask" "F.Paste")
			(net "SW_HDD_P9")
			(options
				(clearance outline)
				(anchor circle)
			)
			(primitives
				(gr_poly
					(pts
						(arc
							(start 0.3048 -0.2032)
							(mid 0.275042 -0.275042)
							(end 0.2032 -0.3048)
						)
						(arc
							(start -0.2032 -0.3048)
							(mid -0.275042 -0.275042)
							(end -0.3048 -0.2032)
						)
						(arc
							(start -0.3048 0.2032)
							(mid -0.275042 0.275042)
							(end -0.2032 0.3048)
						)
						(arc
							(start 0.2032 0.3048)
							(mid 0.275042 0.275042)
							(end 0.3048 0.2032)
						)
					)
					(width 0)
					(fill yes)
				)
			)
		)
		(pad "2" smd custom
			(at 0 0.4445 270)
			(size 0.1524 0.1524)
			(layers "F.Cu" "F.Mask" "F.Paste")
			(net "GND")
			(options
				(clearance outline)
				(anchor circle)
			)
			(primitives
				(gr_poly
					(pts
						(arc
							(start 0.3048 -0.2032)
							(mid 0.275042 -0.275042)
							(end 0.2032 -0.3048)
						)
						(arc
							(start -0.2032 -0.3048)
							(mid -0.275042 -0.275042)
							(end -0.3048 -0.2032)
						)
						(arc
							(start -0.3048 0.2032)
							(mid -0.275042 0.275042)
							(end -0.2032 0.3048)
						)
						(arc
							(start 0.2032 0.3048)
							(mid 0.275042 0.275042)
							(end 0.3048 0.2032)
						)
					)
					(width 0)
					(fill yes)
				)
			)
		)
	)
	(footprint ""
		(layer "F.Cu")
		(at 340.251796 -97.390204 -90)
		(property "Reference" "R472"
			(at 0 0 270)
			(layer "F.SilkS")
			(hide yes)
			(effects
				(font
					(size 1.27 1.27)
				)
			)
		)
		(property "Value" "4K7R2F-GP"
			(at 0.064008 -3.993896 270)
			(unlocked yes)
			(layer "F.Fab")
			(hide yes)
			(effects
				(font
					(size 1.016 1.016)
					(thickness 0.1524)
				)
			)
		)
		(property "Device Type" "R402H16"
			(at 0.064008 -5.517896 270)
			(unlocked yes)
			(layer "F.Fab")
			(hide yes)
			(effects
				(font
					(size 1.016 1.016)
					(thickness 0.1524)
				)
			)
		)
		(duplicate_pad_numbers_are_jumpers no)
		(fp_line
			(start -0.508 -0.9398)
			(end -0.508 0.9398)
			(stroke
				(width 0.1524)
				(type default)
			)
			(layer "F.SilkS")
		)
		(fp_line
			(start 0.508 -0.9398)
			(end -0.508 -0.9398)
			(stroke
				(width 0.1524)
				(type default)
			)
			(layer "F.SilkS")
		)
		(fp_rect
			(start -0.508 0.9398)
			(end 0.508 -0.9398)
			(stroke
				(width 0)
				(type default)
			)
			(fill no)
			(layer "F.CrtYd")
		)
		(fp_rect
			(start -0.508 0.9398)
			(end 0.508 -0.9398)
			(stroke
				(width 0)
				(type default)
			)
			(fill no)
			(layer "F.Fab")
		)
		(pad "1" smd custom
			(at 0 -0.4445 270)
			(size 0.1397 0.1397)
			(layers "F.Cu" "F.Mask" "F.Paste")
			(net "DRIVE_B_19_ACT")
			(options
				(clearance outline)
				(anchor circle)
			)
			(primitives
				(gr_poly
					(pts
						(arc
							(start -0.1778 -0.2794)
							(mid -0.249642 -0.249642)
							(end -0.2794 -0.1778)
						)
						(arc
							(start -0.2794 0.1778)
							(mid -0.249642 0.249642)
							(end -0.1778 0.2794)
						)
						(arc
							(start 0.1778 0.2794)
							(mid 0.249642 0.249642)
							(end 0.2794 0.1778)
						)
						(arc
							(start 0.2794 -0.1778)
							(mid 0.249642 -0.249642)
							(end 0.1778 -0.2794)
						)
					)
					(width 0)
					(fill yes)
				)
			)
		)
		(pad "2" smd custom
			(at 0 0.4445 270)
			(size 0.1397 0.1397)
			(layers "F.Cu" "F.Mask" "F.Paste")
			(net "GND")
			(options
				(clearance outline)
				(anchor circle)
			)
			(primitives
				(gr_poly
					(pts
						(arc
							(start -0.1778 -0.2794)
							(mid -0.249642 -0.249642)
							(end -0.2794 -0.1778)
						)
						(arc
							(start -0.2794 0.1778)
							(mid -0.249642 0.249642)
							(end -0.1778 0.2794)
						)
						(arc
							(start 0.1778 0.2794)
							(mid 0.249642 0.249642)
							(end 0.2794 0.1778)
						)
						(arc
							(start 0.2794 -0.1778)
							(mid 0.249642 -0.249642)
							(end 0.1778 -0.2794)
						)
					)
					(width 0)
					(fill yes)
				)
			)
		)
	)
	(footprint ""
		(layer "F.Cu")
		(at 43.528996 -362.077 180)
		(property "Reference" "Q211"
			(at 0 0 180)
			(layer "F.SilkS")
			(hide yes)
			(effects
				(font
					(size 1.27 1.27)
				)
			)
		)
		(property "Value" "2N7002K-2-GP"
			(at 0.127 -8.9662 180)
			(unlocked yes)
			(layer "F.Fab")
			(hide yes)
			(effects
				(font
					(size 1.016 1.016)
					(thickness 0.1524)
				)
			)
		)
		(property "Device Type" "SOT23DGS2D4H44"
			(at 0.127 -10.4902 180)
			(unlocked yes)
			(layer "F.Fab")
			(hide yes)
			(effects
				(font
					(size 1.016 1.016)
					(thickness 0.1524)
				)
			)
		)
		(duplicate_pad_numbers_are_jumpers no)
		(fp_line
			(start 1.651 1.778)
			(end 1.651 -1.778)
			(stroke
				(width 0.1524)
				(type default)
			)
			(layer "F.SilkS")
		)
		(fp_line
			(start 1.651 -1.778)
			(end -1.651 -1.778)
			(stroke
				(width 0.1524)
				(type default)
			)
			(layer "F.SilkS")
		)
		(fp_line
			(start -1.651 1.778)
			(end 1.651 1.778)
			(stroke
				(width 0.1524)
				(type default)
			)
			(layer "F.SilkS")
		)
		(fp_line
			(start -1.651 -1.778)
			(end -1.651 1.778)
			(stroke
				(width 0.1524)
				(type default)
			)
			(layer "F.SilkS")
		)
		(fp_poly
			(pts
				(xy -1.778 1.8796) (xy -1.778 -1.8796) (xy 1.778 -1.8796) (xy 1.778 1.8796)
			)
			(stroke
				(width 0)
				(type default)
			)
			(fill no)
			(layer "F.CrtYd")
		)
		(fp_poly
			(pts
				(xy -1.778 1.8796) (xy -1.778 -1.8796) (xy 1.778 -1.8796) (xy 1.778 1.8796)
			)
			(stroke
				(width 0)
				(type default)
			)
			(fill no)
			(layer "F.Fab")
		)
		(pad "D" smd custom
			(at 0 -0.9525 180)
			(size 0.1905 0.1905)
			(layers "F.Cu" "F.Mask" "F.Paste")
			(net "GATE_FAN0")
			(options
				(clearance outline)
				(anchor circle)
			)
			(primitives
				(gr_poly
					(pts
						(arc
							(start -0.1778 0.5715)
							(mid -0.321484 0.511984)
							(end -0.381 0.3683)
						)
						(arc
							(start -0.381 -0.3683)
							(mid -0.321484 -0.511984)
							(end -0.1778 -0.5715)
						)
						(arc
							(start 0.1778 -0.5715)
							(mid 0.321484 -0.511984)
							(end 0.381 -0.3683)
						)
						(arc
							(start 0.381 0.3683)
							(mid 0.321484 0.511984)
							(end 0.1778 0.5715)
						)
					)
					(width 0)
					(fill yes)
				)
			)
		)
		(pad "G" smd custom
			(at -0.98425 0.9525 180)
			(size 0.1905 0.1905)
			(layers "F.Cu" "F.Mask" "F.Paste")
			(net "FAN_EN")
			(options
				(clearance outline)
				(anchor circle)
			)
			(primitives
				(gr_poly
					(pts
						(arc
							(start -0.1778 0.5715)
							(mid -0.321484 0.511984)
							(end -0.381 0.3683)
						)
						(arc
							(start -0.381 -0.3683)
							(mid -0.321484 -0.511984)
							(end -0.1778 -0.5715)
						)
						(arc
							(start 0.1778 -0.5715)
							(mid 0.321484 -0.511984)
							(end 0.381 -0.3683)
						)
						(arc
							(start 0.381 0.3683)
							(mid 0.321484 0.511984)
							(end 0.1778 0.5715)
						)
					)
					(width 0)
					(fill yes)
				)
			)
		)
		(pad "S" smd custom
			(at 0.98425 0.9525 180)
			(size 0.1905 0.1905)
			(layers "F.Cu" "F.Mask" "F.Paste")
			(net "GND")
			(options
				(clearance outline)
				(anchor circle)
			)
			(primitives
				(gr_poly
					(pts
						(arc
							(start -0.1778 0.5715)
							(mid -0.321484 0.511984)
							(end -0.381 0.3683)
						)
						(arc
							(start -0.381 -0.3683)
							(mid -0.321484 -0.511984)
							(end -0.1778 -0.5715)
						)
						(arc
							(start 0.1778 -0.5715)
							(mid 0.321484 -0.511984)
							(end 0.381 -0.3683)
						)
						(arc
							(start 0.381 0.3683)
							(mid 0.321484 0.511984)
							(end 0.1778 0.5715)
						)
					)
					(width 0)
					(fill yes)
				)
			)
		)
	)
	(footprint ""
		(layer "F.Cu")
		(at 365.125 -155.6004 -90)
		(property "Reference" "R508"
			(at 0 0 270)
			(layer "F.SilkS")
			(hide yes)
			(effects
				(font
					(size 1.27 1.27)
				)
			)
		)
		(property "Value" "2R6F-GP"
			(at -0.0508 -4.8514 270)
			(unlocked yes)
			(layer "F.Fab")
			(hide yes)
			(effects
				(font
					(size 1.016 1.016)
					(thickness 0.1524)
				)
			)
		)
		(property "Device Type" "R1206H26"
			(at 0 -6.3754 270)
			(unlocked yes)
			(layer "F.Fab")
			(hide yes)
			(effects
				(font
					(size 1.016 1.016)
					(thickness 0.1524)
				)
			)
		)
		(duplicate_pad_numbers_are_jumpers no)
		(fp_line
			(start -1.016 2.2352)
			(end -1.016 -2.2352)
			(stroke
				(width 0.1524)
				(type default)
			)
			(layer "F.SilkS")
		)
		(fp_line
			(start 1.016 2.2352)
			(end -1.016 2.2352)
			(stroke
				(width 0.1524)
				(type default)
			)
			(layer "F.SilkS")
		)
		(fp_line
			(start -1.016 -2.2352)
			(end 1.016 -2.2352)
			(stroke
				(width 0.1524)
				(type default)
			)
			(layer "F.SilkS")
		)
		(fp_line
			(start 1.016 -2.2352)
			(end 1.016 2.2352)
			(stroke
				(width 0.1524)
				(type default)
			)
			(layer "F.SilkS")
		)
		(fp_rect
			(start -1.0922 2.3114)
			(end 1.0922 -2.3114)
			(stroke
				(width 0)
				(type default)
			)
			(fill no)
			(layer "F.CrtYd")
		)
		(fp_poly
			(pts
				(xy -1.0922 -2.3114) (xy 1.0922 -2.3114) (xy 1.0922 2.3114) (xy -1.0922 2.3114)
			)
			(stroke
				(width 0)
				(type default)
			)
			(fill no)
			(layer "F.Fab")
		)
		(pad "1" smd rect
			(at 0 -1.397 270)
			(size 1.651 1.27)
			(layers "F.Cu" "F.Mask" "F.Paste")
			(net "P12V_HDD19")
		)
		(pad "2" smd rect
			(at 0 1.397 270)
			(size 1.651 1.27)
			(layers "F.Cu" "F.Mask" "F.Paste")
			(net "12V_PRE_19")
		)
	)
	(footprint ""
		(layer "F.Cu")
		(at 169.672 -361.696)
		(property "Reference" "C545"
			(at 0 0 0)
			(layer "F.SilkS")
			(hide yes)
			(effects
				(font
					(size 1.27 1.27)
				)
			)
		)
		(property "Value" "SCD1U25V2KX-2-GP"
			(at 1.1811 -2.7051 0)
			(unlocked yes)
			(layer "F.Fab")
			(hide yes)
			(effects
				(font
					(size 1.016 1.016)
					(thickness 0.1524)
				)
			)
		)
		(property "Device Type" "C402H22"
			(at 1.1811 -4.2291 0)
			(unlocked yes)
			(layer "F.Fab")
			(hide yes)
			(effects
				(font
					(size 1.016 1.016)
					(thickness 0.1524)
				)
			)
		)
		(duplicate_pad_numbers_are_jumpers no)
		(fp_rect
			(start -0.4318 0.9525)
			(end 0.4318 -0.9525)
			(stroke
				(width 0)
				(type default)
			)
			(fill no)
			(layer "F.CrtYd")
		)
		(fp_rect
			(start -0.4318 0.9525)
			(end 0.4318 -0.9525)
			(stroke
				(width 0)
				(type default)
			)
			(fill no)
			(layer "F.Fab")
		)
		(pad "1" smd custom
			(at 0 -0.4445)
			(size 0.1524 0.1524)
			(layers "F.Cu" "F.Mask" "F.Paste")
			(net "MB0_PSET_R")
			(options
				(clearance outline)
				(anchor circle)
			)
			(primitives
				(gr_poly
					(pts
						(arc
							(start 0.3048 -0.2032)
							(mid 0.275042 -0.275042)
							(end 0.2032 -0.3048)
						)
						(arc
							(start -0.2032 -0.3048)
							(mid -0.275042 -0.275042)
							(end -0.3048 -0.2032)
						)
						(arc
							(start -0.3048 0.2032)
							(mid -0.275042 0.275042)
							(end -0.2032 0.3048)
						)
						(arc
							(start 0.2032 0.3048)
							(mid 0.275042 0.275042)
							(end 0.3048 0.2032)
						)
					)
					(width 0)
					(fill yes)
				)
			)
		)
		(pad "2" smd custom
			(at 0 0.4445)
			(size 0.1524 0.1524)
			(layers "F.Cu" "F.Mask" "F.Paste")
			(net "AGND_CURRENT_MON")
			(options
				(clearance outline)
				(anchor circle)
			)
			(primitives
				(gr_poly
					(pts
						(arc
							(start 0.3048 -0.2032)
							(mid 0.275042 -0.275042)
							(end 0.2032 -0.3048)
						)
						(arc
							(start -0.2032 -0.3048)
							(mid -0.275042 -0.275042)
							(end -0.3048 -0.2032)
						)
						(arc
							(start -0.3048 0.2032)
							(mid -0.275042 0.275042)
							(end -0.2032 0.3048)
						)
						(arc
							(start 0.2032 0.3048)
							(mid 0.275042 0.275042)
							(end 0.3048 0.2032)
						)
					)
					(width 0)
					(fill yes)
				)
			)
		)
	)
	(footprint ""
		(layer "F.Cu")
		(at 137.538968 -97.404428 -90)
		(property "Reference" "R394"
			(at 0 0 270)
			(layer "F.SilkS")
			(hide yes)
			(effects
				(font
					(size 1.27 1.27)
				)
			)
		)
		(property "Value" "4K7R2F-GP"
			(at 0.064008 -3.993896 270)
			(unlocked yes)
			(layer "F.Fab")
			(hide yes)
			(effects
				(font
					(size 1.016 1.016)
					(thickness 0.1524)
				)
			)
		)
		(property "Device Type" "R402H16"
			(at 0.064008 -5.517896 270)
			(unlocked yes)
			(layer "F.Fab")
			(hide yes)
			(effects
				(font
					(size 1.016 1.016)
					(thickness 0.1524)
				)
			)
		)
		(duplicate_pad_numbers_are_jumpers no)
		(fp_line
			(start -0.508 -0.9398)
			(end -0.508 0.9398)
			(stroke
				(width 0.1524)
				(type default)
			)
			(layer "F.SilkS")
		)
		(fp_line
			(start 0.508 -0.9398)
			(end -0.508 -0.9398)
			(stroke
				(width 0.1524)
				(type default)
			)
			(layer "F.SilkS")
		)
		(fp_rect
			(start -0.508 0.9398)
			(end 0.508 -0.9398)
			(stroke
				(width 0)
				(type default)
			)
			(fill no)
			(layer "F.CrtYd")
		)
		(fp_rect
			(start -0.508 0.9398)
			(end 0.508 -0.9398)
			(stroke
				(width 0)
				(type default)
			)
			(fill no)
			(layer "F.Fab")
		)
		(pad "1" smd custom
			(at 0 -0.4445 270)
			(size 0.1397 0.1397)
			(layers "F.Cu" "F.Mask" "F.Paste")
			(net "DRIVE_B_16_ACT")
			(options
				(clearance outline)
				(anchor circle)
			)
			(primitives
				(gr_poly
					(pts
						(arc
							(start -0.1778 -0.2794)
							(mid -0.249642 -0.249642)
							(end -0.2794 -0.1778)
						)
						(arc
							(start -0.2794 0.1778)
							(mid -0.249642 0.249642)
							(end -0.1778 0.2794)
						)
						(arc
							(start 0.1778 0.2794)
							(mid 0.249642 0.249642)
							(end 0.2794 0.1778)
						)
						(arc
							(start 0.2794 -0.1778)
							(mid 0.249642 -0.249642)
							(end 0.1778 -0.2794)
						)
					)
					(width 0)
					(fill yes)
				)
			)
		)
		(pad "2" smd custom
			(at 0 0.4445 270)
			(size 0.1397 0.1397)
			(layers "F.Cu" "F.Mask" "F.Paste")
			(net "GND")
			(options
				(clearance outline)
				(anchor circle)
			)
			(primitives
				(gr_poly
					(pts
						(arc
							(start -0.1778 -0.2794)
							(mid -0.249642 -0.249642)
							(end -0.2794 -0.1778)
						)
						(arc
							(start -0.2794 0.1778)
							(mid -0.249642 0.249642)
							(end -0.1778 0.2794)
						)
						(arc
							(start 0.1778 0.2794)
							(mid 0.249642 0.249642)
							(end 0.2794 0.1778)
						)
						(arc
							(start 0.2794 -0.1778)
							(mid 0.249642 -0.249642)
							(end 0.1778 -0.2794)
						)
					)
					(width 0)
					(fill yes)
				)
			)
		)
	)
	(footprint ""
		(layer "F.Cu")
		(at 210.000088 -66.799968)
		(property "Reference" "DPB1"
			(at 0 0 0)
			(layer "F.SilkS")
			(hide yes)
			(effects
				(font
					(size 1.27 1.27)
				)
			)
		)
		(property "Value" "AMP-CONN150-13R-7-GP"
			(at -11.7475 -21.488654 0)
			(unlocked yes)
			(layer "F.Fab")
			(hide yes)
			(effects
				(font
					(size 1.016 1.016)
					(thickness 0.1524)
				)
			)
		)
		(property "Device Type" "PREFIT-150P-234294H542"
			(at -11.7475 -23.012654 0)
			(unlocked yes)
			(layer "F.Fab")
			(hide yes)
			(effects
				(font
					(size 1.016 1.016)
					(thickness 0.1524)
				)
			)
		)
		(duplicate_pad_numbers_are_jumpers no)
		(fp_line
			(start -0.9398 -15.748)
			(end 22.9616 -15.748)
			(stroke
				(width 0.1524)
				(type default)
			)
			(layer "F.SilkS")
		)
		(fp_line
			(start -0.9398 3.800094)
			(end -0.9398 -15.748)
			(stroke
				(width 0.1524)
				(type default)
			)
			(layer "F.SilkS")
		)
		(fp_line
			(start 22.9616 -15.748)
			(end 22.9616 3.800094)
			(stroke
				(width 0.1524)
				(type default)
			)
			(layer "F.SilkS")
		)
		(fp_line
			(start 22.9616 3.800094)
			(end -0.9398 3.800094)
			(stroke
				(width 0.1524)
				(type default)
			)
			(layer "F.SilkS")
		)
		(fp_poly
			(pts
				(xy 22.098 3.800094) (xy 22.098 2.88417) (xy 22.184106 2.88417) (xy 22.184106 -13.884148) (xy 15.9512 -13.884148)
				(xy 15.9512 -15.3416) (xy 5.6134 -15.3416) (xy 5.6134 -13.884148) (xy -0.9398 -13.884148) (xy -0.9398 -15.748)
				(xy 22.9616 -15.748) (xy 22.9616 3.800094)
			)
			(stroke
				(width 0)
				(type default)
			)
			(fill yes)
			(layer "F.SilkS")
		)
		(fp_poly
			(pts
				(arc
					(start 0.3556 3.5052)
					(mid 0.1524 3.7084)
					(end -0.0508 3.5052)
				)
				(arc
					(start -0.0508 3.0988)
					(mid 0.1524 2.8956)
					(end 0.3556 3.0988)
				)
			)
			(stroke
				(width 0)
				(type default)
			)
			(fill yes)
			(layer "F.SilkS")
		)
		(fp_poly
			(pts
				(arc
					(start 1.9812 3.5052)
					(mid 1.778 3.7084)
					(end 1.5748 3.5052)
				)
				(arc
					(start 1.5748 3.0988)
					(mid 1.778 2.8956)
					(end 1.9812 3.0988)
				)
			)
			(stroke
				(width 0)
				(type default)
			)
			(fill yes)
			(layer "F.SilkS")
		)
		(fp_poly
			(pts
				(arc
					(start 3.781044 3.5052)
					(mid 3.577844 3.7084)
					(end 3.374644 3.5052)
				)
				(arc
					(start 3.374644 3.0988)
					(mid 3.577844 2.8956)
					(end 3.781044 3.0988)
				)
			)
			(stroke
				(width 0)
				(type default)
			)
			(fill yes)
			(layer "F.SilkS")
		)
		(fp_poly
			(pts
				(arc
					(start 5.580888 3.5052)
					(mid 5.377688 3.7084)
					(end 5.174488 3.5052)
				)
				(arc
					(start 5.174488 3.0988)
					(mid 5.377688 2.8956)
					(end 5.580888 3.0988)
				)
			)
			(stroke
				(width 0)
				(type default)
			)
			(fill yes)
			(layer "F.SilkS")
		)
		(fp_poly
			(pts
				(arc
					(start 7.380732 3.5052)
					(mid 7.177532 3.7084)
					(end 6.974332 3.5052)
				)
				(arc
					(start 6.974332 3.0988)
					(mid 7.177532 2.8956)
					(end 7.380732 3.0988)
				)
			)
			(stroke
				(width 0)
				(type default)
			)
			(fill yes)
			(layer "F.SilkS")
		)
		(fp_poly
			(pts
				(arc
					(start 9.180576 3.5052)
					(mid 8.977376 3.7084)
					(end 8.774176 3.5052)
				)
				(arc
					(start 8.774176 3.0988)
					(mid 8.977376 2.8956)
					(end 9.180576 3.0988)
				)
			)
			(stroke
				(width 0)
				(type default)
			)
			(fill yes)
			(layer "F.SilkS")
		)
		(fp_poly
			(pts
				(arc
					(start 10.98042 3.5052)
					(mid 10.77722 3.7084)
					(end 10.57402 3.5052)
				)
				(arc
					(start 10.57402 3.0988)
					(mid 10.77722 2.8956)
					(end 10.98042 3.0988)
				)
			)
			(stroke
				(width 0)
				(type default)
			)
			(fill yes)
			(layer "F.SilkS")
		)
		(fp_poly
			(pts
				(arc
					(start 12.780264 3.5052)
					(mid 12.577064 3.7084)
					(end 12.373864 3.5052)
				)
				(arc
					(start 12.373864 3.0988)
					(mid 12.577064 2.8956)
					(end 12.780264 3.0988)
				)
			)
			(stroke
				(width 0)
				(type default)
			)
			(fill yes)
			(layer "F.SilkS")
		)
		(fp_poly
			(pts
				(arc
					(start 16.379952 3.5052)
					(mid 16.176752 3.7084)
					(end 15.973552 3.5052)
				)
				(arc
					(start 15.973552 3.0988)
					(mid 16.176752 2.8956)
					(end 16.379952 3.0988)
				)
			)
			(stroke
				(width 0)
				(type default)
			)
			(fill yes)
			(layer "F.SilkS")
		)
		(fp_poly
			(pts
				(arc
					(start 18.179796 3.5052)
					(mid 17.976596 3.7084)
					(end 17.773396 3.5052)
				)
				(arc
					(start 17.773396 3.0988)
					(mid 17.976596 2.8956)
					(end 18.179796 3.0988)
				)
			)
			(stroke
				(width 0)
				(type default)
			)
			(fill yes)
			(layer "F.SilkS")
		)
		(fp_poly
			(pts
				(arc
					(start 19.97964 3.5052)
					(mid 19.77644 3.7084)
					(end 19.57324 3.5052)
				)
				(arc
					(start 19.57324 3.0988)
					(mid 19.77644 2.8956)
					(end 19.97964 3.0988)
				)
			)
			(stroke
				(width 0)
				(type default)
			)
			(fill yes)
			(layer "F.SilkS")
		)
		(fp_poly
			(pts
				(arc
					(start 21.779484 3.5052)
					(mid 21.576284 3.7084)
					(end 21.373084 3.5052)
				)
				(arc
					(start 21.373084 3.0988)
					(mid 21.576284 2.8956)
					(end 21.779484 3.0988)
				)
			)
			(stroke
				(width 0)
				(type default)
			)
			(fill yes)
			(layer "F.SilkS")
		)
		(fp_rect
			(start -5.3848 7.6962)
			(end 26.9748 -18.6944)
			(stroke
				(width 0)
				(type default)
			)
			(fill no)
			(layer "B.CrtYd")
		)
		(fp_rect
			(start -0.6858 13.8938)
			(end 22.7076 -15.494)
			(stroke
				(width 0)
				(type default)
			)
			(fill no)
			(layer "F.CrtYd")
		)
		(fp_poly
			(pts
				(xy -5.6896 18.8976) (xy -5.6896 -20.4978) (xy 27.7114 -20.4978) (xy 27.7114 -0.00635) (xy 23.2156 -0.00635)
				(xy 23.2156 -16.002) (xy -1.1938 -16.002) (xy -1.1938 14.4018) (xy 23.2156 14.4018) (xy 23.2156 0.00635)
				(xy 27.7114 0.00635) (xy 27.7114 18.8976)
			)
			(stroke
				(width 0)
				(type default)
			)
			(fill no)
			(layer "F.CrtYd")
		)
		(fp_poly
			(pts
				(xy -1.1938 14.4018) (xy -1.1938 -16.002) (xy 23.2156 -16.002) (xy 23.2156 -0.00635) (xy 22.7076 -0.00635)
				(xy 22.7076 -15.494) (xy -0.6858 -15.494) (xy -0.6858 13.8938) (xy 22.7076 13.8938) (xy 22.7076 0.00635)
				(xy 23.2156 0.00635) (xy 23.2156 14.4018)
			)
			(stroke
				(width 0)
				(type default)
			)
			(fill no)
			(layer "F.CrtYd")
		)
		(fp_rect
			(start -10.3886 12.7)
			(end 31.9786 -23.6982)
			(stroke
				(width 0)
				(type default)
			)
			(fill no)
			(layer "B.Fab")
		)
		(fp_rect
			(start -5.3848 7.6962)
			(end 26.9748 -18.6944)
			(stroke
				(width 0)
				(type default)
			)
			(fill no)
			(layer "B.Fab")
		)
		(fp_rect
			(start -10.6934 23.9014)
			(end 32.7152 -25.5016)
			(stroke
				(width 0)
				(type default)
			)
			(fill no)
			(layer "F.Fab")
		)
		(fp_rect
			(start -5.6896 18.8976)
			(end 27.7114 -20.4978)
			(stroke
				(width 0)
				(type default)
			)
			(fill no)
			(layer "F.Fab")
		)
		(fp_rect
			(start -1.1938 14.4018)
			(end 23.2156 -16.002)
			(stroke
				(width 0)
				(type default)
			)
			(fill no)
			(layer "F.Fab")
		)
		(fp_text user "Press Fit"
			(at 5.6388 -14.5542 0)
			(unlocked yes)
			(layer "F.SilkS")
			(effects
				(font
					(size 1.016 1.016)
					(thickness 0.1524)
				)
				(justify left)
			)
		)
		(fp_text user "Slit"
			(at 7.627366 5.900928 0)
			(unlocked yes)
			(layer "F.SilkS")
			(effects
				(font
					(size 1.016 1.016)
					(thickness 0.1524)
				)
				(justify left)
			)
		)
		(fp_text user "Can not place BGA,CSP,Wave Solder component"
			(at -14.1986 10.7188 0)
			(unlocked yes)
			(layer "B.Fab")
			(effects
				(font
					(size 1.016 1.016)
					(thickness 0.1524)
				)
				(justify left)
			)
		)
		(fp_text user "Can not place BGA,CSP,Wave Solder component"
			(at -13.0048 21.7932 0)
			(unlocked yes)
			(layer "F.Fab")
			(effects
				(font
					(size 1.016 1.016)
					(thickness 0.1524)
				)
				(justify left)
			)
		)
		(fp_text user "High Limit 2mm"
			(at 3.556 16.3068 0)
			(unlocked yes)
			(layer "F.Fab")
			(effects
				(font
					(size 1.016 1.016)
					(thickness 0.1524)
				)
				(justify left)
			)
		)
		(pad "A1" thru_hole circle
			(at 0 0)
			(size 0.762 0.762)
			(drill 0.359918)
			(layers "*.Cu" "*.Mask")
			(remove_unused_layers no)
			(net "PWM_BMC_B_ZONE_C")
			(clearance 0.1651)
			(thermal_gap 0.1651)
		)
		(pad "A2" thru_hole circle
			(at 1.800098 1.199896)
			(size 0.762 0.762)
			(drill 0.359918)
			(layers "*.Cu" "*.Mask")
			(remove_unused_layers no)
			(net "PCIE_COMP_B_TO_SCC_B_1_DP")
			(clearance 0.1651)
			(thermal_gap 0.1651)
		)
		(pad "A3" thru_hole circle
			(at 3.599942 0)
			(size 0.762 0.762)
			(drill 0.359918)
			(layers "*.Cu" "*.Mask")
			(remove_unused_layers no)
			(net "I2C_DPB_B_SCL")
			(clearance 0.1651)
			(thermal_gap 0.1651)
		)
		(pad "A4" thru_hole circle
			(at 5.40004 1.199896)
			(size 0.762 0.762)
			(drill 0.359918)
			(layers "*.Cu" "*.Mask")
			(remove_unused_layers no)
			(net "PCIE_COMP_B_TO_SCC_B_3_DP")
			(clearance 0.1651)
			(thermal_gap 0.1651)
		)
		(pad "A5" thru_hole circle
			(at 7.199884 0)
			(size 0.762 0.762)
			(drill 0.359918)
			(layers "*.Cu" "*.Mask")
			(remove_unused_layers no)
			(net "I2C_BMC_A_EXP_B_SCL")
			(clearance 0.1651)
			(thermal_gap 0.1651)
		)
		(pad "A6" thru_hole circle
			(at 8.999982 1.199896)
			(size 0.762 0.762)
			(drill 0.359918)
			(layers "*.Cu" "*.Mask")
			(remove_unused_layers no)
			(net "PCIE_COMP_B_TO_SCC_B_5_DP")
			(clearance 0.1651)
			(thermal_gap 0.1651)
		)
		(pad "A7" thru_hole circle
			(at 10.80008 0)
			(size 0.762 0.762)
			(drill 0.359918)
			(layers "*.Cu" "*.Mask")
			(remove_unused_layers no)
			(net "UART_EXP_B_TX")
			(clearance 0.1651)
			(thermal_gap 0.1651)
		)
		(pad "A8" thru_hole circle
			(at 12.599924 1.199896)
			(size 0.762 0.762)
			(drill 0.359918)
			(layers "*.Cu" "*.Mask")
			(remove_unused_layers no)
			(net "PCIE_COMP_B_TO_SCC_B_7_DP")
			(clearance 0.1651)
			(thermal_gap 0.1651)
		)
		(pad "A9" thru_hole circle
			(at 16.20012 0)
			(size 0.762 0.762)
			(drill 0.359918)
			(layers "*.Cu" "*.Mask")
			(remove_unused_layers no)
			(net "SCC_B_STBY_PGOOD")
			(clearance 0.1651)
			(thermal_gap 0.1651)
		)
		(pad "A10" thru_hole circle
			(at 17.999964 2.29997)
			(size 0.762 0.762)
			(drill 0.359918)
			(layers "*.Cu" "*.Mask")
			(remove_unused_layers no)
			(net "SCC_B_PWR_LED")
			(clearance 0.1651)
			(thermal_gap 0.1651)
		)
		(pad "A11" thru_hole circle
			(at 19.800062 0)
			(size 0.762 0.762)
			(drill 0.359918)
			(layers "*.Cu" "*.Mask")
			(remove_unused_layers no)
			(net "DRIVE_B_24_ACT")
			(clearance 0.1651)
			(thermal_gap 0.1651)
		)
		(pad "A12" thru_hole circle
			(at 21.599906 2.29997)
			(size 0.762 0.762)
			(drill 0.359918)
			(layers "*.Cu" "*.Mask")
			(remove_unused_layers no)
			(net "BMC_B_EXP_B_SPARE_0")
			(clearance 0.1651)
			(thermal_gap 0.1651)
		)
		(pad "B1" thru_hole circle
			(at 0 -1.400048)
			(size 0.762 0.762)
			(drill 0.359918)
			(layers "*.Cu" "*.Mask")
			(remove_unused_layers no)
			(net "PWM_BMC_B_ZONE_D")
			(clearance 0.1651)
			(thermal_gap 0.1651)
		)
		(pad "B2" thru_hole circle
			(at 1.800098 -0.199898)
			(size 0.762 0.762)
			(drill 0.359918)
			(layers "*.Cu" "*.Mask")
			(remove_unused_layers no)
			(net "PCIE_COMP_B_TO_SCC_B_1_DN")
			(clearance 0.1651)
			(thermal_gap 0.1651)
		)
		(pad "B3" thru_hole circle
			(at 3.599942 -1.400048)
			(size 0.762 0.762)
			(drill 0.359918)
			(layers "*.Cu" "*.Mask")
			(remove_unused_layers no)
			(net "I2C_DPB_B_SDA")
			(clearance 0.1651)
			(thermal_gap 0.1651)
		)
		(pad "B4" thru_hole circle
			(at 5.40004 -0.199898)
			(size 0.762 0.762)
			(drill 0.359918)
			(layers "*.Cu" "*.Mask")
			(remove_unused_layers no)
			(net "PCIE_COMP_B_TO_SCC_B_3_DN")
			(clearance 0.1651)
			(thermal_gap 0.1651)
		)
		(pad "B5" thru_hole circle
			(at 7.199884 -1.400048)
			(size 0.762 0.762)
			(drill 0.359918)
			(layers "*.Cu" "*.Mask")
			(remove_unused_layers no)
			(net "I2C_BMC_A_EXP_B_SDA")
			(clearance 0.1651)
			(thermal_gap 0.1651)
		)
		(pad "B6" thru_hole circle
			(at 8.999982 -0.199898)
			(size 0.762 0.762)
			(drill 0.359918)
			(layers "*.Cu" "*.Mask")
			(remove_unused_layers no)
			(net "PCIE_COMP_B_TO_SCC_B_5_DN")
			(clearance 0.1651)
			(thermal_gap 0.1651)
		)
		(pad "B7" thru_hole circle
			(at 10.80008 -1.400048)
			(size 0.762 0.762)
			(drill 0.359918)
			(layers "*.Cu" "*.Mask")
			(remove_unused_layers no)
			(net "UART_EXP_B_RX")
			(clearance 0.1651)
			(thermal_gap 0.1651)
		)
		(pad "B8" thru_hole circle
			(at 12.599924 -0.199898)
			(size 0.762 0.762)
			(drill 0.359918)
			(layers "*.Cu" "*.Mask")
			(remove_unused_layers no)
			(net "PCIE_COMP_B_TO_SCC_B_7_DN")
			(clearance 0.1651)
			(thermal_gap 0.1651)
		)
		(pad "B9" thru_hole circle
			(at 16.20012 -1.400048)
			(size 0.762 0.762)
			(drill 0.359918)
			(layers "*.Cu" "*.Mask")
			(remove_unused_layers no)
			(net "SCC_A_FULL_PWR_EN")
			(clearance 0.1651)
			(thermal_gap 0.1651)
		)
		(pad "B10" thru_hole circle
			(at 17.999964 1.199896)
			(size 0.762 0.762)
			(drill 0.359918)
			(layers "*.Cu" "*.Mask")
			(remove_unused_layers no)
			(net "FAN_0_INS_N")
			(clearance 0.1651)
			(thermal_gap 0.1651)
		)
		(pad "B11" thru_hole circle
			(at 19.800062 -1.400048)
			(size 0.762 0.762)
			(drill 0.359918)
			(layers "*.Cu" "*.Mask")
			(remove_unused_layers no)
			(net "DRIVE_B_25_ACT")
			(clearance 0.1651)
			(thermal_gap 0.1651)
		)
		(pad "B12" thru_hole circle
			(at 21.599906 1.199896)
			(size 0.762 0.762)
			(drill 0.359918)
			(layers "*.Cu" "*.Mask")
			(remove_unused_layers no)
			(net "BMC_B_EXP_B_SPARE_1")
			(clearance 0.1651)
			(thermal_gap 0.1651)
		)
		(pad "C1" thru_hole circle
			(at 0 -3.599942)
			(size 0.762 0.762)
			(drill 0.359918)
			(layers "*.Cu" "*.Mask")
			(remove_unused_layers no)
			(net "PCIE_COMP_B_TO_SCC_B_0_DP")
			(clearance 0.1651)
			(thermal_gap 0.1651)
		)
		(pad "C2" thru_hole circle
			(at 1.800098 -2.400046)
			(size 0.762 0.762)
			(drill 0.359918)
			(layers "*.Cu" "*.Mask")
			(remove_unused_layers no)
			(net "I2C_SCC_B_SCL")
			(clearance 0.1651)
			(thermal_gap 0.1651)
		)
		(pad "C3" thru_hole circle
			(at 3.599942 -3.599942)
			(size 0.762 0.762)
			(drill 0.359918)
			(layers "*.Cu" "*.Mask")
			(remove_unused_layers no)
			(net "PCIE_COMP_B_TO_SCC_B_2_DP")
			(clearance 0.1651)
			(thermal_gap 0.1651)
		)
		(pad "C4" thru_hole circle
			(at 5.40004 -2.400046)
			(size 0.762 0.762)
			(drill 0.359918)
			(layers "*.Cu" "*.Mask")
			(remove_unused_layers no)
			(net "PWM_BMC_A_ZONE_C")
			(clearance 0.1651)
			(thermal_gap 0.1651)
		)
		(pad "C5" thru_hole circle
			(at 7.199884 -3.599942)
			(size 0.762 0.762)
			(drill 0.359918)
			(layers "*.Cu" "*.Mask")
			(remove_unused_layers no)
			(net "PCIE_COMP_B_TO_SCC_B_4_DP")
			(clearance 0.1651)
			(thermal_gap 0.1651)
		)
		(pad "C6" thru_hole circle
			(at 8.999982 -2.400046)
			(size 0.762 0.762)
			(drill 0.359918)
			(layers "*.Cu" "*.Mask")
			(remove_unused_layers no)
			(net "I2C_DRIVE_B_FLT_LED_SDA")
			(clearance 0.1651)
			(thermal_gap 0.1651)
		)
		(pad "C7" thru_hole circle
			(at 10.80008 -3.599942)
			(size 0.762 0.762)
			(drill 0.359918)
			(layers "*.Cu" "*.Mask")
			(remove_unused_layers no)
			(net "PCIE_COMP_B_TO_SCC_B_6_DP")
			(clearance 0.1651)
			(thermal_gap 0.1651)
		)
		(pad "C8" thru_hole circle
			(at 12.599924 -2.400046)
			(size 0.762 0.762)
			(drill 0.359918)
			(layers "*.Cu" "*.Mask")
			(remove_unused_layers no)
			(net "UART_IOC_B_TX")
			(clearance 0.1651)
			(thermal_gap 0.1651)
		)
		(pad "C9" thru_hole circle
			(at 16.20012 -2.500122)
			(size 0.762 0.762)
			(drill 0.359918)
			(layers "*.Cu" "*.Mask")
			(remove_unused_layers no)
			(net "SCC_B_FULL_PWR_EN")
			(clearance 0.1651)
			(thermal_gap 0.1651)
		)
		(pad "C10" thru_hole circle
			(at 17.999964 -0.199898)
			(size 0.762 0.762)
			(drill 0.359918)
			(layers "*.Cu" "*.Mask")
			(remove_unused_layers no)
			(net "FAN_1_INS_N")
			(clearance 0.1651)
			(thermal_gap 0.1651)
		)
		(pad "C11" thru_hole circle
			(at 19.800062 -2.500122)
			(size 0.762 0.762)
			(drill 0.359918)
			(layers "*.Cu" "*.Mask")
			(remove_unused_layers no)
			(net "DRIVE_B_26_ACT")
			(clearance 0.1651)
			(thermal_gap 0.1651)
		)
		(pad "C12" thru_hole circle
			(at 21.599906 -0.199898)
			(size 0.762 0.762)
			(drill 0.359918)
			(layers "*.Cu" "*.Mask")
			(remove_unused_layers no)
			(net "BMC_A_HEARTBEAT")
			(clearance 0.1651)
			(thermal_gap 0.1651)
		)
		(pad "D1" thru_hole circle
			(at 0 -4.99999)
			(size 0.762 0.762)
			(drill 0.359918)
			(layers "*.Cu" "*.Mask")
			(remove_unused_layers no)
			(net "PCIE_COMP_B_TO_SCC_B_0_DN")
			(clearance 0.1651)
			(thermal_gap 0.1651)
		)
		(pad "D2" thru_hole circle
			(at 1.800098 -3.800094)
			(size 0.762 0.762)
			(drill 0.359918)
			(layers "*.Cu" "*.Mask")
			(remove_unused_layers no)
			(net "I2C_SCC_B_SDA")
			(clearance 0.1651)
			(thermal_gap 0.1651)
		)
		(pad "D3" thru_hole circle
			(at 3.599942 -4.99999)
			(size 0.762 0.762)
			(drill 0.359918)
			(layers "*.Cu" "*.Mask")
			(remove_unused_layers no)
			(net "PCIE_COMP_B_TO_SCC_B_2_DN")
			(clearance 0.1651)
			(thermal_gap 0.1651)
		)
		(pad "D4" thru_hole circle
			(at 5.40004 -3.800094)
			(size 0.762 0.762)
			(drill 0.359918)
			(layers "*.Cu" "*.Mask")
			(remove_unused_layers no)
			(net "PWM_BMC_A_ZONE_D")
			(clearance 0.1651)
			(thermal_gap 0.1651)
		)
		(pad "D5" thru_hole circle
			(at 7.199884 -4.99999)
			(size 0.762 0.762)
			(drill 0.359918)
			(layers "*.Cu" "*.Mask")
			(remove_unused_layers no)
			(net "PCIE_COMP_B_TO_SCC_B_4_DN")
			(clearance 0.1651)
			(thermal_gap 0.1651)
		)
		(pad "D6" thru_hole circle
			(at 8.999982 -3.800094)
			(size 0.762 0.762)
			(drill 0.359918)
			(layers "*.Cu" "*.Mask")
			(remove_unused_layers no)
			(net "I2C_DRIVE_B_FLT_LED_SCL")
			(clearance 0.1651)
			(thermal_gap 0.1651)
		)
		(pad "D7" thru_hole circle
			(at 10.80008 -4.99999)
			(size 0.762 0.762)
			(drill 0.359918)
			(layers "*.Cu" "*.Mask")
			(remove_unused_layers no)
			(net "PCIE_COMP_B_TO_SCC_B_6_DN")
			(clearance 0.1651)
			(thermal_gap 0.1651)
		)
		(pad "D8" thru_hole circle
			(at 12.599924 -3.800094)
			(size 0.762 0.762)
			(drill 0.359918)
			(layers "*.Cu" "*.Mask")
			(remove_unused_layers no)
			(net "UART_IOC_B_RX")
			(clearance 0.1651)
			(thermal_gap 0.1651)
		)
		(pad "D9" thru_hole circle
			(at 16.20012 -3.599942)
			(size 0.762 0.762)
			(drill 0.359918)
			(layers "*.Cu" "*.Mask")
			(remove_unused_layers no)
			(net "SCC_B_FULL_PGOOD")
			(clearance 0.1651)
			(thermal_gap 0.1651)
		)
		(pad "D10" thru_hole circle
			(at 17.999964 -1.299972)
			(size 0.762 0.762)
			(drill 0.359918)
			(layers "*.Cu" "*.Mask")
			(remove_unused_layers no)
			(net "FAN_2_INS_N")
			(clearance 0.1651)
			(thermal_gap 0.1651)
		)
		(pad "D11" thru_hole circle
			(at 19.800062 -3.599942)
			(size 0.762 0.762)
			(drill 0.359918)
			(layers "*.Cu" "*.Mask")
			(remove_unused_layers no)
			(net "DRIVE_B_27_ACT")
			(clearance 0.1651)
			(thermal_gap 0.1651)
		)
		(pad "D12" thru_hole circle
			(at 21.599906 -1.299972)
			(size 0.762 0.762)
			(drill 0.359918)
			(layers "*.Cu" "*.Mask")
			(remove_unused_layers no)
			(net "BMC_B_HEARTBEAT")
			(clearance 0.1651)
			(thermal_gap 0.1651)
		)
		(pad "E1" thru_hole circle
			(at 0 -7.199884)
			(size 0.762 0.762)
			(drill 0.359918)
			(layers "*.Cu" "*.Mask")
			(remove_unused_layers no)
			(net "PCIE_COMP_B_TO_SCC_B_CLK_0_DP")
			(clearance 0.1651)
			(thermal_gap 0.1651)
		)
		(pad "E2" thru_hole circle
			(at 1.800098 -5.999988)
			(size 0.762 0.762)
			(drill 0.359918)
			(layers "*.Cu" "*.Mask")
			(remove_unused_layers no)
			(net "I2C_DPB_A_SCL_BUF")
			(clearance 0.1651)
			(thermal_gap 0.1651)
		)
		(pad "E3" thru_hole circle
			(at 3.599942 -7.199884)
			(size 0.762 0.762)
			(drill 0.359918)
			(layers "*.Cu" "*.Mask")
			(remove_unused_layers no)
			(net "I2C_CLIP_A_SCL")
			(clearance 0.1651)
			(thermal_gap 0.1651)
		)
		(pad "E4" thru_hole circle
			(at 5.40004 -5.999988)
			(size 0.762 0.762)
			(drill 0.359918)
			(layers "*.Cu" "*.Mask")
			(remove_unused_layers no)
			(net "COMP_B_EXP_B_SPARE_0")
			(clearance 0.1651)
			(thermal_gap 0.1651)
		)
		(pad "E5" thru_hole circle
			(at 7.199884 -7.199884)
			(size 0.762 0.762)
			(drill 0.359918)
			(layers "*.Cu" "*.Mask")
			(remove_unused_layers no)
			(net "I2C_BMC_B_EXP_B_SCL")
			(clearance 0.1651)
			(thermal_gap 0.1651)
		)
		(pad "E6" thru_hole circle
			(at 8.999982 -5.999988)
			(size 0.762 0.762)
			(drill 0.359918)
			(layers "*.Cu" "*.Mask")
			(remove_unused_layers no)
			(net "Net_76")
			(clearance 0.1651)
			(thermal_gap 0.1651)
		)
		(pad "E7" thru_hole circle
			(at 10.80008 -7.199884)
			(size 0.762 0.762)
			(drill 0.359918)
			(layers "*.Cu" "*.Mask")
			(remove_unused_layers no)
			(net "UART_SDB_B_RX")
			(clearance 0.1651)
			(thermal_gap 0.1651)
		)
		(pad "E8" thru_hole circle
			(at 12.599924 -5.999988)
			(size 0.762 0.762)
			(drill 0.359918)
			(layers "*.Cu" "*.Mask")
			(remove_unused_layers no)
			(net "PWM_SCC_A_ZONE_C")
			(clearance 0.1651)
			(thermal_gap 0.1651)
		)
		(pad "E9" thru_hole circle
			(at 16.20012 -4.99999)
			(size 0.762 0.762)
			(drill 0.359918)
			(layers "*.Cu" "*.Mask")
			(remove_unused_layers no)
			(net "DRAWER_CLOSED_N")
			(clearance 0.1651)
			(thermal_gap 0.1651)
		)
		(pad "E10" thru_hole circle
			(at 17.999964 -2.400046)
			(size 0.762 0.762)
			(drill 0.359918)
			(layers "*.Cu" "*.Mask")
			(remove_unused_layers no)
			(net "FAN_3_INS_N")
			(clearance 0.1651)
			(thermal_gap 0.1651)
		)
		(pad "E11" thru_hole circle
			(at 19.800062 -4.99999)
			(size 0.762 0.762)
			(drill 0.359918)
			(layers "*.Cu" "*.Mask")
			(remove_unused_layers no)
			(net "DRIVE_B_28_ACT")
			(clearance 0.1651)
			(thermal_gap 0.1651)
		)
		(pad "E12" thru_hole circle
			(at 21.599906 -2.400046)
			(size 0.762 0.762)
			(drill 0.359918)
			(layers "*.Cu" "*.Mask")
			(remove_unused_layers no)
			(net "SCC_A_HEARTBEAT")
			(clearance 0.1651)
			(thermal_gap 0.1651)
		)
		(pad "F1" thru_hole circle
			(at 0 -8.599932)
			(size 0.762 0.762)
			(drill 0.359918)
			(layers "*.Cu" "*.Mask")
			(remove_unused_layers no)
			(net "PCIE_COMP_B_TO_SCC_B_CLK_0_DN")
			(clearance 0.1651)
			(thermal_gap 0.1651)
		)
		(pad "F2" thru_hole circle
			(at 1.800098 -7.400036)
			(size 0.762 0.762)
			(drill 0.359918)
			(layers "*.Cu" "*.Mask")
			(remove_unused_layers no)
			(net "I2C_DPB_A_SDA_BUF")
			(clearance 0.1651)
			(thermal_gap 0.1651)
		)
		(pad "F3" thru_hole circle
			(at 3.599942 -8.599932)
			(size 0.762 0.762)
			(drill 0.359918)
			(layers "*.Cu" "*.Mask")
			(remove_unused_layers no)
			(net "I2C_CLIP_A_SDA")
			(clearance 0.1651)
			(thermal_gap 0.1651)
		)
		(pad "F4" thru_hole circle
			(at 5.40004 -7.400036)
			(size 0.762 0.762)
			(drill 0.359918)
			(layers "*.Cu" "*.Mask")
			(remove_unused_layers no)
			(net "PCIE_COMP_B_TO_SCC_B_RST_0")
			(clearance 0.1651)
			(thermal_gap 0.1651)
		)
		(pad "F5" thru_hole circle
			(at 7.199884 -8.599932)
			(size 0.762 0.762)
			(drill 0.359918)
			(layers "*.Cu" "*.Mask")
			(remove_unused_layers no)
			(net "I2C_BMC_B_EXP_B_SDA")
			(clearance 0.1651)
			(thermal_gap 0.1651)
		)
		(pad "F6" thru_hole circle
			(at 8.999982 -7.400036)
			(size 0.762 0.762)
			(drill 0.359918)
			(layers "*.Cu" "*.Mask")
			(remove_unused_layers no)
			(net "SCC_B_RESET_N")
			(clearance 0.1651)
			(thermal_gap 0.1651)
		)
		(pad "F7" thru_hole circle
			(at 10.80008 -8.599932)
			(size 0.762 0.762)
			(drill 0.359918)
			(layers "*.Cu" "*.Mask")
			(remove_unused_layers no)
			(net "UART_SDB_B_TX")
			(clearance 0.1651)
			(thermal_gap 0.1651)
		)
		(pad "F8" thru_hole circle
			(at 12.599924 -7.400036)
			(size 0.762 0.762)
			(drill 0.359918)
			(layers "*.Cu" "*.Mask")
			(remove_unused_layers no)
			(net "PWM_SCC_A_ZONE_D")
			(clearance 0.1651)
			(thermal_gap 0.1651)
		)
		(pad "F9" thru_hole circle
			(at 16.20012 -6.100064)
			(size 0.762 0.762)
			(drill 0.359918)
			(layers "*.Cu" "*.Mask")
			(remove_unused_layers no)
			(net "P12V_IN_PGOOD")
			(clearance 0.1651)
			(thermal_gap 0.1651)
		)
		(pad "F10" thru_hole circle
			(at 17.999964 -3.800094)
			(size 0.762 0.762)
			(drill 0.359918)
			(layers "*.Cu" "*.Mask")
			(remove_unused_layers no)
			(net "IOM_A_INS_N")
			(clearance 0.1651)
			(thermal_gap 0.1651)
		)
		(pad "F11" thru_hole circle
			(at 19.800062 -6.100064)
			(size 0.762 0.762)
			(drill 0.359918)
			(layers "*.Cu" "*.Mask")
			(remove_unused_layers no)
			(net "DRIVE_B_29_ACT")
			(clearance 0.1651)
			(thermal_gap 0.1651)
		)
		(pad "F12" thru_hole circle
			(at 21.599906 -3.800094)
			(size 0.762 0.762)
			(drill 0.359918)
			(layers "*.Cu" "*.Mask")
			(remove_unused_layers no)
			(net "SCC_B_HEARTBEAT")
			(clearance 0.1651)
			(thermal_gap 0.1651)
		)
		(pad "G1" thru_hole circle
			(at 0 -10.80008)
			(size 0.762 0.762)
			(drill 0.359918)
			(layers "*.Cu" "*.Mask")
			(remove_unused_layers no)
			(net "PCIE_SCC_B_TO_COMP_B_0_DP")
			(clearance 0.1651)
			(thermal_gap 0.1651)
		)
		(pad "G2" thru_hole circle
			(at 1.800098 -9.59993)
			(size 0.762 0.762)
			(drill 0.359918)
			(layers "*.Cu" "*.Mask")
			(remove_unused_layers no)
			(net "PCIE_SCC_B_TO_COMP_B_1_DP")
			(clearance 0.1651)
			(thermal_gap 0.1651)
		)
		(pad "G3" thru_hole circle
			(at 3.599942 -10.80008)
			(size 0.762 0.762)
			(drill 0.359918)
			(layers "*.Cu" "*.Mask")
			(remove_unused_layers no)
			(net "PCIE_SCC_B_TO_COMP_B_2_DP")
			(clearance 0.1651)
			(thermal_gap 0.1651)
		)
		(pad "G4" thru_hole circle
			(at 5.40004 -9.59993)
			(size 0.762 0.762)
			(drill 0.359918)
			(layers "*.Cu" "*.Mask")
			(remove_unused_layers no)
			(net "PCIE_SCC_B_TO_COMP_B_3_DP")
			(clearance 0.1651)
			(thermal_gap 0.1651)
		)
		(pad "G5" thru_hole circle
			(at 7.199884 -10.80008)
			(size 0.762 0.762)
			(drill 0.359918)
			(layers "*.Cu" "*.Mask")
			(remove_unused_layers no)
			(net "PCIE_SCC_B_TO_COMP_B_4_DP")
			(clearance 0.1651)
			(thermal_gap 0.1651)
		)
		(pad "G6" thru_hole circle
			(at 8.999982 -9.59993)
			(size 0.762 0.762)
			(drill 0.359918)
			(layers "*.Cu" "*.Mask")
			(remove_unused_layers no)
			(net "PCIE_SCC_B_TO_COMP_B_5_DP")
			(clearance 0.1651)
			(thermal_gap 0.1651)
		)
		(pad "G7" thru_hole circle
			(at 10.80008 -10.80008)
			(size 0.762 0.762)
			(drill 0.359918)
			(layers "*.Cu" "*.Mask")
			(remove_unused_layers no)
			(net "PCIE_SCC_B_TO_COMP_B_6_DP")
			(clearance 0.1651)
			(thermal_gap 0.1651)
		)
		(pad "G8" thru_hole circle
			(at 12.599924 -9.59993)
			(size 0.762 0.762)
			(drill 0.359918)
			(layers "*.Cu" "*.Mask")
			(remove_unused_layers no)
			(net "PCIE_SCC_B_TO_COMP_B_7_DP")
			(clearance 0.1651)
			(thermal_gap 0.1651)
		)
		(pad "G9" thru_hole circle
			(at 16.20012 -7.199884)
			(size 0.762 0.762)
			(drill 0.359918)
			(layers "*.Cu" "*.Mask")
			(remove_unused_layers no)
			(net "P12V_B_PGOOD")
			(clearance 0.1651)
			(thermal_gap 0.1651)
		)
		(pad "G10" thru_hole circle
			(at 17.999964 -4.899914)
			(size 0.762 0.762)
			(drill 0.359918)
			(layers "*.Cu" "*.Mask")
			(remove_unused_layers no)
			(net "IOM_B_INS_N")
			(clearance 0.1651)
			(thermal_gap 0.1651)
		)
		(pad "G11" thru_hole circle
			(at 19.800062 -7.199884)
			(size 0.762 0.762)
			(drill 0.359918)
			(layers "*.Cu" "*.Mask")
			(remove_unused_layers no)
			(net "DRIVE_B_30_ACT")
			(clearance 0.1651)
			(thermal_gap 0.1651)
		)
		(pad "G12" thru_hole circle
			(at 21.599906 -4.899914)
			(size 0.762 0.762)
			(drill 0.359918)
			(layers "*.Cu" "*.Mask")
			(remove_unused_layers no)
			(net "FDPB_FAN_LED0")
			(clearance 0.1651)
			(thermal_gap 0.1651)
		)
		(pad "GND1" thru_hole circle
			(at 0 -2.500122)
			(size 0.762 0.762)
			(drill 0.359918)
			(layers "*.Cu" "*.Mask")
			(remove_unused_layers no)
			(net "GND")
			(clearance 0.1651)
			(thermal_gap 0.1651)
		)
		(pad "GND2" thru_hole circle
			(at 0 -6.100064)
			(size 0.762 0.762)
			(drill 0.359918)
			(layers "*.Cu" "*.Mask")
			(remove_unused_layers no)
			(net "GND")
			(clearance 0.1651)
			(thermal_gap 0.1651)
		)
		(pad "GND3" thru_hole circle
			(at 0 -9.700006)
			(size 0.762 0.762)
			(drill 0.359918)
			(layers "*.Cu" "*.Mask")
			(remove_unused_layers no)
			(net "GND")
			(clearance 0.1651)
			(thermal_gap 0.1651)
		)
		(pad "GND4" thru_hole circle
			(at 0 -13.299948)
			(size 0.762 0.762)
			(drill 0.359918)
			(layers "*.Cu" "*.Mask")
			(remove_unused_layers no)
			(net "GND")
			(clearance 0.1651)
			(thermal_gap 0.1651)
		)
		(pad "GND5" thru_hole circle
			(at 1.800098 2.29997)
			(size 0.762 0.762)
			(drill 0.359918)
			(layers "*.Cu" "*.Mask")
			(remove_unused_layers no)
			(net "GND")
			(clearance 0.1651)
			(thermal_gap 0.1651)
		)
		(pad "GND6" thru_hole circle
			(at 1.800098 -1.299972)
			(size 0.762 0.762)
			(drill 0.359918)
			(layers "*.Cu" "*.Mask")
			(remove_unused_layers no)
			(net "GND")
			(clearance 0.1651)
			(thermal_gap 0.1651)
		)
		(pad "GND7" thru_hole circle
			(at 1.800098 -4.899914)
			(size 0.762 0.762)
			(drill 0.359918)
			(layers "*.Cu" "*.Mask")
			(remove_unused_layers no)
			(net "GND")
			(clearance 0.1651)
			(thermal_gap 0.1651)
		)
		(pad "GND8" thru_hole circle
			(at 1.800098 -8.50011)
			(size 0.762 0.762)
			(drill 0.359918)
			(layers "*.Cu" "*.Mask")
			(remove_unused_layers no)
			(net "GND")
			(clearance 0.1651)
			(thermal_gap 0.1651)
		)
		(pad "GND9" thru_hole circle
			(at 1.800098 -12.100052)
			(size 0.762 0.762)
			(drill 0.359918)
			(layers "*.Cu" "*.Mask")
			(remove_unused_layers no)
			(net "GND")
			(clearance 0.1651)
			(thermal_gap 0.1651)
		)
		(pad "GND10" thru_hole circle
			(at 3.599942 -2.500122)
			(size 0.762 0.762)
			(drill 0.359918)
			(layers "*.Cu" "*.Mask")
			(remove_unused_layers no)
			(net "GND")
			(clearance 0.1651)
			(thermal_gap 0.1651)
		)
		(pad "GND11" thru_hole circle
			(at 3.599942 -6.100064)
			(size 0.762 0.762)
			(drill 0.359918)
			(layers "*.Cu" "*.Mask")
			(remove_unused_layers no)
			(net "GND")
			(clearance 0.1651)
			(thermal_gap 0.1651)
		)
		(pad "GND12" thru_hole circle
			(at 3.599942 -9.700006)
			(size 0.762 0.762)
			(drill 0.359918)
			(layers "*.Cu" "*.Mask")
			(remove_unused_layers no)
			(net "GND")
			(clearance 0.1651)
			(thermal_gap 0.1651)
		)
		(pad "GND13" thru_hole circle
			(at 3.599942 -13.299948)
			(size 0.762 0.762)
			(drill 0.359918)
			(layers "*.Cu" "*.Mask")
			(remove_unused_layers no)
			(net "GND")
			(clearance 0.1651)
			(thermal_gap 0.1651)
		)
		(pad "GND14" thru_hole circle
			(at 5.40004 2.29997)
			(size 0.762 0.762)
			(drill 0.359918)
			(layers "*.Cu" "*.Mask")
			(remove_unused_layers no)
			(net "GND")
			(clearance 0.1651)
			(thermal_gap 0.1651)
		)
		(pad "GND15" thru_hole circle
			(at 5.40004 -1.299972)
			(size 0.762 0.762)
			(drill 0.359918)
			(layers "*.Cu" "*.Mask")
			(remove_unused_layers no)
			(net "GND")
			(clearance 0.1651)
			(thermal_gap 0.1651)
		)
		(pad "GND16" thru_hole circle
			(at 5.40004 -4.899914)
			(size 0.762 0.762)
			(drill 0.359918)
			(layers "*.Cu" "*.Mask")
			(remove_unused_layers no)
			(net "GND")
			(clearance 0.1651)
			(thermal_gap 0.1651)
		)
		(pad "GND17" thru_hole circle
			(at 5.40004 -8.50011)
			(size 0.762 0.762)
			(drill 0.359918)
			(layers "*.Cu" "*.Mask")
			(remove_unused_layers no)
			(net "GND")
			(clearance 0.1651)
			(thermal_gap 0.1651)
		)
		(pad "GND18" thru_hole circle
			(at 5.40004 -12.100052)
			(size 0.762 0.762)
			(drill 0.359918)
			(layers "*.Cu" "*.Mask")
			(remove_unused_layers no)
			(net "GND")
			(clearance 0.1651)
			(thermal_gap 0.1651)
		)
		(pad "GND19" thru_hole circle
			(at 7.199884 -2.500122)
			(size 0.762 0.762)
			(drill 0.359918)
			(layers "*.Cu" "*.Mask")
			(remove_unused_layers no)
			(net "GND")
			(clearance 0.1651)
			(thermal_gap 0.1651)
		)
		(pad "GND20" thru_hole circle
			(at 7.199884 -6.100064)
			(size 0.762 0.762)
			(drill 0.359918)
			(layers "*.Cu" "*.Mask")
			(remove_unused_layers no)
			(net "GND")
			(clearance 0.1651)
			(thermal_gap 0.1651)
		)
		(pad "GND21" thru_hole circle
			(at 7.199884 -9.700006)
			(size 0.762 0.762)
			(drill 0.359918)
			(layers "*.Cu" "*.Mask")
			(remove_unused_layers no)
			(net "GND")
			(clearance 0.1651)
			(thermal_gap 0.1651)
		)
		(pad "GND22" thru_hole circle
			(at 7.199884 -13.299948)
			(size 0.762 0.762)
			(drill 0.359918)
			(layers "*.Cu" "*.Mask")
			(remove_unused_layers no)
			(net "GND")
			(clearance 0.1651)
			(thermal_gap 0.1651)
		)
		(pad "GND23" thru_hole circle
			(at 8.999982 2.29997)
			(size 0.762 0.762)
			(drill 0.359918)
			(layers "*.Cu" "*.Mask")
			(remove_unused_layers no)
			(net "GND")
			(clearance 0.1651)
			(thermal_gap 0.1651)
		)
		(pad "GND24" thru_hole circle
			(at 8.999982 -1.299972)
			(size 0.762 0.762)
			(drill 0.359918)
			(layers "*.Cu" "*.Mask")
			(remove_unused_layers no)
			(net "GND")
			(clearance 0.1651)
			(thermal_gap 0.1651)
		)
		(pad "GND25" thru_hole circle
			(at 8.999982 -4.899914)
			(size 0.762 0.762)
			(drill 0.359918)
			(layers "*.Cu" "*.Mask")
			(remove_unused_layers no)
			(net "GND")
			(clearance 0.1651)
			(thermal_gap 0.1651)
		)
		(pad "GND26" thru_hole circle
			(at 8.999982 -8.50011)
			(size 0.762 0.762)
			(drill 0.359918)
			(layers "*.Cu" "*.Mask")
			(remove_unused_layers no)
			(net "GND")
			(clearance 0.1651)
			(thermal_gap 0.1651)
		)
		(pad "GND27" thru_hole circle
			(at 8.999982 -12.100052)
			(size 0.762 0.762)
			(drill 0.359918)
			(layers "*.Cu" "*.Mask")
			(remove_unused_layers no)
			(net "GND")
			(clearance 0.1651)
			(thermal_gap 0.1651)
		)
		(pad "GND28" thru_hole circle
			(at 10.80008 -2.500122)
			(size 0.762 0.762)
			(drill 0.359918)
			(layers "*.Cu" "*.Mask")
			(remove_unused_layers no)
			(net "GND")
			(clearance 0.1651)
			(thermal_gap 0.1651)
		)
		(pad "GND29" thru_hole circle
			(at 10.80008 -6.100064)
			(size 0.762 0.762)
			(drill 0.359918)
			(layers "*.Cu" "*.Mask")
			(remove_unused_layers no)
			(net "GND")
			(clearance 0.1651)
			(thermal_gap 0.1651)
		)
		(pad "GND30" thru_hole circle
			(at 10.80008 -9.700006)
			(size 0.762 0.762)
			(drill 0.359918)
			(layers "*.Cu" "*.Mask")
			(remove_unused_layers no)
			(net "GND")
			(clearance 0.1651)
			(thermal_gap 0.1651)
		)
		(pad "GND31" thru_hole circle
			(at 10.80008 -13.299948)
			(size 0.762 0.762)
			(drill 0.359918)
			(layers "*.Cu" "*.Mask")
			(remove_unused_layers no)
			(net "GND")
			(clearance 0.1651)
			(thermal_gap 0.1651)
		)
		(pad "GND32" thru_hole circle
			(at 12.599924 2.29997)
			(size 0.762 0.762)
			(drill 0.359918)
			(layers "*.Cu" "*.Mask")
			(remove_unused_layers no)
			(net "GND")
			(clearance 0.1651)
			(thermal_gap 0.1651)
		)
		(pad "GND33" thru_hole circle
			(at 12.599924 -1.299972)
			(size 0.762 0.762)
			(drill 0.359918)
			(layers "*.Cu" "*.Mask")
			(remove_unused_layers no)
			(net "GND")
			(clearance 0.1651)
			(thermal_gap 0.1651)
		)
		(pad "GND34" thru_hole circle
			(at 12.599924 -4.899914)
			(size 0.762 0.762)
			(drill 0.359918)
			(layers "*.Cu" "*.Mask")
			(remove_unused_layers no)
			(net "GND")
			(clearance 0.1651)
			(thermal_gap 0.1651)
		)
		(pad "GND35" thru_hole circle
			(at 12.599924 -8.50011)
			(size 0.762 0.762)
			(drill 0.359918)
			(layers "*.Cu" "*.Mask")
			(remove_unused_layers no)
			(net "GND")
			(clearance 0.1651)
			(thermal_gap 0.1651)
		)
		(pad "GND36" thru_hole circle
			(at 12.599924 -12.100052)
			(size 0.762 0.762)
			(drill 0.359918)
			(layers "*.Cu" "*.Mask")
			(remove_unused_layers no)
			(net "GND")
			(clearance 0.1651)
			(thermal_gap 0.1651)
		)
		(pad "H1" thru_hole circle
			(at 0 -12.199874)
			(size 0.762 0.762)
			(drill 0.359918)
			(layers "*.Cu" "*.Mask")
			(remove_unused_layers no)
			(net "PCIE_SCC_B_TO_COMP_B_0_DN")
			(clearance 0.1651)
			(thermal_gap 0.1651)
		)
		(pad "H2" thru_hole circle
			(at 1.800098 -10.999978)
			(size 0.762 0.762)
			(drill 0.359918)
			(layers "*.Cu" "*.Mask")
			(remove_unused_layers no)
			(net "PCIE_SCC_B_TO_COMP_B_1_DN")
			(clearance 0.1651)
			(thermal_gap 0.1651)
		)
		(pad "H3" thru_hole circle
			(at 3.599942 -12.199874)
			(size 0.762 0.762)
			(drill 0.359918)
			(layers "*.Cu" "*.Mask")
			(remove_unused_layers no)
			(net "PCIE_SCC_B_TO_COMP_B_2_DN")
			(clearance 0.1651)
			(thermal_gap 0.1651)
		)
		(pad "H4" thru_hole circle
			(at 5.40004 -10.999978)
			(size 0.762 0.762)
			(drill 0.359918)
			(layers "*.Cu" "*.Mask")
			(remove_unused_layers no)
			(net "PCIE_SCC_B_TO_COMP_B_3_DN")
			(clearance 0.1651)
			(thermal_gap 0.1651)
		)
		(pad "H5" thru_hole circle
			(at 7.199884 -12.199874)
			(size 0.762 0.762)
			(drill 0.359918)
			(layers "*.Cu" "*.Mask")
			(remove_unused_layers no)
			(net "PCIE_SCC_B_TO_COMP_B_4_DN")
			(clearance 0.1651)
			(thermal_gap 0.1651)
		)
		(pad "H6" thru_hole circle
			(at 8.999982 -10.999978)
			(size 0.762 0.762)
			(drill 0.359918)
			(layers "*.Cu" "*.Mask")
			(remove_unused_layers no)
			(net "PCIE_SCC_B_TO_COMP_B_5_DN")
			(clearance 0.1651)
			(thermal_gap 0.1651)
		)
		(pad "H7" thru_hole circle
			(at 10.80008 -12.199874)
			(size 0.762 0.762)
			(drill 0.359918)
			(layers "*.Cu" "*.Mask")
			(remove_unused_layers no)
			(net "PCIE_SCC_B_TO_COMP_B_6_DN")
			(clearance 0.1651)
			(thermal_gap 0.1651)
		)
		(pad "H8" thru_hole circle
			(at 12.599924 -10.999978)
			(size 0.762 0.762)
			(drill 0.359918)
			(layers "*.Cu" "*.Mask")
			(remove_unused_layers no)
			(net "PCIE_SCC_B_TO_COMP_B_7_DN")
			(clearance 0.1651)
			(thermal_gap 0.1651)
		)
		(pad "H9" thru_hole circle
			(at 16.20012 -8.599932)
			(size 0.762 0.762)
			(drill 0.359918)
			(layers "*.Cu" "*.Mask")
			(remove_unused_layers no)
			(net "SCC_B_STBY_PWR_EN")
			(clearance 0.1651)
			(thermal_gap 0.1651)
		)
		(pad "H10" thru_hole circle
			(at 17.999964 -5.999988)
			(size 0.762 0.762)
			(drill 0.359918)
			(layers "*.Cu" "*.Mask")
			(remove_unused_layers no)
			(net "SCC_A_INS_N")
			(clearance 0.1651)
			(thermal_gap 0.1651)
		)
		(pad "H11" thru_hole circle
			(at 19.800062 -8.599932)
			(size 0.762 0.762)
			(drill 0.359918)
			(layers "*.Cu" "*.Mask")
			(remove_unused_layers no)
			(net "DRIVE_B_31_ACT")
			(clearance 0.1651)
			(thermal_gap 0.1651)
		)
		(pad "H12" thru_hole circle
			(at 21.599906 -5.999988)
			(size 0.762 0.762)
			(drill 0.359918)
			(layers "*.Cu" "*.Mask")
			(remove_unused_layers no)
			(net "FDPB_FAN_LED1")
			(clearance 0.1651)
			(thermal_gap 0.1651)
		)
		(pad "J9" thru_hole circle
			(at 16.20012 -9.700006)
			(size 0.762 0.762)
			(drill 0.359918)
			(layers "*.Cu" "*.Mask")
			(remove_unused_layers no)
			(net "DPB_PWR_BTN_BUF_B")
			(clearance 0.1651)
			(thermal_gap 0.1651)
		)
		(pad "J10" thru_hole circle
			(at 17.999964 -7.400036)
			(size 0.762 0.762)
			(drill 0.359918)
			(layers "*.Cu" "*.Mask")
			(remove_unused_layers no)
			(net "SCC_B_INS_N")
			(clearance 0.1651)
			(thermal_gap 0.1651)
		)
		(pad "J11" thru_hole circle
			(at 19.800062 -9.700006)
			(size 0.762 0.762)
			(drill 0.359918)
			(layers "*.Cu" "*.Mask")
			(remove_unused_layers no)
			(net "DRIVE_B_32_ACT")
			(clearance 0.1651)
			(thermal_gap 0.1651)
		)
		(pad "J12" thru_hole circle
			(at 21.599906 -7.400036)
			(size 0.762 0.762)
			(drill 0.359918)
			(layers "*.Cu" "*.Mask")
			(remove_unused_layers no)
			(net "FDPB_FAN_LED2")
			(clearance 0.1651)
			(thermal_gap 0.1651)
		)
		(pad "K9" thru_hole circle
			(at 16.20012 -10.80008)
			(size 0.762 0.762)
			(drill 0.359918)
			(layers "*.Cu" "*.Mask")
			(remove_unused_layers no)
			(net "SCC_B_FAULT_LED")
			(clearance 0.1651)
			(thermal_gap 0.1651)
		)
		(pad "K10" thru_hole circle
			(at 17.999964 -8.50011)
			(size 0.762 0.762)
			(drill 0.359918)
			(layers "*.Cu" "*.Mask")
			(remove_unused_layers no)
			(net "SCC_B_TYPE_0")
			(clearance 0.1651)
			(thermal_gap 0.1651)
		)
		(pad "K11" thru_hole circle
			(at 19.800062 -10.80008)
			(size 0.762 0.762)
			(drill 0.359918)
			(layers "*.Cu" "*.Mask")
			(remove_unused_layers no)
			(net "DRIVE_B_33_ACT")
			(clearance 0.1651)
			(thermal_gap 0.1651)
		)
		(pad "K12" thru_hole circle
			(at 21.599906 -8.50011)
			(size 0.762 0.762)
			(drill 0.359918)
			(layers "*.Cu" "*.Mask")
			(remove_unused_layers no)
			(net "FDPB_FAN_LED3")
			(clearance 0.1651)
			(thermal_gap 0.1651)
		)
		(pad "L9" thru_hole circle
			(at 16.20012 -12.199874)
			(size 0.762 0.762)
			(drill 0.359918)
			(layers "*.Cu" "*.Mask")
			(remove_unused_layers no)
			(net "SCC_B_TYPE_3")
			(clearance 0.1651)
			(thermal_gap 0.1651)
		)
		(pad "L10" thru_hole circle
			(at 17.999964 -9.59993)
			(size 0.762 0.762)
			(drill 0.359918)
			(layers "*.Cu" "*.Mask")
			(remove_unused_layers no)
			(net "SCC_B_TYPE_1")
			(clearance 0.1651)
			(thermal_gap 0.1651)
		)
		(pad "L11" thru_hole circle
			(at 19.800062 -12.199874)
			(size 0.762 0.762)
			(drill 0.359918)
			(layers "*.Cu" "*.Mask")
			(remove_unused_layers no)
			(net "DRIVE_B_34_ACT")
			(clearance 0.1651)
			(thermal_gap 0.1651)
		)
		(pad "L12" thru_hole circle
			(at 21.599906 -9.59993)
			(size 0.762 0.762)
			(drill 0.359918)
			(layers "*.Cu" "*.Mask")
			(remove_unused_layers no)
			(net "P3V3_STBY_A")
			(clearance 0.1651)
			(thermal_gap 0.1651)
		)
		(pad "M9" thru_hole circle
			(at 16.20012 -13.299948)
			(size 0.762 0.762)
			(drill 0.359918)
			(layers "*.Cu" "*.Mask")
			(remove_unused_layers no)
			(net "GND")
			(clearance 0.1651)
			(thermal_gap 0.1651)
		)
		(pad "M10" thru_hole circle
			(at 17.999964 -10.999978)
			(size 0.762 0.762)
			(drill 0.359918)
			(layers "*.Cu" "*.Mask")
			(remove_unused_layers no)
			(net "SCC_B_TYPE_2")
			(clearance 0.1651)
			(thermal_gap 0.1651)
		)
		(pad "M11" thru_hole circle
			(at 19.800062 -13.299948)
			(size 0.762 0.762)
			(drill 0.359918)
			(layers "*.Cu" "*.Mask")
			(remove_unused_layers no)
			(net "DRIVE_B_35_ACT")
			(clearance 0.1651)
			(thermal_gap 0.1651)
		)
		(pad "M12" thru_hole circle
			(at 21.599906 -10.999978)
			(size 0.762 0.762)
			(drill 0.359918)
			(layers "*.Cu" "*.Mask")
			(remove_unused_layers no)
			(net "P3V3_STBY_B")
			(clearance 0.1651)
			(thermal_gap 0.1651)
		)
		(pad "N10" thru_hole circle
			(at 17.999964 -12.100052)
			(size 0.762 0.762)
			(drill 0.359918)
			(layers "*.Cu" "*.Mask")
			(remove_unused_layers no)
			(net "GND")
			(clearance 0.1651)
			(thermal_gap 0.1651)
		)
		(pad "N12" thru_hole circle
			(at 21.599906 -12.100052)
			(size 0.762 0.762)
			(drill 0.359918)
			(layers "*.Cu" "*.Mask")
			(remove_unused_layers no)
			(net "P5V_B_2")
			(clearance 0.1651)
			(thermal_gap 0.1651)
		)
	)
	(footprint ""
		(layer "F.Cu")
		(at 311.9374 -334.462882)
		(property "Reference" "U20"
			(at 0 0 0)
			(layer "F.SilkS")
			(hide yes)
			(effects
				(font
					(size 1.27 1.27)
				)
			)
		)
		(property "Value" "NCT7368S-GP"
			(at 4.0259 1.5748 0)
			(unlocked yes)
			(layer "F.Fab")
			(hide yes)
			(effects
				(font
					(size 1.016 1.016)
					(thickness 0.1524)
				)
			)
		)
		(property "Device Type" "SOIC8-G3627H69"
			(at 4.0259 0.0508 0)
			(unlocked yes)
			(layer "F.Fab")
			(hide yes)
			(effects
				(font
					(size 1.016 1.016)
					(thickness 0.1524)
				)
			)
		)
		(duplicate_pad_numbers_are_jumpers no)
		(fp_line
			(start -2.8829 -3.6322)
			(end 2.7178 -3.6322)
			(stroke
				(width 0.1524)
				(type default)
			)
			(layer "F.SilkS")
		)
		(fp_line
			(start -2.8829 -0.6223)
			(end -2.2479 0.0127)
			(stroke
				(width 0.1524)
				(type default)
			)
			(layer "F.SilkS")
		)
		(fp_line
			(start -2.8829 0.6477)
			(end -2.8829 -0.6223)
			(stroke
				(width 0.1524)
				(type default)
			)
			(layer "F.SilkS")
		)
		(fp_line
			(start -2.8829 3.6322)
			(end -2.8829 -3.6322)
			(stroke
				(width 0.1524)
				(type default)
			)
			(layer "F.SilkS")
		)
		(fp_line
			(start -2.7051 3.6322)
			(end -2.7051 1.5494)
			(stroke
				(width 0.508)
				(type default)
			)
			(layer "F.SilkS")
		)
		(fp_line
			(start -2.2479 0.0127)
			(end -2.8829 0.6477)
			(stroke
				(width 0.1524)
				(type default)
			)
			(layer "F.SilkS")
		)
		(fp_line
			(start 2.7178 -3.6322)
			(end 2.7178 3.6322)
			(stroke
				(width 0.1524)
				(type default)
			)
			(layer "F.SilkS")
		)
		(fp_line
			(start 2.7178 3.6322)
			(end -2.8829 3.6322)
			(stroke
				(width 0.1524)
				(type default)
			)
			(layer "F.SilkS")
		)
		(fp_poly
			(pts
				(xy -2.1209 2.9972) (xy -2.1209 1.9558) (xy -2.4511 1.9558) (xy -2.4511 -1.9558) (xy -2.1209 -1.9558)
				(xy -2.1209 -2.9972) (xy 2.1209 -2.9972) (xy 2.1209 -1.9558) (xy 2.4511 -1.9558) (xy 2.4511 1.9558)
				(xy 2.1209 1.9558) (xy 2.1209 2.9972)
			)
			(stroke
				(width 0)
				(type default)
			)
			(fill no)
			(layer "F.CrtYd")
		)
		(fp_poly
			(pts
				(xy -2.9591 3.8862) (xy -2.9591 -3.8862) (xy 2.9591 -3.8862) (xy 2.9591 1.95072) (xy 2.4511 1.95072)
				(xy 2.4511 -1.9558) (xy 2.1209 -1.9558) (xy 2.1209 -2.9972) (xy -2.1209 -2.9972) (xy -2.1209 -1.9558)
				(xy -2.4511 -1.9558) (xy -2.4511 1.9558) (xy -2.1209 1.9558) (xy -2.1209 2.9972) (xy 2.1209 2.9972)
				(xy 2.1209 1.9558) (xy 2.9591 1.9558) (xy 2.9591 3.8862)
			)
			(stroke
				(width 0)
				(type default)
			)
			(fill no)
			(layer "F.CrtYd")
		)
		(fp_rect
			(start -2.9591 3.8862)
			(end 2.9591 -3.8862)
			(stroke
				(width 0)
				(type default)
			)
			(fill no)
			(layer "F.Fab")
		)
		(pad "1" smd rect
			(at -1.905 2.5527)
			(size 0.635 1.651)
			(layers "F.Cu" "F.Mask" "F.Paste")
			(net "P3V3_IN")
		)
		(pad "2" smd rect
			(at -0.635 2.5527)
			(size 0.635 1.651)
			(layers "F.Cu" "F.Mask" "F.Paste")
			(net "PWM_SCC_A_ZONE_D")
		)
		(pad "3" smd rect
			(at 0.635 2.5527)
			(size 0.635 1.651)
			(layers "F.Cu" "F.Mask" "F.Paste")
			(net "PWM_BMC_A_ZONE_D")
		)
		(pad "4" smd rect
			(at 1.905 2.5527)
			(size 0.635 1.651)
			(layers "F.Cu" "F.Mask" "F.Paste")
			(net "PWM_BMC_B_ZONE_D")
		)
		(pad "5" smd rect
			(at 1.905 -2.5527)
			(size 0.635 1.651)
			(layers "F.Cu" "F.Mask" "F.Paste")
			(net "PWM_CAMP_SEL2")
		)
		(pad "6" smd rect
			(at 0.635 -2.5527)
			(size 0.635 1.651)
			(layers "F.Cu" "F.Mask" "F.Paste")
			(net "THERMHOT#_D")
		)
		(pad "7" smd rect
			(at -0.635 -2.5527)
			(size 0.635 1.651)
			(layers "F.Cu" "F.Mask" "F.Paste")
			(net "PWM_OUT_D_R")
		)
		(pad "8" smd rect
			(at -1.905 -2.5527)
			(size 0.635 1.651)
			(layers "F.Cu" "F.Mask" "F.Paste")
			(net "PWM_SCC_B_ZONE_D")
		)
		(pad "9" smd rect
			(at 0 0)
			(size 3.6068 2.6924)
			(layers "F.Cu" "F.Mask" "F.Paste")
			(net "GND")
		)
	)
	(footprint ""
		(layer "F.Cu")
		(at 51.7906 -263.779 -90)
		(property "Reference" "C44"
			(at 0 0 270)
			(layer "F.SilkS")
			(hide yes)
			(effects
				(font
					(size 1.27 1.27)
				)
			)
		)
		(property "Value" "SC1U16V3KX-5GP"
			(at 0 -2.8194 270)
			(unlocked yes)
			(layer "F.Fab")
			(hide yes)
			(effects
				(font
					(size 1.016 1.016)
					(thickness 0.1524)
				)
			)
		)
		(property "Device Type" "C603H36"
			(at 0 -4.3434 270)
			(unlocked yes)
			(layer "F.Fab")
			(hide yes)
			(effects
				(font
					(size 1.016 1.016)
					(thickness 0.1524)
				)
			)
		)
		(duplicate_pad_numbers_are_jumpers no)
		(fp_line
			(start 0.508 0)
			(end -0.508 0)
			(stroke
				(width 0.2032)
				(type default)
			)
			(layer "F.SilkS")
		)
		(fp_rect
			(start -0.5842 1.3335)
			(end 0.5842 -1.3335)
			(stroke
				(width 0)
				(type default)
			)
			(fill no)
			(layer "F.CrtYd")
		)
		(fp_rect
			(start -0.5842 1.3335)
			(end 0.5842 -1.3335)
			(stroke
				(width 0)
				(type default)
			)
			(fill no)
			(layer "F.Fab")
		)
		(pad "1" smd custom
			(at 0 -0.762 270)
			(size 0.2159 0.2159)
			(layers "F.Cu" "F.Mask" "F.Paste")
			(net "P5V_HDD1")
			(options
				(clearance outline)
				(anchor circle)
			)
			(primitives
				(gr_poly
					(pts
						(arc
							(start -0.3302 -0.4318)
							(mid -0.402042 -0.402042)
							(end -0.4318 -0.3302)
						)
						(arc
							(start -0.4318 0.3302)
							(mid -0.402042 0.402042)
							(end -0.3302 0.4318)
						)
						(arc
							(start 0.3302 0.4318)
							(mid 0.402042 0.402042)
							(end 0.4318 0.3302)
						)
						(arc
							(start 0.4318 -0.3302)
							(mid 0.402042 -0.402042)
							(end 0.3302 -0.4318)
						)
					)
					(width 0)
					(fill yes)
				)
			)
		)
		(pad "2" smd custom
			(at 0 0.762 270)
			(size 0.2159 0.2159)
			(layers "F.Cu" "F.Mask" "F.Paste")
			(net "GND")
			(options
				(clearance outline)
				(anchor circle)
			)
			(primitives
				(gr_poly
					(pts
						(arc
							(start -0.3302 -0.4318)
							(mid -0.402042 -0.402042)
							(end -0.4318 -0.3302)
						)
						(arc
							(start -0.4318 0.3302)
							(mid -0.402042 0.402042)
							(end -0.3302 0.4318)
						)
						(arc
							(start 0.3302 0.4318)
							(mid 0.402042 0.402042)
							(end 0.4318 0.3302)
						)
						(arc
							(start 0.4318 -0.3302)
							(mid 0.402042 -0.402042)
							(end 0.3302 -0.4318)
						)
					)
					(width 0)
					(fill yes)
				)
			)
		)
	)
	(footprint ""
		(layer "F.Cu")
		(at 458.216 -128.651)
		(property "Reference" "R589"
			(at 0 0 0)
			(layer "F.SilkS")
			(hide yes)
			(effects
				(font
					(size 1.27 1.27)
				)
			)
		)
		(property "Value" "4K7R2F-GP"
			(at 0.064008 -3.993896 0)
			(unlocked yes)
			(layer "F.Fab")
			(hide yes)
			(effects
				(font
					(size 1.016 1.016)
					(thickness 0.1524)
				)
			)
		)
		(property "Device Type" "R402H16"
			(at 0.064008 -5.517896 0)
			(unlocked yes)
			(layer "F.Fab")
			(hide yes)
			(effects
				(font
					(size 1.016 1.016)
					(thickness 0.1524)
				)
			)
		)
		(duplicate_pad_numbers_are_jumpers no)
		(fp_line
			(start -0.508 -0.9398)
			(end -0.508 0.9398)
			(stroke
				(width 0.1524)
				(type default)
			)
			(layer "F.SilkS")
		)
		(fp_line
			(start 0.508 -0.9398)
			(end -0.508 -0.9398)
			(stroke
				(width 0.1524)
				(type default)
			)
			(layer "F.SilkS")
		)
		(fp_rect
			(start -0.508 0.9398)
			(end 0.508 -0.9398)
			(stroke
				(width 0)
				(type default)
			)
			(fill no)
			(layer "F.CrtYd")
		)
		(fp_rect
			(start -0.508 0.9398)
			(end 0.508 -0.9398)
			(stroke
				(width 0)
				(type default)
			)
			(fill no)
			(layer "F.Fab")
		)
		(pad "1" smd custom
			(at 0 -0.4445)
			(size 0.1397 0.1397)
			(layers "F.Cu" "F.Mask" "F.Paste")
			(net "SW_PWR_R_HDD22")
			(options
				(clearance outline)
				(anchor circle)
			)
			(primitives
				(gr_poly
					(pts
						(arc
							(start -0.1778 -0.2794)
							(mid -0.249642 -0.249642)
							(end -0.2794 -0.1778)
						)
						(arc
							(start -0.2794 0.1778)
							(mid -0.249642 0.249642)
							(end -0.1778 0.2794)
						)
						(arc
							(start 0.1778 0.2794)
							(mid 0.249642 0.249642)
							(end 0.2794 0.1778)
						)
						(arc
							(start 0.2794 -0.1778)
							(mid 0.249642 -0.249642)
							(end 0.1778 -0.2794)
						)
					)
					(width 0)
					(fill yes)
				)
			)
		)
		(pad "2" smd custom
			(at 0 0.4445)
			(size 0.1397 0.1397)
			(layers "F.Cu" "F.Mask" "F.Paste")
			(net "GND")
			(options
				(clearance outline)
				(anchor circle)
			)
			(primitives
				(gr_poly
					(pts
						(arc
							(start -0.1778 -0.2794)
							(mid -0.249642 -0.249642)
							(end -0.2794 -0.1778)
						)
						(arc
							(start -0.2794 0.1778)
							(mid -0.249642 0.249642)
							(end -0.1778 0.2794)
						)
						(arc
							(start 0.1778 0.2794)
							(mid 0.249642 0.249642)
							(end 0.2794 0.1778)
						)
						(arc
							(start 0.2794 -0.1778)
							(mid 0.249642 -0.249642)
							(end 0.1778 -0.2794)
						)
					)
					(width 0)
					(fill yes)
				)
			)
		)
	)
	(footprint ""
		(layer "F.Cu")
		(at 167.7162 -369.189 90)
		(property "Reference" "R1060"
			(at 0 0 90)
			(layer "F.SilkS")
			(hide yes)
			(effects
				(font
					(size 1.27 1.27)
				)
			)
		)
		(property "Value" "10R2F-L-GP"
			(at 0.064008 -3.993896 90)
			(unlocked yes)
			(layer "F.Fab")
			(hide yes)
			(effects
				(font
					(size 1.016 1.016)
					(thickness 0.1524)
				)
			)
		)
		(property "Device Type" "R402H14"
			(at 0.064008 -5.517896 90)
			(unlocked yes)
			(layer "F.Fab")
			(hide yes)
			(effects
				(font
					(size 1.016 1.016)
					(thickness 0.1524)
				)
			)
		)
		(duplicate_pad_numbers_are_jumpers no)
		(fp_line
			(start 0.508 -0.9398)
			(end -0.508 -0.9398)
			(stroke
				(width 0.1524)
				(type default)
			)
			(layer "F.SilkS")
		)
		(fp_line
			(start -0.508 -0.9398)
			(end -0.508 0.9398)
			(stroke
				(width 0.1524)
				(type default)
			)
			(layer "F.SilkS")
		)
		(fp_rect
			(start -0.508 0.9398)
			(end 0.508 -0.9398)
			(stroke
				(width 0)
				(type default)
			)
			(fill no)
			(layer "F.CrtYd")
		)
		(fp_rect
			(start -0.508 0.9398)
			(end 0.508 -0.9398)
			(stroke
				(width 0)
				(type default)
			)
			(fill no)
			(layer "F.Fab")
		)
		(pad "1" smd custom
			(at 0 -0.4445 90)
			(size 0.1397 0.1397)
			(layers "F.Cu" "F.Mask" "F.Paste")
			(net "MB0_CM_SENSE_R2_P")
			(options
				(clearance outline)
				(anchor circle)
			)
			(primitives
				(gr_poly
					(pts
						(arc
							(start -0.1778 -0.2794)
							(mid -0.249642 -0.249642)
							(end -0.2794 -0.1778)
						)
						(arc
							(start -0.2794 0.1778)
							(mid -0.249642 0.249642)
							(end -0.1778 0.2794)
						)
						(arc
							(start 0.1778 0.2794)
							(mid 0.249642 0.249642)
							(end 0.2794 0.1778)
						)
						(arc
							(start 0.2794 -0.1778)
							(mid 0.249642 -0.249642)
							(end 0.1778 -0.2794)
						)
					)
					(width 0)
					(fill yes)
				)
			)
		)
		(pad "2" smd custom
			(at 0 0.4445 90)
			(size 0.1397 0.1397)
			(layers "F.Cu" "F.Mask" "F.Paste")
			(net "MB0_HS_SENSE_P")
			(options
				(clearance outline)
				(anchor circle)
			)
			(primitives
				(gr_poly
					(pts
						(arc
							(start -0.1778 -0.2794)
							(mid -0.249642 -0.249642)
							(end -0.2794 -0.1778)
						)
						(arc
							(start -0.2794 0.1778)
							(mid -0.249642 0.249642)
							(end -0.1778 0.2794)
						)
						(arc
							(start 0.1778 0.2794)
							(mid 0.249642 0.249642)
							(end 0.2794 0.1778)
						)
						(arc
							(start 0.2794 -0.1778)
							(mid 0.249642 -0.249642)
							(end 0.1778 -0.2794)
						)
					)
					(width 0)
					(fill yes)
				)
			)
		)
	)
	(footprint ""
		(layer "F.Cu")
		(at 81.407 -214.249)
		(property "Reference" "R237"
			(at 0 0 0)
			(layer "F.SilkS")
			(hide yes)
			(effects
				(font
					(size 1.27 1.27)
				)
			)
		)
		(property "Value" "91R3F-1-GP"
			(at -0.0254 -2.5146 0)
			(unlocked yes)
			(layer "F.Fab")
			(hide yes)
			(effects
				(font
					(size 1.016 1.016)
					(thickness 0.1524)
				)
			)
		)
		(property "Device Type" "R603H22"
			(at -0.0254 -4.0386 0)
			(unlocked yes)
			(layer "F.Fab")
			(hide yes)
			(effects
				(font
					(size 1.016 1.016)
					(thickness 0.1524)
				)
			)
		)
		(duplicate_pad_numbers_are_jumpers no)
		(fp_line
			(start -0.4826 0)
			(end -0.2032 0)
			(stroke
				(width 0.2032)
				(type default)
			)
			(layer "F.SilkS")
		)
		(fp_line
			(start 0.2032 0)
			(end 0.4826 0)
			(stroke
				(width 0.2032)
				(type default)
			)
			(layer "F.SilkS")
		)
		(fp_rect
			(start -0.5842 1.3335)
			(end 0.5842 -1.3335)
			(stroke
				(width 0)
				(type default)
			)
			(fill no)
			(layer "F.CrtYd")
		)
		(fp_rect
			(start -0.5842 1.3335)
			(end 0.5842 -1.3335)
			(stroke
				(width 0)
				(type default)
			)
			(fill no)
			(layer "F.Fab")
		)
		(pad "1" smd custom
			(at 0 -0.762)
			(size 0.2159 0.2159)
			(layers "F.Cu" "F.Mask" "F.Paste")
			(net "P5V_B_1")
			(options
				(clearance outline)
				(anchor circle)
			)
			(primitives
				(gr_poly
					(pts
						(arc
							(start -0.3302 -0.4318)
							(mid -0.402042 -0.402042)
							(end -0.4318 -0.3302)
						)
						(arc
							(start -0.4318 0.3302)
							(mid -0.402042 0.402042)
							(end -0.3302 0.4318)
						)
						(arc
							(start 0.3302 0.4318)
							(mid 0.402042 0.402042)
							(end 0.4318 0.3302)
						)
						(arc
							(start 0.4318 -0.3302)
							(mid 0.402042 -0.402042)
							(end 0.3302 -0.4318)
						)
					)
					(width 0)
					(fill yes)
				)
			)
		)
		(pad "2" smd custom
			(at 0 0.762)
			(size 0.2159 0.2159)
			(layers "F.Cu" "F.Mask" "F.Paste")
			(net "DRV_ACT_2")
			(options
				(clearance outline)
				(anchor circle)
			)
			(primitives
				(gr_poly
					(pts
						(arc
							(start -0.3302 -0.4318)
							(mid -0.402042 -0.402042)
							(end -0.4318 -0.3302)
						)
						(arc
							(start -0.4318 0.3302)
							(mid -0.402042 0.402042)
							(end -0.3302 0.4318)
						)
						(arc
							(start 0.3302 0.4318)
							(mid 0.402042 0.402042)
							(end 0.4318 0.3302)
						)
						(arc
							(start 0.4318 -0.3302)
							(mid 0.402042 -0.402042)
							(end 0.3302 -0.4318)
						)
					)
					(width 0)
					(fill yes)
				)
			)
		)
	)
	(footprint ""
		(layer "F.Cu")
		(at 464.185 -250.444 90)
		(property "Reference" "R330"
			(at 0 0 90)
			(layer "F.SilkS")
			(hide yes)
			(effects
				(font
					(size 1.27 1.27)
				)
			)
		)
		(property "Value" "200KR2F-L-GP"
			(at 0.064008 -3.993896 90)
			(unlocked yes)
			(layer "F.Fab")
			(hide yes)
			(effects
				(font
					(size 1.016 1.016)
					(thickness 0.1524)
				)
			)
		)
		(property "Device Type" "R402H16"
			(at 0.064008 -5.517896 90)
			(unlocked yes)
			(layer "F.Fab")
			(hide yes)
			(effects
				(font
					(size 1.016 1.016)
					(thickness 0.1524)
				)
			)
		)
		(duplicate_pad_numbers_are_jumpers no)
		(fp_line
			(start 0.508 -0.9398)
			(end -0.508 -0.9398)
			(stroke
				(width 0.1524)
				(type default)
			)
			(layer "F.SilkS")
		)
		(fp_line
			(start -0.508 -0.9398)
			(end -0.508 0.9398)
			(stroke
				(width 0.1524)
				(type default)
			)
			(layer "F.SilkS")
		)
		(fp_rect
			(start -0.508 0.9398)
			(end 0.508 -0.9398)
			(stroke
				(width 0)
				(type default)
			)
			(fill no)
			(layer "F.CrtYd")
		)
		(fp_rect
			(start -0.508 0.9398)
			(end 0.508 -0.9398)
			(stroke
				(width 0)
				(type default)
			)
			(fill no)
			(layer "F.Fab")
		)
		(pad "1" smd custom
			(at 0 -0.4445 90)
			(size 0.1397 0.1397)
			(layers "F.Cu" "F.Mask" "F.Paste")
			(net "SW_HDD_R10")
			(options
				(clearance outline)
				(anchor circle)
			)
			(primitives
				(gr_poly
					(pts
						(arc
							(start -0.1778 -0.2794)
							(mid -0.249642 -0.249642)
							(end -0.2794 -0.1778)
						)
						(arc
							(start -0.2794 0.1778)
							(mid -0.249642 0.249642)
							(end -0.1778 0.2794)
						)
						(arc
							(start 0.1778 0.2794)
							(mid 0.249642 0.249642)
							(end 0.2794 0.1778)
						)
						(arc
							(start 0.2794 -0.1778)
							(mid 0.249642 -0.249642)
							(end 0.1778 -0.2794)
						)
					)
					(width 0)
					(fill yes)
				)
			)
		)
		(pad "2" smd custom
			(at 0 0.4445 90)
			(size 0.1397 0.1397)
			(layers "F.Cu" "F.Mask" "F.Paste")
			(net "SW_HDD_N10")
			(options
				(clearance outline)
				(anchor circle)
			)
			(primitives
				(gr_poly
					(pts
						(arc
							(start -0.1778 -0.2794)
							(mid -0.249642 -0.249642)
							(end -0.2794 -0.1778)
						)
						(arc
							(start -0.2794 0.1778)
							(mid -0.249642 0.249642)
							(end -0.1778 0.2794)
						)
						(arc
							(start 0.1778 0.2794)
							(mid 0.249642 0.249642)
							(end 0.2794 0.1778)
						)
						(arc
							(start 0.2794 -0.1778)
							(mid 0.249642 -0.249642)
							(end 0.1778 -0.2794)
						)
					)
					(width 0)
					(fill yes)
				)
			)
		)
	)
	(footprint ""
		(layer "F.Cu")
		(at 478.79 -263.271)
		(property "Reference" "R334"
			(at 0 0 0)
			(layer "F.SilkS")
			(hide yes)
			(effects
				(font
					(size 1.27 1.27)
				)
			)
		)
		(property "Value" "2R6F-GP"
			(at -0.0508 -4.8514 0)
			(unlocked yes)
			(layer "F.Fab")
			(hide yes)
			(effects
				(font
					(size 1.016 1.016)
					(thickness 0.1524)
				)
			)
		)
		(property "Device Type" "R1206H26"
			(at 0 -6.3754 0)
			(unlocked yes)
			(layer "F.Fab")
			(hide yes)
			(effects
				(font
					(size 1.016 1.016)
					(thickness 0.1524)
				)
			)
		)
		(duplicate_pad_numbers_are_jumpers no)
		(fp_line
			(start -1.016 -2.2352)
			(end 1.016 -2.2352)
			(stroke
				(width 0.1524)
				(type default)
			)
			(layer "F.SilkS")
		)
		(fp_line
			(start -1.016 2.2352)
			(end -1.016 -2.2352)
			(stroke
				(width 0.1524)
				(type default)
			)
			(layer "F.SilkS")
		)
		(fp_line
			(start 1.016 -2.2352)
			(end 1.016 2.2352)
			(stroke
				(width 0.1524)
				(type default)
			)
			(layer "F.SilkS")
		)
		(fp_line
			(start 1.016 2.2352)
			(end -1.016 2.2352)
			(stroke
				(width 0.1524)
				(type default)
			)
			(layer "F.SilkS")
		)
		(fp_rect
			(start -1.0922 2.3114)
			(end 1.0922 -2.3114)
			(stroke
				(width 0)
				(type default)
			)
			(fill no)
			(layer "F.CrtYd")
		)
		(fp_poly
			(pts
				(xy -1.0922 -2.3114) (xy 1.0922 -2.3114) (xy 1.0922 2.3114) (xy -1.0922 2.3114)
			)
			(stroke
				(width 0)
				(type default)
			)
			(fill no)
			(layer "F.Fab")
		)
		(pad "1" smd rect
			(at 0 -1.397)
			(size 1.651 1.27)
			(layers "F.Cu" "F.Mask" "F.Paste")
			(net "P5V_HDD11")
		)
		(pad "2" smd rect
			(at 0 1.397)
			(size 1.651 1.27)
			(layers "F.Cu" "F.Mask" "F.Paste")
			(net "5V_PRE_11")
		)
	)
	(footprint ""
		(layer "F.Cu")
		(at 22.987 -18.3896 -90)
		(property "Reference" "R630"
			(at 0 0 270)
			(layer "F.SilkS")
			(hide yes)
			(effects
				(font
					(size 1.27 1.27)
				)
			)
		)
		(property "Value" "1KR2F-3-GP"
			(at 0.064008 -3.993896 270)
			(unlocked yes)
			(layer "F.Fab")
			(hide yes)
			(effects
				(font
					(size 1.016 1.016)
					(thickness 0.1524)
				)
			)
		)
		(property "Device Type" "R402H16"
			(at 0.064008 -5.517896 270)
			(unlocked yes)
			(layer "F.Fab")
			(hide yes)
			(effects
				(font
					(size 1.016 1.016)
					(thickness 0.1524)
				)
			)
		)
		(duplicate_pad_numbers_are_jumpers no)
		(fp_line
			(start -0.508 -0.9398)
			(end -0.508 0.9398)
			(stroke
				(width 0.1524)
				(type default)
			)
			(layer "F.SilkS")
		)
		(fp_line
			(start 0.508 -0.9398)
			(end -0.508 -0.9398)
			(stroke
				(width 0.1524)
				(type default)
			)
			(layer "F.SilkS")
		)
		(fp_rect
			(start -0.508 0.9398)
			(end 0.508 -0.9398)
			(stroke
				(width 0)
				(type default)
			)
			(fill no)
			(layer "F.CrtYd")
		)
		(fp_rect
			(start -0.508 0.9398)
			(end 0.508 -0.9398)
			(stroke
				(width 0)
				(type default)
			)
			(fill no)
			(layer "F.Fab")
		)
		(pad "1" smd custom
			(at 0 -0.4445 270)
			(size 0.1397 0.1397)
			(layers "F.Cu" "F.Mask" "F.Paste")
			(net "P3V3_STBY_B")
			(options
				(clearance outline)
				(anchor circle)
			)
			(primitives
				(gr_poly
					(pts
						(arc
							(start -0.1778 -0.2794)
							(mid -0.249642 -0.249642)
							(end -0.2794 -0.1778)
						)
						(arc
							(start -0.2794 0.1778)
							(mid -0.249642 0.249642)
							(end -0.1778 0.2794)
						)
						(arc
							(start 0.1778 0.2794)
							(mid 0.249642 0.249642)
							(end 0.2794 0.1778)
						)
						(arc
							(start 0.2794 -0.1778)
							(mid 0.249642 -0.249642)
							(end 0.1778 -0.2794)
						)
					)
					(width 0)
					(fill yes)
				)
			)
		)
		(pad "2" smd custom
			(at 0 0.4445 270)
			(size 0.1397 0.1397)
			(layers "F.Cu" "F.Mask" "F.Paste")
			(net "SW_PWR_R_HDD24")
			(options
				(clearance outline)
				(anchor circle)
			)
			(primitives
				(gr_poly
					(pts
						(arc
							(start -0.1778 -0.2794)
							(mid -0.249642 -0.249642)
							(end -0.2794 -0.1778)
						)
						(arc
							(start -0.2794 0.1778)
							(mid -0.249642 0.249642)
							(end -0.1778 0.2794)
						)
						(arc
							(start 0.1778 0.2794)
							(mid 0.249642 0.249642)
							(end 0.2794 0.1778)
						)
						(arc
							(start 0.2794 -0.1778)
							(mid 0.249642 -0.249642)
							(end 0.1778 -0.2794)
						)
					)
					(width 0)
					(fill yes)
				)
			)
		)
	)
	(footprint ""
		(layer "F.Cu")
		(at 18.923 -35.687 90)
		(property "Reference" "R623"
			(at 0 0 90)
			(layer "F.SilkS")
			(hide yes)
			(effects
				(font
					(size 1.27 1.27)
				)
			)
		)
		(property "Value" "2R6F-GP"
			(at -0.0508 -4.8514 90)
			(unlocked yes)
			(layer "F.Fab")
			(hide yes)
			(effects
				(font
					(size 1.016 1.016)
					(thickness 0.1524)
				)
			)
		)
		(property "Device Type" "R1206H26"
			(at 0 -6.3754 90)
			(unlocked yes)
			(layer "F.Fab")
			(hide yes)
			(effects
				(font
					(size 1.016 1.016)
					(thickness 0.1524)
				)
			)
		)
		(duplicate_pad_numbers_are_jumpers no)
		(fp_line
			(start 1.016 -2.2352)
			(end 1.016 2.2352)
			(stroke
				(width 0.1524)
				(type default)
			)
			(layer "F.SilkS")
		)
		(fp_line
			(start -1.016 -2.2352)
			(end 1.016 -2.2352)
			(stroke
				(width 0.1524)
				(type default)
			)
			(layer "F.SilkS")
		)
		(fp_line
			(start 1.016 2.2352)
			(end -1.016 2.2352)
			(stroke
				(width 0.1524)
				(type default)
			)
			(layer "F.SilkS")
		)
		(fp_line
			(start -1.016 2.2352)
			(end -1.016 -2.2352)
			(stroke
				(width 0.1524)
				(type default)
			)
			(layer "F.SilkS")
		)
		(fp_rect
			(start -1.0922 2.3114)
			(end 1.0922 -2.3114)
			(stroke
				(width 0)
				(type default)
			)
			(fill no)
			(layer "F.CrtYd")
		)
		(fp_poly
			(pts
				(xy -1.0922 -2.3114) (xy 1.0922 -2.3114) (xy 1.0922 2.3114) (xy -1.0922 2.3114)
			)
			(stroke
				(width 0)
				(type default)
			)
			(fill no)
			(layer "F.Fab")
		)
		(pad "1" smd rect
			(at 0 -1.397 90)
			(size 1.651 1.27)
			(layers "F.Cu" "F.Mask" "F.Paste")
			(net "P12V_HDD24")
		)
		(pad "2" smd rect
			(at 0 1.397 90)
			(size 1.651 1.27)
			(layers "F.Cu" "F.Mask" "F.Paste")
			(net "12V_PRE_24")
		)
	)
	(footprint ""
		(layer "F.Cu")
		(at 215.51646 -168.70426 90)
		(property "Reference" "U7"
			(at 0 0 90)
			(layer "F.SilkS")
			(hide yes)
			(effects
				(font
					(size 1.27 1.27)
				)
			)
		)
		(property "Value" "TCA9555PWR-GP"
			(at 0 -6.9342 90)
			(unlocked yes)
			(layer "F.Fab")
			(hide yes)
			(effects
				(font
					(size 1.016 1.016)
					(thickness 0.1524)
				)
			)
		)
		(property "Device Type" "TSOIC24H48"
			(at 0 -8.5852 90)
			(unlocked yes)
			(layer "F.Fab")
			(hide yes)
			(effects
				(font
					(size 1.016 1.016)
					(thickness 0.1524)
				)
			)
		)
		(duplicate_pad_numbers_are_jumpers no)
		(fp_line
			(start 3.81 -1.397)
			(end 3.81 1.397)
			(stroke
				(width 0.1524)
				(type default)
			)
			(layer "F.SilkS")
		)
		(fp_line
			(start -4.2291 -1.397)
			(end 3.81 -1.397)
			(stroke
				(width 0.1524)
				(type default)
			)
			(layer "F.SilkS")
		)
		(fp_line
			(start -4.2291 -0.8001)
			(end -3.429 0)
			(stroke
				(width 0.1524)
				(type default)
			)
			(layer "F.SilkS")
		)
		(fp_line
			(start -3.429 0)
			(end -4.2291 0.8001)
			(stroke
				(width 0.1524)
				(type default)
			)
			(layer "F.SilkS")
		)
		(fp_line
			(start 3.81 1.397)
			(end -4.2291 1.397)
			(stroke
				(width 0.1524)
				(type default)
			)
			(layer "F.SilkS")
		)
		(fp_line
			(start -4.22656 3.81)
			(end -4.2291 1.397)
			(stroke
				(width 0.508)
				(type default)
			)
			(layer "F.SilkS")
		)
		(fp_line
			(start -4.2291 3.937)
			(end -4.2291 -1.397)
			(stroke
				(width 0.1524)
				(type default)
			)
			(layer "F.SilkS")
		)
		(fp_poly
			(pts
				(xy -3.90652 -1.8542) (xy 3.90652 -1.8542) (xy 3.90652 1.8542) (xy -3.90652 1.8542)
			)
			(stroke
				(width 0)
				(type default)
			)
			(fill yes)
			(layer "F.SilkS")
		)
		(fp_poly
			(pts
				(xy -4.2164 3.81) (xy 4.2164 3.81) (xy 4.22656 -3.81) (xy -4.2164 -3.81)
			)
			(stroke
				(width 0)
				(type default)
			)
			(fill no)
			(layer "F.CrtYd")
		)
		(fp_poly
			(pts
				(xy -4.22656 -3.81) (xy 4.22656 -3.81) (xy 4.22656 3.81) (xy -4.22656 3.81)
			)
			(stroke
				(width 0)
				(type default)
			)
			(fill no)
			(layer "F.Fab")
		)
		(pad "1" smd rect
			(at -3.57632 2.8194 90)
			(size 0.3556 1.524)
			(layers "F.Cu" "F.Mask" "F.Paste")
			(net "IO_EXP6_INT_N")
		)
		(pad "2" smd rect
			(at -2.92608 2.8194 90)
			(size 0.3556 1.524)
			(layers "F.Cu" "F.Mask" "F.Paste")
			(net "IO_EXP6_A1")
		)
		(pad "3" smd rect
			(at -2.27584 2.8194 90)
			(size 0.3556 1.524)
			(layers "F.Cu" "F.Mask" "F.Paste")
			(net "IO_EXP6_A2")
		)
		(pad "4" smd rect
			(at -1.6256 2.8194 90)
			(size 0.3556 1.524)
			(layers "F.Cu" "F.Mask" "F.Paste")
			(net "DRIVE_B_32_INS")
		)
		(pad "5" smd rect
			(at -0.97536 2.8194 90)
			(size 0.3556 1.524)
			(layers "F.Cu" "F.Mask" "F.Paste")
			(net "DRIVE_B_33_INS")
		)
		(pad "6" smd rect
			(at -0.32512 2.8194 90)
			(size 0.3556 1.524)
			(layers "F.Cu" "F.Mask" "F.Paste")
			(net "DRIVE_B_34_INS")
		)
		(pad "7" smd rect
			(at 0.32512 2.8194 90)
			(size 0.3556 1.524)
			(layers "F.Cu" "F.Mask" "F.Paste")
			(net "DRIVE_B_35_INS")
		)
		(pad "8" smd rect
			(at 0.97536 2.8194 90)
			(size 0.3556 1.524)
			(layers "F.Cu" "F.Mask" "F.Paste")
			(net "Net_265")
		)
		(pad "9" smd rect
			(at 1.6256 2.8194 90)
			(size 0.3556 1.524)
			(layers "F.Cu" "F.Mask" "F.Paste")
			(net "Net_264")
		)
		(pad "10" smd rect
			(at 2.27584 2.8194 90)
			(size 0.3556 1.524)
			(layers "F.Cu" "F.Mask" "F.Paste")
			(net "Net_263")
		)
		(pad "11" smd rect
			(at 2.92608 2.8194 90)
			(size 0.3556 1.524)
			(layers "F.Cu" "F.Mask" "F.Paste")
			(net "Net_262")
		)
		(pad "12" smd rect
			(at 3.57632 2.8194 90)
			(size 0.3556 1.524)
			(layers "F.Cu" "F.Mask" "F.Paste")
			(net "GND")
		)
		(pad "13" smd rect
			(at 3.57632 -2.8194 90)
			(size 0.3556 1.524)
			(layers "F.Cu" "F.Mask" "F.Paste")
			(net "DRAWER_CLOSED_N")
		)
		(pad "14" smd rect
			(at 2.92608 -2.8194 90)
			(size 0.3556 1.524)
			(layers "F.Cu" "F.Mask" "F.Paste")
			(net "FAN_0_INS_N")
		)
		(pad "15" smd rect
			(at 2.27584 -2.8194 90)
			(size 0.3556 1.524)
			(layers "F.Cu" "F.Mask" "F.Paste")
			(net "FAN_1_INS_N")
		)
		(pad "16" smd rect
			(at 1.6256 -2.8194 90)
			(size 0.3556 1.524)
			(layers "F.Cu" "F.Mask" "F.Paste")
			(net "FAN_2_INS_N")
		)
		(pad "17" smd rect
			(at 0.97536 -2.8194 90)
			(size 0.3556 1.524)
			(layers "F.Cu" "F.Mask" "F.Paste")
			(net "FAN_3_INS_N")
		)
		(pad "18" smd rect
			(at 0.32512 -2.8194 90)
			(size 0.3556 1.524)
			(layers "F.Cu" "F.Mask" "F.Paste")
			(net "IOM_A_INS_N")
		)
		(pad "19" smd rect
			(at -0.32512 -2.8194 90)
			(size 0.3556 1.524)
			(layers "F.Cu" "F.Mask" "F.Paste")
			(net "IOM_B_INS_N")
		)
		(pad "20" smd rect
			(at -0.97536 -2.8194 90)
			(size 0.3556 1.524)
			(layers "F.Cu" "F.Mask" "F.Paste")
			(net "SCC_A_INS_N")
		)
		(pad "21" smd rect
			(at -1.6256 -2.8194 90)
			(size 0.3556 1.524)
			(layers "F.Cu" "F.Mask" "F.Paste")
			(net "IO_EXP6_A0")
		)
		(pad "22" smd rect
			(at -2.27584 -2.8194 90)
			(size 0.3556 1.524)
			(layers "F.Cu" "F.Mask" "F.Paste")
			(net "IO_EXP6_SCL")
		)
		(pad "23" smd rect
			(at -2.92608 -2.8194 90)
			(size 0.3556 1.524)
			(layers "F.Cu" "F.Mask" "F.Paste")
			(net "IO_EXP6_SDA")
		)
		(pad "24" smd rect
			(at -3.57632 -2.8194 90)
			(size 0.3556 1.524)
			(layers "F.Cu" "F.Mask" "F.Paste")
			(net "P3V3_STBY_B")
		)
	)
	(footprint ""
		(layer "F.Cu")
		(at 46.228 -150.622 -90)
		(property "Reference" "C203"
			(at 0 0 270)
			(layer "F.SilkS")
			(hide yes)
			(effects
				(font
					(size 1.27 1.27)
				)
			)
		)
		(property "Value" "SC4D7U25V5KX-1-GP"
			(at -0.0762 -6.1214 270)
			(unlocked yes)
			(layer "F.Fab")
			(hide yes)
			(effects
				(font
					(size 1.016 1.016)
					(thickness 0.1524)
				)
			)
		)
		(property "Device Type" "C805H58"
			(at -0.0762 -8.1534 270)
			(unlocked yes)
			(layer "F.Fab")
			(hide yes)
			(effects
				(font
					(size 1.016 1.016)
					(thickness 0.1524)
				)
			)
		)
		(duplicate_pad_numbers_are_jumpers no)
		(fp_line
			(start 0.635 0)
			(end -0.635 0)
			(stroke
				(width 0.508)
				(type default)
			)
			(layer "F.SilkS")
		)
		(fp_rect
			(start -0.9652 1.778)
			(end 0.9652 -1.778)
			(stroke
				(width 0)
				(type default)
			)
			(fill no)
			(layer "F.CrtYd")
		)
		(fp_poly
			(pts
				(xy -0.9652 -1.778) (xy 0.9652 -1.778) (xy 0.9652 1.778) (xy -0.9652 1.778)
			)
			(stroke
				(width 0)
				(type default)
			)
			(fill no)
			(layer "F.Fab")
		)
		(pad "1" smd rect
			(at 0 -0.9652 270)
			(size 1.397 1.143)
			(layers "F.Cu" "F.Mask" "F.Paste")
			(net "P12V_HDD13")
		)
		(pad "2" smd rect
			(at 0 0.9652 270)
			(size 1.397 1.143)
			(layers "F.Cu" "F.Mask" "F.Paste")
			(net "GND")
		)
	)
	(footprint ""
		(layer "F.Cu")
		(at 323.3166 -132.437124)
		(property "Reference" "VIA38"
			(at 0 0 0)
			(layer "F.SilkS")
			(hide yes)
			(effects
				(font
					(size 1.27 1.27)
				)
			)
		)
		(property "Value" "100OHM-8L-2D36MM-L16-GP"
			(at -3.4036 -0.4572 0)
			(unlocked yes)
			(layer "F.Fab")
			(hide yes)
			(effects
				(font
					(size 1.016 1.016)
					(thickness 0.1524)
				)
			)
		)
		(property "Device Type" "VIA-PCIE-4P-427097"
			(at -3.4036 -1.9812 0)
			(unlocked yes)
			(layer "F.Fab")
			(hide yes)
			(effects
				(font
					(size 1.016 1.016)
					(thickness 0.1524)
				)
			)
		)
		(duplicate_pad_numbers_are_jumpers no)
		(fp_rect
			(start -2.1336 0.4826)
			(end 2.1336 -0.4826)
			(stroke
				(width 0)
				(type default)
			)
			(fill no)
			(layer "F.CrtYd")
		)
		(fp_rect
			(start -2.1336 0.4826)
			(end 2.1336 -0.4826)
			(stroke
				(width 0)
				(type default)
			)
			(fill no)
			(layer "F.Fab")
		)
		(pad "1" thru_hole circle
			(at -1.651 0)
			(size 0.508 0.508)
			(drill 0.254)
			(layers "*.Cu" "*.Mask")
			(remove_unused_layers no)
			(net "GND")
			(clearance 0.2286)
			(thermal_gap 0.2286)
		)
		(pad "2" thru_hole circle
			(at -0.635 0)
			(size 0.508 0.508)
			(drill 0.254)
			(layers "*.Cu" "*.Mask")
			(remove_unused_layers no)
			(net "PHY_DRV_B_TO_SCC_B_18_DP")
			(clearance 0.2286)
			(thermal_gap 0.2286)
		)
		(pad "3" thru_hole circle
			(at 0.635 0)
			(size 0.508 0.508)
			(drill 0.254)
			(layers "*.Cu" "*.Mask")
			(remove_unused_layers no)
			(net "PHY_DRV_B_TO_SCC_B_18_DN")
			(clearance 0.2286)
			(thermal_gap 0.2286)
		)
		(pad "4" thru_hole circle
			(at 1.651 0)
			(size 0.508 0.508)
			(drill 0.254)
			(layers "*.Cu" "*.Mask")
			(remove_unused_layers no)
			(net "GND")
			(clearance 0.2286)
			(thermal_gap 0.2286)
		)
	)
	(footprint ""
		(layer "F.Cu")
		(at 463.423 -133.858 90)
		(property "Reference" "D22"
			(at 0 0 90)
			(layer "F.SilkS")
			(hide yes)
			(effects
				(font
					(size 1.27 1.27)
				)
			)
		)
		(property "Value" "RB551V30-GP"
			(at 0 -6.7818 90)
			(unlocked yes)
			(layer "F.Fab")
			(hide yes)
			(effects
				(font
					(size 1.016 1.016)
					(thickness 0.1524)
				)
			)
		)
		(property "Device Type" "SOD323AKH38"
			(at 0 -8.6868 90)
			(unlocked yes)
			(layer "F.Fab")
			(hide yes)
			(effects
				(font
					(size 1.016 1.016)
					(thickness 0.1524)
				)
			)
		)
		(duplicate_pad_numbers_are_jumpers no)
		(fp_line
			(start 0.889 -1.9304)
			(end 0.889 2.159)
			(stroke
				(width 0.1524)
				(type default)
			)
			(layer "F.SilkS")
		)
		(fp_line
			(start -0.889 -1.9304)
			(end 0.889 -1.9304)
			(stroke
				(width 0.1524)
				(type default)
			)
			(layer "F.SilkS")
		)
		(fp_line
			(start 0.762 2.0574)
			(end -0.762 2.0574)
			(stroke
				(width 0.508)
				(type default)
			)
			(layer "F.SilkS")
		)
		(fp_line
			(start 0.889 2.159)
			(end -0.889 2.159)
			(stroke
				(width 0.1524)
				(type default)
			)
			(layer "F.SilkS")
		)
		(fp_line
			(start -0.889 2.159)
			(end -0.889 -1.9304)
			(stroke
				(width 0.1524)
				(type default)
			)
			(layer "F.SilkS")
		)
		(fp_rect
			(start -1.016 2.3114)
			(end 1.016 -2.0066)
			(stroke
				(width 0)
				(type default)
			)
			(fill no)
			(layer "F.CrtYd")
		)
		(fp_poly
			(pts
				(xy -1.016 -2.0066) (xy 1.016 -2.0066) (xy 1.016 2.3114) (xy -1.016 2.3114)
			)
			(stroke
				(width 0)
				(type default)
			)
			(fill no)
			(layer "F.Fab")
		)
		(pad "A" smd rect
			(at 0 -1.143 90)
			(size 0.5588 1.016)
			(layers "F.Cu" "F.Mask" "F.Paste")
			(net "SW_HDD_R22")
		)
		(pad "K" smd rect
			(at 0 1.143 90)
			(size 0.5588 1.016)
			(layers "F.Cu" "F.Mask" "F.Paste")
			(net "SW_HDD_N22")
		)
	)
	(footprint ""
		(layer "F.Cu")
		(at 170.18 -363.22 -90)
		(property "Reference" "R1003"
			(at 0 0 270)
			(layer "F.SilkS")
			(hide yes)
			(effects
				(font
					(size 1.27 1.27)
				)
			)
		)
		(property "Value" "100KR2F-L1-GP"
			(at 0.064008 -3.993896 270)
			(unlocked yes)
			(layer "F.Fab")
			(hide yes)
			(effects
				(font
					(size 1.016 1.016)
					(thickness 0.1524)
				)
			)
		)
		(property "Device Type" "R402H16"
			(at 0.064008 -5.517896 270)
			(unlocked yes)
			(layer "F.Fab")
			(hide yes)
			(effects
				(font
					(size 1.016 1.016)
					(thickness 0.1524)
				)
			)
		)
		(duplicate_pad_numbers_are_jumpers no)
		(fp_line
			(start -0.508 -0.9398)
			(end -0.508 0.9398)
			(stroke
				(width 0.1524)
				(type default)
			)
			(layer "F.SilkS")
		)
		(fp_line
			(start 0.508 -0.9398)
			(end -0.508 -0.9398)
			(stroke
				(width 0.1524)
				(type default)
			)
			(layer "F.SilkS")
		)
		(fp_rect
			(start -0.508 0.9398)
			(end 0.508 -0.9398)
			(stroke
				(width 0)
				(type default)
			)
			(fill no)
			(layer "F.CrtYd")
		)
		(fp_rect
			(start -0.508 0.9398)
			(end 0.508 -0.9398)
			(stroke
				(width 0)
				(type default)
			)
			(fill no)
			(layer "F.Fab")
		)
		(pad "1" smd custom
			(at 0 -0.4445 270)
			(size 0.1397 0.1397)
			(layers "F.Cu" "F.Mask" "F.Paste")
			(net "MB0_VCAP_R")
			(options
				(clearance outline)
				(anchor circle)
			)
			(primitives
				(gr_poly
					(pts
						(arc
							(start -0.1778 -0.2794)
							(mid -0.249642 -0.249642)
							(end -0.2794 -0.1778)
						)
						(arc
							(start -0.2794 0.1778)
							(mid -0.249642 0.249642)
							(end -0.1778 0.2794)
						)
						(arc
							(start 0.1778 0.2794)
							(mid 0.249642 0.249642)
							(end 0.2794 0.1778)
						)
						(arc
							(start 0.2794 -0.1778)
							(mid 0.249642 -0.249642)
							(end 0.1778 -0.2794)
						)
					)
					(width 0)
					(fill yes)
				)
			)
		)
		(pad "2" smd custom
			(at 0 0.4445 270)
			(size 0.1397 0.1397)
			(layers "F.Cu" "F.Mask" "F.Paste")
			(net "MB0_PSET_R")
			(options
				(clearance outline)
				(anchor circle)
			)
			(primitives
				(gr_poly
					(pts
						(arc
							(start -0.1778 -0.2794)
							(mid -0.249642 -0.249642)
							(end -0.2794 -0.1778)
						)
						(arc
							(start -0.2794 0.1778)
							(mid -0.249642 0.249642)
							(end -0.1778 0.2794)
						)
						(arc
							(start 0.1778 0.2794)
							(mid 0.249642 0.249642)
							(end 0.2794 0.1778)
						)
						(arc
							(start 0.2794 -0.1778)
							(mid 0.249642 -0.249642)
							(end 0.1778 -0.2794)
						)
					)
					(width 0)
					(fill yes)
				)
			)
		)
	)
	(footprint ""
		(layer "F.Cu")
		(at 27.801824 -223.027748 90)
		(property "Reference" "C625"
			(at 0 0 90)
			(layer "F.SilkS")
			(hide yes)
			(effects
				(font
					(size 1.27 1.27)
				)
			)
		)
		(property "Value" "SCD1U16V2KX-3GP"
			(at 1.1811 -2.7051 90)
			(unlocked yes)
			(layer "F.Fab")
			(hide yes)
			(effects
				(font
					(size 1.016 1.016)
					(thickness 0.1524)
				)
			)
		)
		(property "Device Type" "C402H22"
			(at 1.1811 -4.2291 90)
			(unlocked yes)
			(layer "F.Fab")
			(hide yes)
			(effects
				(font
					(size 1.016 1.016)
					(thickness 0.1524)
				)
			)
		)
		(duplicate_pad_numbers_are_jumpers no)
		(fp_rect
			(start -0.4318 0.9525)
			(end 0.4318 -0.9525)
			(stroke
				(width 0)
				(type default)
			)
			(fill no)
			(layer "F.CrtYd")
		)
		(fp_rect
			(start -0.4318 0.9525)
			(end 0.4318 -0.9525)
			(stroke
				(width 0)
				(type default)
			)
			(fill no)
			(layer "F.Fab")
		)
		(pad "1" smd custom
			(at 0 -0.4445 90)
			(size 0.1524 0.1524)
			(layers "F.Cu" "F.Mask" "F.Paste")
			(net "P5V_B_1_VBST_RC")
			(options
				(clearance outline)
				(anchor circle)
			)
			(primitives
				(gr_poly
					(pts
						(arc
							(start 0.3048 -0.2032)
							(mid 0.275042 -0.275042)
							(end 0.2032 -0.3048)
						)
						(arc
							(start -0.2032 -0.3048)
							(mid -0.275042 -0.275042)
							(end -0.3048 -0.2032)
						)
						(arc
							(start -0.3048 0.2032)
							(mid -0.275042 0.275042)
							(end -0.2032 0.3048)
						)
						(arc
							(start 0.2032 0.3048)
							(mid 0.275042 0.275042)
							(end 0.3048 0.2032)
						)
					)
					(width 0)
					(fill yes)
				)
			)
		)
		(pad "2" smd custom
			(at 0 0.4445 90)
			(size 0.1524 0.1524)
			(layers "F.Cu" "F.Mask" "F.Paste")
			(net "P5V_B_1_LL")
			(options
				(clearance outline)
				(anchor circle)
			)
			(primitives
				(gr_poly
					(pts
						(arc
							(start 0.3048 -0.2032)
							(mid 0.275042 -0.275042)
							(end 0.2032 -0.3048)
						)
						(arc
							(start -0.2032 -0.3048)
							(mid -0.275042 -0.275042)
							(end -0.3048 -0.2032)
						)
						(arc
							(start -0.3048 0.2032)
							(mid -0.275042 0.275042)
							(end -0.2032 0.3048)
						)
						(arc
							(start 0.2032 0.3048)
							(mid 0.275042 0.275042)
							(end 0.3048 0.2032)
						)
					)
					(width 0)
					(fill yes)
				)
			)
		)
	)
	(footprint ""
		(layer "F.Cu")
		(at 222.3008 -301.8536 90)
		(property "Reference" "C709"
			(at 0 0 90)
			(layer "F.SilkS")
			(hide yes)
			(effects
				(font
					(size 1.27 1.27)
				)
			)
		)
		(property "Value" "SCD1U16V2KX-3GP"
			(at 1.1811 -2.7051 90)
			(unlocked yes)
			(layer "F.Fab")
			(hide yes)
			(effects
				(font
					(size 1.016 1.016)
					(thickness 0.1524)
				)
			)
		)
		(property "Device Type" "C402H22"
			(at 1.1811 -4.2291 90)
			(unlocked yes)
			(layer "F.Fab")
			(hide yes)
			(effects
				(font
					(size 1.016 1.016)
					(thickness 0.1524)
				)
			)
		)
		(duplicate_pad_numbers_are_jumpers no)
		(fp_rect
			(start -0.4318 0.9525)
			(end 0.4318 -0.9525)
			(stroke
				(width 0)
				(type default)
			)
			(fill no)
			(layer "F.CrtYd")
		)
		(fp_rect
			(start -0.4318 0.9525)
			(end 0.4318 -0.9525)
			(stroke
				(width 0)
				(type default)
			)
			(fill no)
			(layer "F.Fab")
		)
		(pad "1" smd custom
			(at 0 -0.4445 90)
			(size 0.1524 0.1524)
			(layers "F.Cu" "F.Mask" "F.Paste")
			(net "FANTACH_A_OE")
			(options
				(clearance outline)
				(anchor circle)
			)
			(primitives
				(gr_poly
					(pts
						(arc
							(start 0.3048 -0.2032)
							(mid 0.275042 -0.275042)
							(end 0.2032 -0.3048)
						)
						(arc
							(start -0.2032 -0.3048)
							(mid -0.275042 -0.275042)
							(end -0.3048 -0.2032)
						)
						(arc
							(start -0.3048 0.2032)
							(mid -0.275042 0.275042)
							(end -0.2032 0.3048)
						)
						(arc
							(start 0.2032 0.3048)
							(mid 0.275042 0.275042)
							(end 0.3048 0.2032)
						)
					)
					(width 0)
					(fill yes)
				)
			)
		)
		(pad "2" smd custom
			(at 0 0.4445 90)
			(size 0.1524 0.1524)
			(layers "F.Cu" "F.Mask" "F.Paste")
			(net "GND")
			(options
				(clearance outline)
				(anchor circle)
			)
			(primitives
				(gr_poly
					(pts
						(arc
							(start 0.3048 -0.2032)
							(mid 0.275042 -0.275042)
							(end 0.2032 -0.3048)
						)
						(arc
							(start -0.2032 -0.3048)
							(mid -0.275042 -0.275042)
							(end -0.3048 -0.2032)
						)
						(arc
							(start -0.3048 0.2032)
							(mid -0.275042 0.275042)
							(end -0.2032 0.3048)
						)
						(arc
							(start 0.2032 0.3048)
							(mid 0.275042 0.275042)
							(end 0.3048 0.2032)
						)
					)
					(width 0)
					(fill yes)
				)
			)
		)
	)
	(footprint ""
		(layer "F.Cu")
		(at 333.1718 -17.1196 180)
		(property "Reference" "R776"
			(at 0 0 180)
			(layer "F.SilkS")
			(hide yes)
			(effects
				(font
					(size 1.27 1.27)
				)
			)
		)
		(property "Value" "200KR2F-L-GP"
			(at 0.064008 -3.993896 180)
			(unlocked yes)
			(layer "F.Fab")
			(hide yes)
			(effects
				(font
					(size 1.016 1.016)
					(thickness 0.1524)
				)
			)
		)
		(property "Device Type" "R402H16"
			(at 0.064008 -5.517896 180)
			(unlocked yes)
			(layer "F.Fab")
			(hide yes)
			(effects
				(font
					(size 1.016 1.016)
					(thickness 0.1524)
				)
			)
		)
		(duplicate_pad_numbers_are_jumpers no)
		(fp_line
			(start 0.508 -0.9398)
			(end -0.508 -0.9398)
			(stroke
				(width 0.1524)
				(type default)
			)
			(layer "F.SilkS")
		)
		(fp_line
			(start -0.508 -0.9398)
			(end -0.508 0.9398)
			(stroke
				(width 0.1524)
				(type default)
			)
			(layer "F.SilkS")
		)
		(fp_rect
			(start -0.508 0.9398)
			(end 0.508 -0.9398)
			(stroke
				(width 0)
				(type default)
			)
			(fill no)
			(layer "F.CrtYd")
		)
		(fp_rect
			(start -0.508 0.9398)
			(end 0.508 -0.9398)
			(stroke
				(width 0)
				(type default)
			)
			(fill no)
			(layer "F.Fab")
		)
		(pad "1" smd custom
			(at 0 -0.4445 180)
			(size 0.1397 0.1397)
			(layers "F.Cu" "F.Mask" "F.Paste")
			(net "SW_HDD_R30")
			(options
				(clearance outline)
				(anchor circle)
			)
			(primitives
				(gr_poly
					(pts
						(arc
							(start -0.1778 -0.2794)
							(mid -0.249642 -0.249642)
							(end -0.2794 -0.1778)
						)
						(arc
							(start -0.2794 0.1778)
							(mid -0.249642 0.249642)
							(end -0.1778 0.2794)
						)
						(arc
							(start 0.1778 0.2794)
							(mid 0.249642 0.249642)
							(end 0.2794 0.1778)
						)
						(arc
							(start 0.2794 -0.1778)
							(mid 0.249642 -0.249642)
							(end 0.1778 -0.2794)
						)
					)
					(width 0)
					(fill yes)
				)
			)
		)
		(pad "2" smd custom
			(at 0 0.4445 180)
			(size 0.1397 0.1397)
			(layers "F.Cu" "F.Mask" "F.Paste")
			(net "SW_HDD_N30")
			(options
				(clearance outline)
				(anchor circle)
			)
			(primitives
				(gr_poly
					(pts
						(arc
							(start -0.1778 -0.2794)
							(mid -0.249642 -0.249642)
							(end -0.2794 -0.1778)
						)
						(arc
							(start -0.2794 0.1778)
							(mid -0.249642 0.249642)
							(end -0.1778 0.2794)
						)
						(arc
							(start 0.1778 0.2794)
							(mid 0.249642 0.249642)
							(end 0.2794 0.1778)
						)
						(arc
							(start 0.2794 -0.1778)
							(mid 0.249642 -0.249642)
							(end 0.1778 -0.2794)
						)
					)
					(width 0)
					(fill yes)
				)
			)
		)
	)
	(footprint ""
		(layer "F.Cu")
		(at 49.29886 -119.453406 -90)
		(property "Reference" "R1119"
			(at 0 0 270)
			(layer "F.SilkS")
			(hide yes)
			(effects
				(font
					(size 1.27 1.27)
				)
			)
		)
		(property "Value" "10KR2F-2-GP"
			(at 0.064008 -3.993896 270)
			(unlocked yes)
			(layer "F.Fab")
			(hide yes)
			(effects
				(font
					(size 1.016 1.016)
					(thickness 0.1524)
				)
			)
		)
		(property "Device Type" "R402H16"
			(at 0.064008 -5.517896 270)
			(unlocked yes)
			(layer "F.Fab")
			(hide yes)
			(effects
				(font
					(size 1.016 1.016)
					(thickness 0.1524)
				)
			)
		)
		(duplicate_pad_numbers_are_jumpers no)
		(fp_line
			(start -0.508 -0.9398)
			(end -0.508 0.9398)
			(stroke
				(width 0.1524)
				(type default)
			)
			(layer "F.SilkS")
		)
		(fp_line
			(start 0.508 -0.9398)
			(end -0.508 -0.9398)
			(stroke
				(width 0.1524)
				(type default)
			)
			(layer "F.SilkS")
		)
		(fp_rect
			(start -0.508 0.9398)
			(end 0.508 -0.9398)
			(stroke
				(width 0)
				(type default)
			)
			(fill no)
			(layer "F.CrtYd")
		)
		(fp_rect
			(start -0.508 0.9398)
			(end 0.508 -0.9398)
			(stroke
				(width 0)
				(type default)
			)
			(fill no)
			(layer "F.Fab")
		)
		(pad "1" smd custom
			(at 0 -0.4445 270)
			(size 0.1397 0.1397)
			(layers "F.Cu" "F.Mask" "F.Paste")
			(net "P5V_B_2_EN_R")
			(options
				(clearance outline)
				(anchor circle)
			)
			(primitives
				(gr_poly
					(pts
						(arc
							(start -0.1778 -0.2794)
							(mid -0.249642 -0.249642)
							(end -0.2794 -0.1778)
						)
						(arc
							(start -0.2794 0.1778)
							(mid -0.249642 0.249642)
							(end -0.1778 0.2794)
						)
						(arc
							(start 0.1778 0.2794)
							(mid 0.249642 0.249642)
							(end 0.2794 0.1778)
						)
						(arc
							(start 0.2794 -0.1778)
							(mid 0.249642 -0.249642)
							(end 0.1778 -0.2794)
						)
					)
					(width 0)
					(fill yes)
				)
			)
		)
		(pad "2" smd custom
			(at 0 0.4445 270)
			(size 0.1397 0.1397)
			(layers "F.Cu" "F.Mask" "F.Paste")
			(net "GND")
			(options
				(clearance outline)
				(anchor circle)
			)
			(primitives
				(gr_poly
					(pts
						(arc
							(start -0.1778 -0.2794)
							(mid -0.249642 -0.249642)
							(end -0.2794 -0.1778)
						)
						(arc
							(start -0.2794 0.1778)
							(mid -0.249642 0.249642)
							(end -0.1778 0.2794)
						)
						(arc
							(start 0.1778 0.2794)
							(mid 0.249642 0.249642)
							(end 0.2794 0.1778)
						)
						(arc
							(start 0.2794 -0.1778)
							(mid 0.249642 -0.249642)
							(end 0.1778 -0.2794)
						)
					)
					(width 0)
					(fill yes)
				)
			)
		)
	)
	(footprint ""
		(layer "F.Cu")
		(at 83.566 -19.558 180)
		(property "Reference" "Q131"
			(at 0 0 180)
			(layer "F.SilkS")
			(hide yes)
			(effects
				(font
					(size 1.27 1.27)
				)
			)
		)
		(property "Value" "2N7002KDW-GP"
			(at -2.3622 -8.2042 180)
			(unlocked yes)
			(layer "F.Fab")
			(hide yes)
			(effects
				(font
					(size 1.016 1.016)
					(thickness 0.1524)
				)
			)
		)
		(property "Device Type" "SOT-363H44"
			(at -2.3622 -10.1092 180)
			(unlocked yes)
			(layer "F.Fab")
			(hide yes)
			(effects
				(font
					(size 1.016 1.016)
					(thickness 0.1524)
				)
			)
		)
		(duplicate_pad_numbers_are_jumpers no)
		(fp_line
			(start 1.4478 1.7018)
			(end 1.4478 -1.7018)
			(stroke
				(width 0.1524)
				(type default)
			)
			(layer "F.SilkS")
		)
		(fp_line
			(start 1.4478 -1.7018)
			(end -1.4478 -1.7018)
			(stroke
				(width 0.1524)
				(type default)
			)
			(layer "F.SilkS")
		)
		(fp_line
			(start -1.27 1.524)
			(end -1.27 0.6604)
			(stroke
				(width 0.4826)
				(type default)
			)
			(layer "F.SilkS")
		)
		(fp_line
			(start -1.4478 1.7018)
			(end 1.4478 1.7018)
			(stroke
				(width 0.1524)
				(type default)
			)
			(layer "F.SilkS")
		)
		(fp_line
			(start -1.4478 -1.7018)
			(end -1.4478 1.7018)
			(stroke
				(width 0.1524)
				(type default)
			)
			(layer "F.SilkS")
		)
		(fp_poly
			(pts
				(xy -1.524 -1.778) (xy 1.524 -1.778) (xy 1.524 1.778) (xy -1.524 1.778)
			)
			(stroke
				(width 0)
				(type default)
			)
			(fill no)
			(layer "F.CrtYd")
		)
		(fp_poly
			(pts
				(xy -1.524 -1.778) (xy 1.524 -1.778) (xy 1.524 1.778) (xy -1.524 1.778)
			)
			(stroke
				(width 0)
				(type default)
			)
			(fill no)
			(layer "F.Fab")
		)
		(pad "1" smd rect
			(at -0.65024 0.9398 180)
			(size 0.4064 1.016)
			(layers "F.Cu" "F.Mask" "F.Paste")
			(net "GND")
		)
		(pad "2" smd rect
			(at 0 0.9398 180)
			(size 0.4064 1.016)
			(layers "F.Cu" "F.Mask" "F.Paste")
			(net "SW_PWR_R_HDD26")
		)
		(pad "3" smd rect
			(at 0.65024 0.9398 180)
			(size 0.4064 1.016)
			(layers "F.Cu" "F.Mask" "F.Paste")
			(net "SW_HDD_P26")
		)
		(pad "4" smd rect
			(at 0.65024 -0.9398 180)
			(size 0.4064 1.016)
			(layers "F.Cu" "F.Mask" "F.Paste")
			(net "GND")
		)
		(pad "5" smd rect
			(at 0 -0.9398 180)
			(size 0.4064 1.016)
			(layers "F.Cu" "F.Mask" "F.Paste")
			(net "SW_HDD_G26")
		)
		(pad "6" smd rect
			(at -0.65024 -0.9398 180)
			(size 0.4064 1.016)
			(layers "F.Cu" "F.Mask" "F.Paste")
			(net "SW_HDD_R26")
		)
	)
	(footprint ""
		(layer "F.Cu")
		(at 353.184714 -15.219426 -90)
		(property "Reference" "C431"
			(at 0 0 270)
			(layer "F.SilkS")
			(hide yes)
			(effects
				(font
					(size 1.27 1.27)
				)
			)
		)
		(property "Value" "SCD01U16V1KX-GP"
			(at -2.8321 -1.7399 270)
			(unlocked yes)
			(layer "F.Fab")
			(hide yes)
			(effects
				(font
					(size 1.016 1.016)
					(thickness 0.1524)
				)
			)
		)
		(property "Device Type" "C0201H13"
			(at -2.8321 -3.2639 270)
			(unlocked yes)
			(layer "F.Fab")
			(hide yes)
			(effects
				(font
					(size 1.016 1.016)
					(thickness 0.1524)
				)
			)
		)
		(duplicate_pad_numbers_are_jumpers no)
		(fp_rect
			(start -0.2794 0.6477)
			(end 0.2794 -0.6477)
			(stroke
				(width 0)
				(type default)
			)
			(fill no)
			(layer "F.CrtYd")
		)
		(fp_rect
			(start -0.2794 0.6477)
			(end 0.2794 -0.6477)
			(stroke
				(width 0)
				(type default)
			)
			(fill no)
			(layer "F.Fab")
		)
		(pad "1" smd custom
			(at 0 -0.2794 270)
			(size 0.0762 0.0762)
			(layers "F.Cu" "F.Mask" "F.Paste")
			(net "SAS_HDD_RX_N31")
			(options
				(clearance outline)
				(anchor circle)
			)
			(primitives
				(gr_poly
					(pts
						(arc
							(start 0.1524 -0.127)
							(mid 0.137521 -0.162921)
							(end 0.1016 -0.1778)
						)
						(arc
							(start -0.1016 -0.1778)
							(mid -0.137521 -0.162921)
							(end -0.1524 -0.127)
						)
						(arc
							(start -0.1524 0.127)
							(mid -0.137521 0.162921)
							(end -0.1016 0.1778)
						)
						(arc
							(start 0.1016 0.1778)
							(mid 0.137521 0.162921)
							(end 0.1524 0.127)
						)
					)
					(width 0)
					(fill yes)
				)
			)
		)
		(pad "2" smd custom
			(at 0 0.2794 270)
			(size 0.0762 0.0762)
			(layers "F.Cu" "F.Mask" "F.Paste")
			(net "PHY_SCC_B_TO_DRV_B_31_DN")
			(options
				(clearance outline)
				(anchor circle)
			)
			(primitives
				(gr_poly
					(pts
						(arc
							(start 0.1524 -0.127)
							(mid 0.137521 -0.162921)
							(end 0.1016 -0.1778)
						)
						(arc
							(start -0.1016 -0.1778)
							(mid -0.137521 -0.162921)
							(end -0.1524 -0.127)
						)
						(arc
							(start -0.1524 0.127)
							(mid -0.137521 0.162921)
							(end -0.1016 0.1778)
						)
						(arc
							(start 0.1016 0.1778)
							(mid 0.137521 0.162921)
							(end 0.1524 0.127)
						)
					)
					(width 0)
					(fill yes)
				)
			)
		)
	)
	(footprint ""
		(layer "F.Cu")
		(at 147.040092 -214.91702 90)
		(property "Reference" "Q247"
			(at 0 0 90)
			(layer "F.SilkS")
			(hide yes)
			(effects
				(font
					(size 1.27 1.27)
				)
			)
		)
		(property "Value" "SSM3K324R-GP"
			(at 0.127 -8.9662 90)
			(unlocked yes)
			(layer "F.Fab")
			(hide yes)
			(effects
				(font
					(size 1.016 1.016)
					(thickness 0.1524)
				)
			)
		)
		(property "Device Type" "SOT23DGS2D4H35"
			(at 0.127 -10.4902 90)
			(unlocked yes)
			(layer "F.Fab")
			(hide yes)
			(effects
				(font
					(size 1.016 1.016)
					(thickness 0.1524)
				)
			)
		)
		(duplicate_pad_numbers_are_jumpers no)
		(fp_line
			(start 1.651 -1.778)
			(end -1.651 -1.778)
			(stroke
				(width 0.1524)
				(type default)
			)
			(layer "F.SilkS")
		)
		(fp_line
			(start -1.651 -1.778)
			(end -1.651 1.778)
			(stroke
				(width 0.1524)
				(type default)
			)
			(layer "F.SilkS")
		)
		(fp_line
			(start 1.651 1.778)
			(end 1.651 -1.778)
			(stroke
				(width 0.1524)
				(type default)
			)
			(layer "F.SilkS")
		)
		(fp_line
			(start -1.651 1.778)
			(end 1.651 1.778)
			(stroke
				(width 0.1524)
				(type default)
			)
			(layer "F.SilkS")
		)
		(fp_poly
			(pts
				(xy -1.778 1.8796) (xy -1.778 -1.8796) (xy 1.778 -1.8796) (xy 1.778 1.8796)
			)
			(stroke
				(width 0)
				(type default)
			)
			(fill no)
			(layer "F.CrtYd")
		)
		(fp_poly
			(pts
				(xy -1.778 1.8796) (xy -1.778 -1.8796) (xy 1.778 -1.8796) (xy 1.778 1.8796)
			)
			(stroke
				(width 0)
				(type default)
			)
			(fill no)
			(layer "F.Fab")
		)
		(pad "D" smd custom
			(at 0 -0.9525 90)
			(size 0.1905 0.1905)
			(layers "F.Cu" "F.Mask" "F.Paste")
			(net "DRV_ACT_4_N")
			(options
				(clearance outline)
				(anchor circle)
			)
			(primitives
				(gr_poly
					(pts
						(arc
							(start -0.1778 0.5715)
							(mid -0.321484 0.511984)
							(end -0.381 0.3683)
						)
						(arc
							(start -0.381 -0.3683)
							(mid -0.321484 -0.511984)
							(end -0.1778 -0.5715)
						)
						(arc
							(start 0.1778 -0.5715)
							(mid 0.321484 -0.511984)
							(end 0.381 -0.3683)
						)
						(arc
							(start 0.381 0.3683)
							(mid 0.321484 0.511984)
							(end 0.1778 0.5715)
						)
					)
					(width 0)
					(fill yes)
				)
			)
		)
		(pad "G" smd custom
			(at -0.98425 0.9525 90)
			(size 0.1905 0.1905)
			(layers "F.Cu" "F.Mask" "F.Paste")
			(net "DRIVE_B_4_ACT")
			(options
				(clearance outline)
				(anchor circle)
			)
			(primitives
				(gr_poly
					(pts
						(arc
							(start -0.1778 0.5715)
							(mid -0.321484 0.511984)
							(end -0.381 0.3683)
						)
						(arc
							(start -0.381 -0.3683)
							(mid -0.321484 -0.511984)
							(end -0.1778 -0.5715)
						)
						(arc
							(start 0.1778 -0.5715)
							(mid 0.321484 -0.511984)
							(end 0.381 -0.3683)
						)
						(arc
							(start 0.381 0.3683)
							(mid 0.321484 0.511984)
							(end 0.1778 0.5715)
						)
					)
					(width 0)
					(fill yes)
				)
			)
		)
		(pad "S" smd custom
			(at 0.98425 0.9525 90)
			(size 0.1905 0.1905)
			(layers "F.Cu" "F.Mask" "F.Paste")
			(net "GND")
			(options
				(clearance outline)
				(anchor circle)
			)
			(primitives
				(gr_poly
					(pts
						(arc
							(start -0.1778 0.5715)
							(mid -0.321484 0.511984)
							(end -0.381 0.3683)
						)
						(arc
							(start -0.381 -0.3683)
							(mid -0.321484 -0.511984)
							(end -0.1778 -0.5715)
						)
						(arc
							(start 0.1778 -0.5715)
							(mid 0.321484 -0.511984)
							(end 0.381 -0.3683)
						)
						(arc
							(start 0.381 0.3683)
							(mid 0.321484 0.511984)
							(end 0.1778 0.5715)
						)
					)
					(width 0)
					(fill yes)
				)
			)
		)
	)
	(footprint ""
		(layer "F.Cu")
		(at 15.24 -18.161 180)
		(property "Reference" "R638"
			(at 0 0 180)
			(layer "F.SilkS")
			(hide yes)
			(effects
				(font
					(size 1.27 1.27)
				)
			)
		)
		(property "Value" "200KR2F-L-GP"
			(at 0.064008 -3.993896 180)
			(unlocked yes)
			(layer "F.Fab")
			(hide yes)
			(effects
				(font
					(size 1.016 1.016)
					(thickness 0.1524)
				)
			)
		)
		(property "Device Type" "R402H16"
			(at 0.064008 -5.517896 180)
			(unlocked yes)
			(layer "F.Fab")
			(hide yes)
			(effects
				(font
					(size 1.016 1.016)
					(thickness 0.1524)
				)
			)
		)
		(duplicate_pad_numbers_are_jumpers no)
		(fp_line
			(start 0.508 -0.9398)
			(end -0.508 -0.9398)
			(stroke
				(width 0.1524)
				(type default)
			)
			(layer "F.SilkS")
		)
		(fp_line
			(start -0.508 -0.9398)
			(end -0.508 0.9398)
			(stroke
				(width 0.1524)
				(type default)
			)
			(layer "F.SilkS")
		)
		(fp_rect
			(start -0.508 0.9398)
			(end 0.508 -0.9398)
			(stroke
				(width 0)
				(type default)
			)
			(fill no)
			(layer "F.CrtYd")
		)
		(fp_rect
			(start -0.508 0.9398)
			(end 0.508 -0.9398)
			(stroke
				(width 0)
				(type default)
			)
			(fill no)
			(layer "F.Fab")
		)
		(pad "1" smd custom
			(at 0 -0.4445 180)
			(size 0.1397 0.1397)
			(layers "F.Cu" "F.Mask" "F.Paste")
			(net "SW_HDD_R24")
			(options
				(clearance outline)
				(anchor circle)
			)
			(primitives
				(gr_poly
					(pts
						(arc
							(start -0.1778 -0.2794)
							(mid -0.249642 -0.249642)
							(end -0.2794 -0.1778)
						)
						(arc
							(start -0.2794 0.1778)
							(mid -0.249642 0.249642)
							(end -0.1778 0.2794)
						)
						(arc
							(start 0.1778 0.2794)
							(mid 0.249642 0.249642)
							(end 0.2794 0.1778)
						)
						(arc
							(start 0.2794 -0.1778)
							(mid 0.249642 -0.249642)
							(end 0.1778 -0.2794)
						)
					)
					(width 0)
					(fill yes)
				)
			)
		)
		(pad "2" smd custom
			(at 0 0.4445 180)
			(size 0.1397 0.1397)
			(layers "F.Cu" "F.Mask" "F.Paste")
			(net "SW_HDD_N24")
			(options
				(clearance outline)
				(anchor circle)
			)
			(primitives
				(gr_poly
					(pts
						(arc
							(start -0.1778 -0.2794)
							(mid -0.249642 -0.249642)
							(end -0.2794 -0.1778)
						)
						(arc
							(start -0.2794 0.1778)
							(mid -0.249642 0.249642)
							(end -0.1778 0.2794)
						)
						(arc
							(start 0.1778 0.2794)
							(mid 0.249642 0.249642)
							(end 0.2794 0.1778)
						)
						(arc
							(start 0.2794 -0.1778)
							(mid 0.249642 -0.249642)
							(end 0.1778 -0.2794)
						)
					)
					(width 0)
					(fill yes)
				)
			)
		)
	)
	(footprint ""
		(layer "F.Cu")
		(at 364.744 -13.589 180)
		(property "Reference" "R791"
			(at 0 0 180)
			(layer "F.SilkS")
			(hide yes)
			(effects
				(font
					(size 1.27 1.27)
				)
			)
		)
		(property "Value" "1KR2F-3-GP"
			(at 0.064008 -3.993896 180)
			(unlocked yes)
			(layer "F.Fab")
			(hide yes)
			(effects
				(font
					(size 1.016 1.016)
					(thickness 0.1524)
				)
			)
		)
		(property "Device Type" "R402H16"
			(at 0.064008 -5.517896 180)
			(unlocked yes)
			(layer "F.Fab")
			(hide yes)
			(effects
				(font
					(size 1.016 1.016)
					(thickness 0.1524)
				)
			)
		)
		(duplicate_pad_numbers_are_jumpers no)
		(fp_line
			(start 0.508 -0.9398)
			(end -0.508 -0.9398)
			(stroke
				(width 0.1524)
				(type default)
			)
			(layer "F.SilkS")
		)
		(fp_line
			(start -0.508 -0.9398)
			(end -0.508 0.9398)
			(stroke
				(width 0.1524)
				(type default)
			)
			(layer "F.SilkS")
		)
		(fp_rect
			(start -0.508 0.9398)
			(end 0.508 -0.9398)
			(stroke
				(width 0)
				(type default)
			)
			(fill no)
			(layer "F.CrtYd")
		)
		(fp_rect
			(start -0.508 0.9398)
			(end 0.508 -0.9398)
			(stroke
				(width 0)
				(type default)
			)
			(fill no)
			(layer "F.Fab")
		)
		(pad "1" smd custom
			(at 0 -0.4445 180)
			(size 0.1397 0.1397)
			(layers "F.Cu" "F.Mask" "F.Paste")
			(net "P3V3_STBY_B")
			(options
				(clearance outline)
				(anchor circle)
			)
			(primitives
				(gr_poly
					(pts
						(arc
							(start -0.1778 -0.2794)
							(mid -0.249642 -0.249642)
							(end -0.2794 -0.1778)
						)
						(arc
							(start -0.2794 0.1778)
							(mid -0.249642 0.249642)
							(end -0.1778 0.2794)
						)
						(arc
							(start 0.1778 0.2794)
							(mid 0.249642 0.249642)
							(end 0.2794 0.1778)
						)
						(arc
							(start 0.2794 -0.1778)
							(mid 0.249642 -0.249642)
							(end 0.1778 -0.2794)
						)
					)
					(width 0)
					(fill yes)
				)
			)
		)
		(pad "2" smd custom
			(at 0 0.4445 180)
			(size 0.1397 0.1397)
			(layers "F.Cu" "F.Mask" "F.Paste")
			(net "SW_PWR_R_HDD31")
			(options
				(clearance outline)
				(anchor circle)
			)
			(primitives
				(gr_poly
					(pts
						(arc
							(start -0.1778 -0.2794)
							(mid -0.249642 -0.249642)
							(end -0.2794 -0.1778)
						)
						(arc
							(start -0.2794 0.1778)
							(mid -0.249642 0.249642)
							(end -0.1778 0.2794)
						)
						(arc
							(start 0.1778 0.2794)
							(mid 0.249642 0.249642)
							(end 0.2794 0.1778)
						)
						(arc
							(start 0.2794 -0.1778)
							(mid 0.249642 -0.249642)
							(end 0.1778 -0.2794)
						)
					)
					(width 0)
					(fill yes)
				)
			)
		)
	)
	(footprint ""
		(layer "F.Cu")
		(at 434.901594 -212.390228 -90)
		(property "Reference" "R309"
			(at 0 0 270)
			(layer "F.SilkS")
			(hide yes)
			(effects
				(font
					(size 1.27 1.27)
				)
			)
		)
		(property "Value" "4K7R2F-GP"
			(at 0.064008 -3.993896 270)
			(unlocked yes)
			(layer "F.Fab")
			(hide yes)
			(effects
				(font
					(size 1.016 1.016)
					(thickness 0.1524)
				)
			)
		)
		(property "Device Type" "R402H16"
			(at 0.064008 -5.517896 270)
			(unlocked yes)
			(layer "F.Fab")
			(hide yes)
			(effects
				(font
					(size 1.016 1.016)
					(thickness 0.1524)
				)
			)
		)
		(duplicate_pad_numbers_are_jumpers no)
		(fp_line
			(start -0.508 -0.9398)
			(end -0.508 0.9398)
			(stroke
				(width 0.1524)
				(type default)
			)
			(layer "F.SilkS")
		)
		(fp_line
			(start 0.508 -0.9398)
			(end -0.508 -0.9398)
			(stroke
				(width 0.1524)
				(type default)
			)
			(layer "F.SilkS")
		)
		(fp_rect
			(start -0.508 0.9398)
			(end 0.508 -0.9398)
			(stroke
				(width 0)
				(type default)
			)
			(fill no)
			(layer "F.CrtYd")
		)
		(fp_rect
			(start -0.508 0.9398)
			(end 0.508 -0.9398)
			(stroke
				(width 0)
				(type default)
			)
			(fill no)
			(layer "F.Fab")
		)
		(pad "1" smd custom
			(at 0 -0.4445 270)
			(size 0.1397 0.1397)
			(layers "F.Cu" "F.Mask" "F.Paste")
			(net "DRIVE_B_10_ACT")
			(options
				(clearance outline)
				(anchor circle)
			)
			(primitives
				(gr_poly
					(pts
						(arc
							(start -0.1778 -0.2794)
							(mid -0.249642 -0.249642)
							(end -0.2794 -0.1778)
						)
						(arc
							(start -0.2794 0.1778)
							(mid -0.249642 0.249642)
							(end -0.1778 0.2794)
						)
						(arc
							(start 0.1778 0.2794)
							(mid 0.249642 0.249642)
							(end 0.2794 0.1778)
						)
						(arc
							(start 0.2794 -0.1778)
							(mid 0.249642 -0.249642)
							(end 0.1778 -0.2794)
						)
					)
					(width 0)
					(fill yes)
				)
			)
		)
		(pad "2" smd custom
			(at 0 0.4445 270)
			(size 0.1397 0.1397)
			(layers "F.Cu" "F.Mask" "F.Paste")
			(net "GND")
			(options
				(clearance outline)
				(anchor circle)
			)
			(primitives
				(gr_poly
					(pts
						(arc
							(start -0.1778 -0.2794)
							(mid -0.249642 -0.249642)
							(end -0.2794 -0.1778)
						)
						(arc
							(start -0.2794 0.1778)
							(mid -0.249642 0.249642)
							(end -0.1778 0.2794)
						)
						(arc
							(start 0.1778 0.2794)
							(mid 0.249642 0.249642)
							(end 0.2794 0.1778)
						)
						(arc
							(start 0.2794 -0.1778)
							(mid 0.249642 -0.249642)
							(end 0.1778 -0.2794)
						)
					)
					(width 0)
					(fill yes)
				)
			)
		)
	)
	(footprint ""
		(layer "F.Cu")
		(at 38.956996 -364.998)
		(property "Reference" "C523"
			(at 0 0 0)
			(layer "F.SilkS")
			(hide yes)
			(effects
				(font
					(size 1.27 1.27)
				)
			)
		)
		(property "Value" "SCD1U25V2KX-2-GP"
			(at 1.1811 -2.7051 0)
			(unlocked yes)
			(layer "F.Fab")
			(hide yes)
			(effects
				(font
					(size 1.016 1.016)
					(thickness 0.1524)
				)
			)
		)
		(property "Device Type" "C402H22"
			(at 1.1811 -4.2291 0)
			(unlocked yes)
			(layer "F.Fab")
			(hide yes)
			(effects
				(font
					(size 1.016 1.016)
					(thickness 0.1524)
				)
			)
		)
		(duplicate_pad_numbers_are_jumpers no)
		(fp_rect
			(start -0.4318 0.9525)
			(end 0.4318 -0.9525)
			(stroke
				(width 0)
				(type default)
			)
			(fill no)
			(layer "F.CrtYd")
		)
		(fp_rect
			(start -0.4318 0.9525)
			(end 0.4318 -0.9525)
			(stroke
				(width 0)
				(type default)
			)
			(fill no)
			(layer "F.Fab")
		)
		(pad "1" smd custom
			(at 0 -0.4445)
			(size 0.1524 0.1524)
			(layers "F.Cu" "F.Mask" "F.Paste")
			(net "FAN_0_TACH1")
			(options
				(clearance outline)
				(anchor circle)
			)
			(primitives
				(gr_poly
					(pts
						(arc
							(start 0.3048 -0.2032)
							(mid 0.275042 -0.275042)
							(end 0.2032 -0.3048)
						)
						(arc
							(start -0.2032 -0.3048)
							(mid -0.275042 -0.275042)
							(end -0.3048 -0.2032)
						)
						(arc
							(start -0.3048 0.2032)
							(mid -0.275042 0.275042)
							(end -0.2032 0.3048)
						)
						(arc
							(start 0.2032 0.3048)
							(mid 0.275042 0.275042)
							(end 0.3048 0.2032)
						)
					)
					(width 0)
					(fill yes)
				)
			)
		)
		(pad "2" smd custom
			(at 0 0.4445)
			(size 0.1524 0.1524)
			(layers "F.Cu" "F.Mask" "F.Paste")
			(net "GND")
			(options
				(clearance outline)
				(anchor circle)
			)
			(primitives
				(gr_poly
					(pts
						(arc
							(start 0.3048 -0.2032)
							(mid 0.275042 -0.275042)
							(end 0.2032 -0.3048)
						)
						(arc
							(start -0.2032 -0.3048)
							(mid -0.275042 -0.275042)
							(end -0.3048 -0.2032)
						)
						(arc
							(start -0.3048 0.2032)
							(mid -0.275042 0.275042)
							(end -0.2032 0.3048)
						)
						(arc
							(start 0.2032 0.3048)
							(mid 0.275042 0.275042)
							(end 0.3048 0.2032)
						)
					)
					(width 0)
					(fill yes)
				)
			)
		)
	)
	(footprint ""
		(layer "F.Cu")
		(at 175.006 -361.696)
		(property "Reference" "R1008"
			(at 0 0 0)
			(layer "F.SilkS")
			(hide yes)
			(effects
				(font
					(size 1.27 1.27)
				)
			)
		)
		(property "Value" "14K3R2F-GP"
			(at 0.064008 -3.993896 0)
			(unlocked yes)
			(layer "F.Fab")
			(hide yes)
			(effects
				(font
					(size 1.016 1.016)
					(thickness 0.1524)
				)
			)
		)
		(property "Device Type" "R402H16"
			(at 0.064008 -5.517896 0)
			(unlocked yes)
			(layer "F.Fab")
			(hide yes)
			(effects
				(font
					(size 1.016 1.016)
					(thickness 0.1524)
				)
			)
		)
		(duplicate_pad_numbers_are_jumpers no)
		(fp_line
			(start -0.508 -0.9398)
			(end -0.508 0.9398)
			(stroke
				(width 0.1524)
				(type default)
			)
			(layer "F.SilkS")
		)
		(fp_line
			(start 0.508 -0.9398)
			(end -0.508 -0.9398)
			(stroke
				(width 0.1524)
				(type default)
			)
			(layer "F.SilkS")
		)
		(fp_rect
			(start -0.508 0.9398)
			(end 0.508 -0.9398)
			(stroke
				(width 0)
				(type default)
			)
			(fill no)
			(layer "F.CrtYd")
		)
		(fp_rect
			(start -0.508 0.9398)
			(end 0.508 -0.9398)
			(stroke
				(width 0)
				(type default)
			)
			(fill no)
			(layer "F.Fab")
		)
		(pad "1" smd custom
			(at 0 -0.4445)
			(size 0.1397 0.1397)
			(layers "F.Cu" "F.Mask" "F.Paste")
			(net "MB0_ISTART_R")
			(options
				(clearance outline)
				(anchor circle)
			)
			(primitives
				(gr_poly
					(pts
						(arc
							(start -0.1778 -0.2794)
							(mid -0.249642 -0.249642)
							(end -0.2794 -0.1778)
						)
						(arc
							(start -0.2794 0.1778)
							(mid -0.249642 0.249642)
							(end -0.1778 0.2794)
						)
						(arc
							(start 0.1778 0.2794)
							(mid 0.249642 0.249642)
							(end 0.2794 0.1778)
						)
						(arc
							(start 0.2794 -0.1778)
							(mid 0.249642 -0.249642)
							(end 0.1778 -0.2794)
						)
					)
					(width 0)
					(fill yes)
				)
			)
		)
		(pad "2" smd custom
			(at 0 0.4445)
			(size 0.1397 0.1397)
			(layers "F.Cu" "F.Mask" "F.Paste")
			(net "AGND_CURRENT_MON")
			(options
				(clearance outline)
				(anchor circle)
			)
			(primitives
				(gr_poly
					(pts
						(arc
							(start -0.1778 -0.2794)
							(mid -0.249642 -0.249642)
							(end -0.2794 -0.1778)
						)
						(arc
							(start -0.2794 0.1778)
							(mid -0.249642 0.249642)
							(end -0.1778 0.2794)
						)
						(arc
							(start 0.1778 0.2794)
							(mid 0.249642 0.249642)
							(end 0.2794 0.1778)
						)
						(arc
							(start 0.2794 -0.1778)
							(mid 0.249642 -0.249642)
							(end 0.1778 -0.2794)
						)
					)
					(width 0)
					(fill yes)
				)
			)
		)
	)
	(footprint ""
		(layer "F.Cu")
		(at 14.859 -30.861)
		(property "Reference" "Q120"
			(at 0 0 0)
			(layer "F.SilkS")
			(hide yes)
			(effects
				(font
					(size 1.27 1.27)
				)
			)
		)
		(property "Value" "AO4407AL-GP"
			(at -3.707384 -1.5367 0)
			(unlocked yes)
			(layer "F.Fab")
			(hide yes)
			(effects
				(font
					(size 1.016 1.016)
					(thickness 0.1524)
				)
			)
		)
		(property "Device Type" "SOIC8H69"
			(at -3.707384 -3.0607 0)
			(unlocked yes)
			(layer "F.Fab")
			(hide yes)
			(effects
				(font
					(size 1.016 1.016)
					(thickness 0.1524)
				)
			)
		)
		(duplicate_pad_numbers_are_jumpers no)
		(fp_line
			(start -2.7432 -1.4224)
			(end -2.7432 1.4224)
			(stroke
				(width 0.1524)
				(type default)
			)
			(layer "F.SilkS")
		)
		(fp_line
			(start -2.7432 1.4224)
			(end -2.6416 1.4224)
			(stroke
				(width 0.1524)
				(type default)
			)
			(layer "F.SilkS")
		)
		(fp_line
			(start -2.7432 1.4224)
			(end 2.1336 1.4224)
			(stroke
				(width 0.1524)
				(type default)
			)
			(layer "F.SilkS")
		)
		(fp_line
			(start -2.7178 -0.508)
			(end -2.1844 -0.0508)
			(stroke
				(width 0.1524)
				(type default)
			)
			(layer "F.SilkS")
		)
		(fp_line
			(start -2.6289 3.4417)
			(end -2.6289 1.4732)
			(stroke
				(width 0.381)
				(type default)
			)
			(layer "F.SilkS")
		)
		(fp_line
			(start -2.1844 -0.0508)
			(end -2.7178 0.508)
			(stroke
				(width 0.1524)
				(type default)
			)
			(layer "F.SilkS")
		)
		(fp_line
			(start 2.1336 -1.4224)
			(end -2.7432 -1.4224)
			(stroke
				(width 0.1524)
				(type default)
			)
			(layer "F.SilkS")
		)
		(fp_line
			(start 2.1336 1.4224)
			(end 2.1336 -1.4224)
			(stroke
				(width 0.1524)
				(type default)
			)
			(layer "F.SilkS")
		)
		(fp_poly
			(pts
				(xy -2.2098 -1.4224) (xy -2.2098 1.4224) (xy 2.2098 1.4224) (xy 2.2098 -1.4224)
			)
			(stroke
				(width 0)
				(type default)
			)
			(fill yes)
			(layer "F.SilkS")
		)
		(fp_rect
			(start -2.450084 2.999994)
			(end 2.450084 -2.999994)
			(stroke
				(width 0)
				(type default)
			)
			(fill no)
			(layer "F.CrtYd")
		)
		(fp_poly
			(pts
				(xy -2.8194 3.6322) (xy -2.8194 -3.6322) (xy 2.8194 -3.6322) (xy 2.8194 1.18364) (xy 2.450084 1.18364)
				(xy 2.450084 -2.999994) (xy -2.450084 -2.999994) (xy -2.450084 2.999994) (xy 2.450084 2.999994)
				(xy 2.450084 1.18618) (xy 2.8194 1.18618) (xy 2.8194 3.6322)
			)
			(stroke
				(width 0)
				(type default)
			)
			(fill no)
			(layer "F.CrtYd")
		)
		(fp_rect
			(start -2.8194 3.6322)
			(end 2.8194 -3.6322)
			(stroke
				(width 0)
				(type default)
			)
			(fill no)
			(layer "F.Fab")
		)
		(pad "1" smd rect
			(at -1.905 2.54)
			(size 0.635 1.651)
			(layers "F.Cu" "F.Mask" "F.Paste")
			(net "P12V_B")
		)
		(pad "2" smd rect
			(at -0.635 2.54)
			(size 0.635 1.651)
			(layers "F.Cu" "F.Mask" "F.Paste")
			(net "P12V_B")
		)
		(pad "3" smd rect
			(at 0.635 2.54)
			(size 0.635 1.651)
			(layers "F.Cu" "F.Mask" "F.Paste")
			(net "P12V_B")
		)
		(pad "4" smd rect
			(at 1.905 2.54)
			(size 0.635 1.651)
			(layers "F.Cu" "F.Mask" "F.Paste")
			(net "SW_HDD_N24")
		)
		(pad "5" smd rect
			(at 1.905 -2.54)
			(size 0.635 1.651)
			(layers "F.Cu" "F.Mask" "F.Paste")
			(net "P12V_HDD24")
		)
		(pad "6" smd rect
			(at 0.635 -2.54)
			(size 0.635 1.651)
			(layers "F.Cu" "F.Mask" "F.Paste")
			(net "P12V_HDD24")
		)
		(pad "7" smd rect
			(at -0.635 -2.54)
			(size 0.635 1.651)
			(layers "F.Cu" "F.Mask" "F.Paste")
			(net "P12V_HDD24")
		)
		(pad "8" smd rect
			(at -1.905 -2.54)
			(size 0.635 1.651)
			(layers "F.Cu" "F.Mask" "F.Paste")
			(net "P12V_HDD24")
		)
	)
	(footprint ""
		(layer "F.Cu")
		(at 469.519 -244.348 180)
		(property "Reference" "R342"
			(at 0 0 180)
			(layer "F.SilkS")
			(hide yes)
			(effects
				(font
					(size 1.27 1.27)
				)
			)
		)
		(property "Value" "0R2J-2-GP"
			(at 0.064008 -3.993896 180)
			(unlocked yes)
			(layer "F.Fab")
			(hide yes)
			(effects
				(font
					(size 1.016 1.016)
					(thickness 0.1524)
				)
			)
		)
		(property "Device Type" "R402H16"
			(at 0.064008 -5.517896 180)
			(unlocked yes)
			(layer "F.Fab")
			(hide yes)
			(effects
				(font
					(size 1.016 1.016)
					(thickness 0.1524)
				)
			)
		)
		(duplicate_pad_numbers_are_jumpers no)
		(fp_line
			(start 0.508 -0.9398)
			(end -0.508 -0.9398)
			(stroke
				(width 0.1524)
				(type default)
			)
			(layer "F.SilkS")
		)
		(fp_line
			(start -0.508 -0.9398)
			(end -0.508 0.9398)
			(stroke
				(width 0.1524)
				(type default)
			)
			(layer "F.SilkS")
		)
		(fp_rect
			(start -0.508 0.9398)
			(end 0.508 -0.9398)
			(stroke
				(width 0)
				(type default)
			)
			(fill no)
			(layer "F.CrtYd")
		)
		(fp_rect
			(start -0.508 0.9398)
			(end 0.508 -0.9398)
			(stroke
				(width 0)
				(type default)
			)
			(fill no)
			(layer "F.Fab")
		)
		(pad "1" smd custom
			(at 0 -0.4445 180)
			(size 0.1397 0.1397)
			(layers "F.Cu" "F.Mask" "F.Paste")
			(net "DRIVE_B_11_PWR")
			(options
				(clearance outline)
				(anchor circle)
			)
			(primitives
				(gr_poly
					(pts
						(arc
							(start -0.1778 -0.2794)
							(mid -0.249642 -0.249642)
							(end -0.2794 -0.1778)
						)
						(arc
							(start -0.2794 0.1778)
							(mid -0.249642 0.249642)
							(end -0.1778 0.2794)
						)
						(arc
							(start 0.1778 0.2794)
							(mid 0.249642 0.249642)
							(end 0.2794 0.1778)
						)
						(arc
							(start 0.2794 -0.1778)
							(mid 0.249642 -0.249642)
							(end 0.1778 -0.2794)
						)
					)
					(width 0)
					(fill yes)
				)
			)
		)
		(pad "2" smd custom
			(at 0 0.4445 180)
			(size 0.1397 0.1397)
			(layers "F.Cu" "F.Mask" "F.Paste")
			(net "SW_PWR_R_HDD11")
			(options
				(clearance outline)
				(anchor circle)
			)
			(primitives
				(gr_poly
					(pts
						(arc
							(start -0.1778 -0.2794)
							(mid -0.249642 -0.249642)
							(end -0.2794 -0.1778)
						)
						(arc
							(start -0.2794 0.1778)
							(mid -0.249642 0.249642)
							(end -0.1778 0.2794)
						)
						(arc
							(start 0.1778 0.2794)
							(mid 0.249642 0.249642)
							(end 0.2794 0.1778)
						)
						(arc
							(start 0.2794 -0.1778)
							(mid 0.249642 -0.249642)
							(end 0.1778 -0.2794)
						)
					)
					(width 0)
					(fill yes)
				)
			)
		)
	)
	(footprint ""
		(layer "F.Cu")
		(at 143.129 -132.588 180)
		(property "Reference" "D16"
			(at 0 0 180)
			(layer "F.SilkS")
			(hide yes)
			(effects
				(font
					(size 1.27 1.27)
				)
			)
		)
		(property "Value" "RB551V30-GP"
			(at 0 -6.7818 180)
			(unlocked yes)
			(layer "F.Fab")
			(hide yes)
			(effects
				(font
					(size 1.016 1.016)
					(thickness 0.1524)
				)
			)
		)
		(property "Device Type" "SOD323AKH38"
			(at 0 -8.6868 180)
			(unlocked yes)
			(layer "F.Fab")
			(hide yes)
			(effects
				(font
					(size 1.016 1.016)
					(thickness 0.1524)
				)
			)
		)
		(duplicate_pad_numbers_are_jumpers no)
		(fp_line
			(start 0.889 2.159)
			(end -0.889 2.159)
			(stroke
				(width 0.1524)
				(type default)
			)
			(layer "F.SilkS")
		)
		(fp_line
			(start 0.889 -1.9304)
			(end 0.889 2.159)
			(stroke
				(width 0.1524)
				(type default)
			)
			(layer "F.SilkS")
		)
		(fp_line
			(start 0.762 2.0574)
			(end -0.762 2.0574)
			(stroke
				(width 0.508)
				(type default)
			)
			(layer "F.SilkS")
		)
		(fp_line
			(start -0.889 2.159)
			(end -0.889 -1.9304)
			(stroke
				(width 0.1524)
				(type default)
			)
			(layer "F.SilkS")
		)
		(fp_line
			(start -0.889 -1.9304)
			(end 0.889 -1.9304)
			(stroke
				(width 0.1524)
				(type default)
			)
			(layer "F.SilkS")
		)
		(fp_rect
			(start -1.016 2.3114)
			(end 1.016 -2.0066)
			(stroke
				(width 0)
				(type default)
			)
			(fill no)
			(layer "F.CrtYd")
		)
		(fp_poly
			(pts
				(xy -1.016 -2.0066) (xy 1.016 -2.0066) (xy 1.016 2.3114) (xy -1.016 2.3114)
			)
			(stroke
				(width 0)
				(type default)
			)
			(fill no)
			(layer "F.Fab")
		)
		(pad "A" smd rect
			(at 0 -1.143 180)
			(size 0.5588 1.016)
			(layers "F.Cu" "F.Mask" "F.Paste")
			(net "SW_HDD_R16")
		)
		(pad "K" smd rect
			(at 0 1.143 180)
			(size 0.5588 1.016)
			(layers "F.Cu" "F.Mask" "F.Paste")
			(net "SW_HDD_N16")
		)
	)
	(footprint ""
		(layer "F.Cu")
		(at 80.137 -214.249)
		(property "Reference" "R236"
			(at 0 0 0)
			(layer "F.SilkS")
			(hide yes)
			(effects
				(font
					(size 1.27 1.27)
				)
			)
		)
		(property "Value" "130R3F-GP"
			(at -0.0254 -2.5146 0)
			(unlocked yes)
			(layer "F.Fab")
			(hide yes)
			(effects
				(font
					(size 1.016 1.016)
					(thickness 0.1524)
				)
			)
		)
		(property "Device Type" "R603H22"
			(at -0.0254 -4.0386 0)
			(unlocked yes)
			(layer "F.Fab")
			(hide yes)
			(effects
				(font
					(size 1.016 1.016)
					(thickness 0.1524)
				)
			)
		)
		(duplicate_pad_numbers_are_jumpers no)
		(fp_line
			(start -0.4826 0)
			(end -0.2032 0)
			(stroke
				(width 0.2032)
				(type default)
			)
			(layer "F.SilkS")
		)
		(fp_line
			(start 0.2032 0)
			(end 0.4826 0)
			(stroke
				(width 0.2032)
				(type default)
			)
			(layer "F.SilkS")
		)
		(fp_rect
			(start -0.5842 1.3335)
			(end 0.5842 -1.3335)
			(stroke
				(width 0)
				(type default)
			)
			(fill no)
			(layer "F.CrtYd")
		)
		(fp_rect
			(start -0.5842 1.3335)
			(end 0.5842 -1.3335)
			(stroke
				(width 0)
				(type default)
			)
			(fill no)
			(layer "F.Fab")
		)
		(pad "1" smd custom
			(at 0 -0.762)
			(size 0.2159 0.2159)
			(layers "F.Cu" "F.Mask" "F.Paste")
			(net "P5V_B_1")
			(options
				(clearance outline)
				(anchor circle)
			)
			(primitives
				(gr_poly
					(pts
						(arc
							(start -0.3302 -0.4318)
							(mid -0.402042 -0.402042)
							(end -0.4318 -0.3302)
						)
						(arc
							(start -0.4318 0.3302)
							(mid -0.402042 0.402042)
							(end -0.3302 0.4318)
						)
						(arc
							(start 0.3302 0.4318)
							(mid 0.402042 0.402042)
							(end 0.4318 0.3302)
						)
						(arc
							(start 0.4318 -0.3302)
							(mid 0.402042 -0.402042)
							(end 0.3302 -0.4318)
						)
					)
					(width 0)
					(fill yes)
				)
			)
		)
		(pad "2" smd custom
			(at 0 0.762)
			(size 0.2159 0.2159)
			(layers "F.Cu" "F.Mask" "F.Paste")
			(net "FLT_HDD2")
			(options
				(clearance outline)
				(anchor circle)
			)
			(primitives
				(gr_poly
					(pts
						(arc
							(start -0.3302 -0.4318)
							(mid -0.402042 -0.402042)
							(end -0.4318 -0.3302)
						)
						(arc
							(start -0.4318 0.3302)
							(mid -0.402042 0.402042)
							(end -0.3302 0.4318)
						)
						(arc
							(start 0.3302 0.4318)
							(mid 0.402042 0.402042)
							(end 0.4318 0.3302)
						)
						(arc
							(start 0.4318 -0.3302)
							(mid 0.402042 -0.402042)
							(end 0.3302 -0.4318)
						)
					)
					(width 0)
					(fill yes)
				)
			)
		)
	)
	(footprint ""
		(layer "F.Cu")
		(at 300.199806 -93.999812)
		(property "Reference" ""
			(at 0 0 0)
			(layer "F.SilkS")
			(hide yes)
			(effects
				(font
					(size 1.27 1.27)
				)
			)
		)
		(property "Value" "*"
			(at -8.398764 -8.057642 0)
			(unlocked yes)
			(layer "F.Fab")
			(hide yes)
			(effects
				(font
					(size 1.016 1.016)
					(thickness 0.1524)
				)
			)
		)
		(duplicate_pad_numbers_are_jumpers no)
		(fp_poly
			(pts
				(arc
					(start 7.3152 0)
					(mid 0 7.3152)
					(end -7.3152 0)
				)
				(arc
					(start -7.3152 -5.9944)
					(mid 0 -13.3096)
					(end 7.3152 -5.9944)
				)
			)
			(stroke
				(width 0)
				(type default)
			)
			(fill no)
			(layer "B.CrtYd")
		)
		(fp_poly
			(pts
				(arc
					(start 7.3152 0)
					(mid 0 7.3152)
					(end -7.3152 0)
				)
				(arc
					(start -7.3152 -5.9944)
					(mid 0 -13.3096)
					(end 7.3152 -5.9944)
				)
			)
			(stroke
				(width 0)
				(type default)
			)
			(fill no)
			(layer "F.CrtYd")
		)
		(fp_poly
			(pts
				(arc
					(start 7.3152 0)
					(mid 0 7.3152)
					(end -7.3152 0)
				)
				(arc
					(start -7.3152 -5.9944)
					(mid 0 -13.3096)
					(end 7.3152 -5.9944)
				)
			)
			(stroke
				(width 0)
				(type default)
			)
			(fill no)
			(layer "B.Fab")
		)
		(fp_poly
			(pts
				(arc
					(start 7.3152 0)
					(mid 0 7.3152)
					(end -7.3152 0)
				)
				(arc
					(start -7.3152 -5.9944)
					(mid 0 -13.3096)
					(end 7.3152 -5.9944)
				)
			)
			(stroke
				(width 0)
				(type default)
			)
			(fill no)
			(layer "F.Fab")
		)
		(pad "1" thru_hole oval
			(at 0 0)
			(size 14.0208 20.0152)
			(drill 0.0254
				(offset 0 -2.9972)
			)
			(layers "*.Cu" "*.Mask")
			(remove_unused_layers no)
			(net "Net_17")
			(clearance -1.002284)
			(thermal_gap 0.1524)
			(padstack
				(mode front_inner_back)
				(layer "Inner"
					(shape custom)
					(size 2.928012 2.928012)
					(options
						(anchor circle)
					)
					(primitives
						(gr_poly
							(pts
								(arc
									(start 4.571746 -2.084324)
									(mid 0.000333 7.430372)
									(end -4.571492 -2.084324)
								)
								(arc
									(start -4.571492 -2.084324)
									(mid -3.570296 -3.611977)
									(end -2.875026 -5.30098)
								)
								(arc
									(start -2.875026 -5.30098)
									(mid 0.000217 -7.43089)
									(end 2.87528 -5.30098)
								)
								(arc
									(start 2.87528 -5.30098)
									(mid 3.570511 -3.611956)
									(end 4.571746 -2.084324)
								)
							)
							(width 0)
							(fill yes)
						)
					)
					(clearance 0.1524)
				)
				(layer "B.Cu"
					(shape oval)
					(size 14.0208 20.0152)
					(offset 0 -2.9972)
					(clearance -1.002284)
				)
			)
		)
		(zone
			(layers "F.Cu" "B.Cu" "In1.Cu" "In2.Cu" "In3.Cu" "In4.Cu" "In5.Cu" "In6.Cu")
			(hatch none 0.5)
			(connect_pads
				(clearance 0)
			)
			(min_thickness 0.25)
			(keepout
				(tracks not_allowed)
				(vias allowed)
				(pads allowed)
				(copperpour not_allowed)
				(footprints allowed)
			)
			(placement
				(enabled no)
				(sheetname "")
			)
			(fill
				(thermal_gap 0.5)
				(thermal_bridge_width 0.5)
				(island_removal_mode 0)
			)
			(polygon
				(pts
					(arc
						(start 293.189406 -99.994212)
						(mid 300.199806 -107.004612)
						(end 307.210206 -99.994212)
					)
					(arc
						(start 307.210206 -93.999812)
						(mid 300.199806 -86.989412)
						(end 293.189406 -93.999812)
					)
				)
			)
		)
	)
	(footprint ""
		(layer "F.Cu")
		(at 254.585978 -227.34905 -90)
		(property "Reference" "C28"
			(at 0 0 270)
			(layer "F.SilkS")
			(hide yes)
			(effects
				(font
					(size 1.27 1.27)
				)
			)
		)
		(property "Value" "SCD1U16V2KX-3GP"
			(at 1.1811 -2.7051 270)
			(unlocked yes)
			(layer "F.Fab")
			(hide yes)
			(effects
				(font
					(size 1.016 1.016)
					(thickness 0.1524)
				)
			)
		)
		(property "Device Type" "C402H22"
			(at 1.1811 -4.2291 270)
			(unlocked yes)
			(layer "F.Fab")
			(hide yes)
			(effects
				(font
					(size 1.016 1.016)
					(thickness 0.1524)
				)
			)
		)
		(duplicate_pad_numbers_are_jumpers no)
		(fp_rect
			(start -0.4318 0.9525)
			(end 0.4318 -0.9525)
			(stroke
				(width 0)
				(type default)
			)
			(fill no)
			(layer "F.CrtYd")
		)
		(fp_rect
			(start -0.4318 0.9525)
			(end 0.4318 -0.9525)
			(stroke
				(width 0)
				(type default)
			)
			(fill no)
			(layer "F.Fab")
		)
		(pad "1" smd custom
			(at 0 -0.4445 270)
			(size 0.1524 0.1524)
			(layers "F.Cu" "F.Mask" "F.Paste")
			(net "P5V_B_1_SENSE")
			(options
				(clearance outline)
				(anchor circle)
			)
			(primitives
				(gr_poly
					(pts
						(arc
							(start 0.3048 -0.2032)
							(mid 0.275042 -0.275042)
							(end 0.2032 -0.3048)
						)
						(arc
							(start -0.2032 -0.3048)
							(mid -0.275042 -0.275042)
							(end -0.3048 -0.2032)
						)
						(arc
							(start -0.3048 0.2032)
							(mid -0.275042 0.275042)
							(end -0.2032 0.3048)
						)
						(arc
							(start 0.2032 0.3048)
							(mid 0.275042 0.275042)
							(end 0.3048 0.2032)
						)
					)
					(width 0)
					(fill yes)
				)
			)
		)
		(pad "2" smd custom
			(at 0 0.4445 270)
			(size 0.1524 0.1524)
			(layers "F.Cu" "F.Mask" "F.Paste")
			(net "GND")
			(options
				(clearance outline)
				(anchor circle)
			)
			(primitives
				(gr_poly
					(pts
						(arc
							(start 0.3048 -0.2032)
							(mid 0.275042 -0.275042)
							(end 0.2032 -0.3048)
						)
						(arc
							(start -0.2032 -0.3048)
							(mid -0.275042 -0.275042)
							(end -0.3048 -0.2032)
						)
						(arc
							(start -0.3048 0.2032)
							(mid -0.275042 0.275042)
							(end -0.2032 0.3048)
						)
						(arc
							(start 0.2032 0.3048)
							(mid 0.275042 0.275042)
							(end 0.3048 0.2032)
						)
					)
					(width 0)
					(fill yes)
				)
			)
		)
	)
	(footprint ""
		(layer "F.Cu")
		(at 35.654996 -364.236 -90)
		(property "Reference" "R931"
			(at 0 0 270)
			(layer "F.SilkS")
			(hide yes)
			(effects
				(font
					(size 1.27 1.27)
				)
			)
		)
		(property "Value" "10KR2F-2-GP"
			(at 0.064008 -3.993896 270)
			(unlocked yes)
			(layer "F.Fab")
			(hide yes)
			(effects
				(font
					(size 1.016 1.016)
					(thickness 0.1524)
				)
			)
		)
		(property "Device Type" "R402H16"
			(at 0.064008 -5.517896 270)
			(unlocked yes)
			(layer "F.Fab")
			(hide yes)
			(effects
				(font
					(size 1.016 1.016)
					(thickness 0.1524)
				)
			)
		)
		(duplicate_pad_numbers_are_jumpers no)
		(fp_line
			(start -0.508 -0.9398)
			(end -0.508 0.9398)
			(stroke
				(width 0.1524)
				(type default)
			)
			(layer "F.SilkS")
		)
		(fp_line
			(start 0.508 -0.9398)
			(end -0.508 -0.9398)
			(stroke
				(width 0.1524)
				(type default)
			)
			(layer "F.SilkS")
		)
		(fp_rect
			(start -0.508 0.9398)
			(end 0.508 -0.9398)
			(stroke
				(width 0)
				(type default)
			)
			(fill no)
			(layer "F.CrtYd")
		)
		(fp_rect
			(start -0.508 0.9398)
			(end 0.508 -0.9398)
			(stroke
				(width 0)
				(type default)
			)
			(fill no)
			(layer "F.Fab")
		)
		(pad "1" smd custom
			(at 0 -0.4445 270)
			(size 0.1397 0.1397)
			(layers "F.Cu" "F.Mask" "F.Paste")
			(net "GND")
			(options
				(clearance outline)
				(anchor circle)
			)
			(primitives
				(gr_poly
					(pts
						(arc
							(start -0.1778 -0.2794)
							(mid -0.249642 -0.249642)
							(end -0.2794 -0.1778)
						)
						(arc
							(start -0.2794 0.1778)
							(mid -0.249642 0.249642)
							(end -0.1778 0.2794)
						)
						(arc
							(start 0.1778 0.2794)
							(mid 0.249642 0.249642)
							(end 0.2794 0.1778)
						)
						(arc
							(start 0.2794 -0.1778)
							(mid 0.249642 -0.249642)
							(end 0.1778 -0.2794)
						)
					)
					(width 0)
					(fill yes)
				)
			)
		)
		(pad "2" smd custom
			(at 0 0.4445 270)
			(size 0.1397 0.1397)
			(layers "F.Cu" "F.Mask" "F.Paste")
			(net "FANTACH_F0")
			(options
				(clearance outline)
				(anchor circle)
			)
			(primitives
				(gr_poly
					(pts
						(arc
							(start -0.1778 -0.2794)
							(mid -0.249642 -0.249642)
							(end -0.2794 -0.1778)
						)
						(arc
							(start -0.2794 0.1778)
							(mid -0.249642 0.249642)
							(end -0.1778 0.2794)
						)
						(arc
							(start 0.1778 0.2794)
							(mid 0.249642 0.249642)
							(end 0.2794 0.1778)
						)
						(arc
							(start 0.2794 -0.1778)
							(mid 0.249642 -0.249642)
							(end 0.1778 -0.2794)
						)
					)
					(width 0)
					(fill yes)
				)
			)
		)
	)
	(footprint ""
		(layer "F.Cu")
		(at 332.105 -131.318 -90)
		(property "Reference" "Q83"
			(at 0 0 270)
			(layer "F.SilkS")
			(hide yes)
			(effects
				(font
					(size 1.27 1.27)
				)
			)
		)
		(property "Value" "2N7002KDW-GP"
			(at -2.3622 -8.2042 270)
			(unlocked yes)
			(layer "F.Fab")
			(hide yes)
			(effects
				(font
					(size 1.016 1.016)
					(thickness 0.1524)
				)
			)
		)
		(property "Device Type" "SOT-363H44"
			(at -2.3622 -10.1092 270)
			(unlocked yes)
			(layer "F.Fab")
			(hide yes)
			(effects
				(font
					(size 1.016 1.016)
					(thickness 0.1524)
				)
			)
		)
		(duplicate_pad_numbers_are_jumpers no)
		(fp_line
			(start -1.4478 1.7018)
			(end 1.4478 1.7018)
			(stroke
				(width 0.1524)
				(type default)
			)
			(layer "F.SilkS")
		)
		(fp_line
			(start 1.4478 1.7018)
			(end 1.4478 -1.7018)
			(stroke
				(width 0.1524)
				(type default)
			)
			(layer "F.SilkS")
		)
		(fp_line
			(start -1.27 1.524)
			(end -1.27 0.6604)
			(stroke
				(width 0.4826)
				(type default)
			)
			(layer "F.SilkS")
		)
		(fp_line
			(start -1.4478 -1.7018)
			(end -1.4478 1.7018)
			(stroke
				(width 0.1524)
				(type default)
			)
			(layer "F.SilkS")
		)
		(fp_line
			(start 1.4478 -1.7018)
			(end -1.4478 -1.7018)
			(stroke
				(width 0.1524)
				(type default)
			)
			(layer "F.SilkS")
		)
		(fp_poly
			(pts
				(xy -1.524 -1.778) (xy 1.524 -1.778) (xy 1.524 1.778) (xy -1.524 1.778)
			)
			(stroke
				(width 0)
				(type default)
			)
			(fill no)
			(layer "F.CrtYd")
		)
		(fp_poly
			(pts
				(xy -1.524 -1.778) (xy 1.524 -1.778) (xy 1.524 1.778) (xy -1.524 1.778)
			)
			(stroke
				(width 0)
				(type default)
			)
			(fill no)
			(layer "F.Fab")
		)
		(pad "1" smd rect
			(at -0.65024 0.9398 270)
			(size 0.4064 1.016)
			(layers "F.Cu" "F.Mask" "F.Paste")
			(net "GND")
		)
		(pad "2" smd rect
			(at 0 0.9398 270)
			(size 0.4064 1.016)
			(layers "F.Cu" "F.Mask" "F.Paste")
			(net "SW_PWR_R_HDD18")
		)
		(pad "3" smd rect
			(at 0.65024 0.9398 270)
			(size 0.4064 1.016)
			(layers "F.Cu" "F.Mask" "F.Paste")
			(net "SW_HDD_P18")
		)
		(pad "4" smd rect
			(at 0.65024 -0.9398 270)
			(size 0.4064 1.016)
			(layers "F.Cu" "F.Mask" "F.Paste")
			(net "GND")
		)
		(pad "5" smd rect
			(at 0 -0.9398 270)
			(size 0.4064 1.016)
			(layers "F.Cu" "F.Mask" "F.Paste")
			(net "SW_HDD_G18")
		)
		(pad "6" smd rect
			(at -0.65024 -0.9398 270)
			(size 0.4064 1.016)
			(layers "F.Cu" "F.Mask" "F.Paste")
			(net "SW_HDD_R18")
		)
	)
	(footprint ""
		(layer "F.Cu")
		(at 209.804 -227.965 -90)
		(property "Reference" "R20"
			(at 0 0 270)
			(layer "F.SilkS")
			(hide yes)
			(effects
				(font
					(size 1.27 1.27)
				)
			)
		)
		(property "Value" "4K7R2F-GP"
			(at 0.064008 -3.993896 270)
			(unlocked yes)
			(layer "F.Fab")
			(hide yes)
			(effects
				(font
					(size 1.016 1.016)
					(thickness 0.1524)
				)
			)
		)
		(property "Device Type" "R402H16"
			(at 0.064008 -5.517896 270)
			(unlocked yes)
			(layer "F.Fab")
			(hide yes)
			(effects
				(font
					(size 1.016 1.016)
					(thickness 0.1524)
				)
			)
		)
		(duplicate_pad_numbers_are_jumpers no)
		(fp_line
			(start -0.508 -0.9398)
			(end -0.508 0.9398)
			(stroke
				(width 0.1524)
				(type default)
			)
			(layer "F.SilkS")
		)
		(fp_line
			(start 0.508 -0.9398)
			(end -0.508 -0.9398)
			(stroke
				(width 0.1524)
				(type default)
			)
			(layer "F.SilkS")
		)
		(fp_rect
			(start -0.508 0.9398)
			(end 0.508 -0.9398)
			(stroke
				(width 0)
				(type default)
			)
			(fill no)
			(layer "F.CrtYd")
		)
		(fp_rect
			(start -0.508 0.9398)
			(end 0.508 -0.9398)
			(stroke
				(width 0)
				(type default)
			)
			(fill no)
			(layer "F.Fab")
		)
		(pad "1" smd custom
			(at 0 -0.4445 270)
			(size 0.1397 0.1397)
			(layers "F.Cu" "F.Mask" "F.Paste")
			(net "IO_EXP1_HDD_FAULT_INT_N")
			(options
				(clearance outline)
				(anchor circle)
			)
			(primitives
				(gr_poly
					(pts
						(arc
							(start -0.1778 -0.2794)
							(mid -0.249642 -0.249642)
							(end -0.2794 -0.1778)
						)
						(arc
							(start -0.2794 0.1778)
							(mid -0.249642 0.249642)
							(end -0.1778 0.2794)
						)
						(arc
							(start 0.1778 0.2794)
							(mid 0.249642 0.249642)
							(end 0.2794 0.1778)
						)
						(arc
							(start 0.2794 -0.1778)
							(mid 0.249642 -0.249642)
							(end 0.1778 -0.2794)
						)
					)
					(width 0)
					(fill yes)
				)
			)
		)
		(pad "2" smd custom
			(at 0 0.4445 270)
			(size 0.1397 0.1397)
			(layers "F.Cu" "F.Mask" "F.Paste")
			(net "P3V3_STBY_B")
			(options
				(clearance outline)
				(anchor circle)
			)
			(primitives
				(gr_poly
					(pts
						(arc
							(start -0.1778 -0.2794)
							(mid -0.249642 -0.249642)
							(end -0.2794 -0.1778)
						)
						(arc
							(start -0.2794 0.1778)
							(mid -0.249642 0.249642)
							(end -0.1778 0.2794)
						)
						(arc
							(start 0.1778 0.2794)
							(mid 0.249642 0.249642)
							(end 0.2794 0.1778)
						)
						(arc
							(start 0.2794 -0.1778)
							(mid 0.249642 -0.249642)
							(end 0.1778 -0.2794)
						)
					)
					(width 0)
					(fill yes)
				)
			)
		)
	)
	(footprint ""
		(layer "F.Cu")
		(at 460.3242 -18.4658 -90)
		(property "Reference" "Q179"
			(at 0 0 270)
			(layer "F.SilkS")
			(hide yes)
			(effects
				(font
					(size 1.27 1.27)
				)
			)
		)
		(property "Value" "2N7002KDW-GP"
			(at -2.3622 -8.2042 270)
			(unlocked yes)
			(layer "F.Fab")
			(hide yes)
			(effects
				(font
					(size 1.016 1.016)
					(thickness 0.1524)
				)
			)
		)
		(property "Device Type" "SOT-363H44"
			(at -2.3622 -10.1092 270)
			(unlocked yes)
			(layer "F.Fab")
			(hide yes)
			(effects
				(font
					(size 1.016 1.016)
					(thickness 0.1524)
				)
			)
		)
		(duplicate_pad_numbers_are_jumpers no)
		(fp_line
			(start -1.4478 1.7018)
			(end 1.4478 1.7018)
			(stroke
				(width 0.1524)
				(type default)
			)
			(layer "F.SilkS")
		)
		(fp_line
			(start 1.4478 1.7018)
			(end 1.4478 -1.7018)
			(stroke
				(width 0.1524)
				(type default)
			)
			(layer "F.SilkS")
		)
		(fp_line
			(start -1.27 1.524)
			(end -1.27 0.6604)
			(stroke
				(width 0.4826)
				(type default)
			)
			(layer "F.SilkS")
		)
		(fp_line
			(start -1.4478 -1.7018)
			(end -1.4478 1.7018)
			(stroke
				(width 0.1524)
				(type default)
			)
			(layer "F.SilkS")
		)
		(fp_line
			(start 1.4478 -1.7018)
			(end -1.4478 -1.7018)
			(stroke
				(width 0.1524)
				(type default)
			)
			(layer "F.SilkS")
		)
		(fp_poly
			(pts
				(xy -1.524 -1.778) (xy 1.524 -1.778) (xy 1.524 1.778) (xy -1.524 1.778)
			)
			(stroke
				(width 0)
				(type default)
			)
			(fill no)
			(layer "F.CrtYd")
		)
		(fp_poly
			(pts
				(xy -1.524 -1.778) (xy 1.524 -1.778) (xy 1.524 1.778) (xy -1.524 1.778)
			)
			(stroke
				(width 0)
				(type default)
			)
			(fill no)
			(layer "F.Fab")
		)
		(pad "1" smd rect
			(at -0.65024 0.9398 270)
			(size 0.4064 1.016)
			(layers "F.Cu" "F.Mask" "F.Paste")
			(net "GND")
		)
		(pad "2" smd rect
			(at 0 0.9398 270)
			(size 0.4064 1.016)
			(layers "F.Cu" "F.Mask" "F.Paste")
			(net "SW_PWR_R_HDD34")
		)
		(pad "3" smd rect
			(at 0.65024 0.9398 270)
			(size 0.4064 1.016)
			(layers "F.Cu" "F.Mask" "F.Paste")
			(net "SW_HDD_P34")
		)
		(pad "4" smd rect
			(at 0.65024 -0.9398 270)
			(size 0.4064 1.016)
			(layers "F.Cu" "F.Mask" "F.Paste")
			(net "GND")
		)
		(pad "5" smd rect
			(at 0 -0.9398 270)
			(size 0.4064 1.016)
			(layers "F.Cu" "F.Mask" "F.Paste")
			(net "SW_HDD_G34")
		)
		(pad "6" smd rect
			(at -0.65024 -0.9398 270)
			(size 0.4064 1.016)
			(layers "F.Cu" "F.Mask" "F.Paste")
			(net "SW_HDD_R34")
		)
	)
	(footprint ""
		(layer "F.Cu")
		(at 46.355 -265.684 -90)
		(property "Reference" "C48"
			(at 0 0 270)
			(layer "F.SilkS")
			(hide yes)
			(effects
				(font
					(size 1.27 1.27)
				)
			)
		)
		(property "Value" "SC4D7U25V5KX-1-GP"
			(at -0.0762 -6.1214 270)
			(unlocked yes)
			(layer "F.Fab")
			(hide yes)
			(effects
				(font
					(size 1.016 1.016)
					(thickness 0.1524)
				)
			)
		)
		(property "Device Type" "C805H58"
			(at -0.0762 -8.1534 270)
			(unlocked yes)
			(layer "F.Fab")
			(hide yes)
			(effects
				(font
					(size 1.016 1.016)
					(thickness 0.1524)
				)
			)
		)
		(duplicate_pad_numbers_are_jumpers no)
		(fp_line
			(start 0.635 0)
			(end -0.635 0)
			(stroke
				(width 0.508)
				(type default)
			)
			(layer "F.SilkS")
		)
		(fp_rect
			(start -0.9652 1.778)
			(end 0.9652 -1.778)
			(stroke
				(width 0)
				(type default)
			)
			(fill no)
			(layer "F.CrtYd")
		)
		(fp_poly
			(pts
				(xy -0.9652 -1.778) (xy 0.9652 -1.778) (xy 0.9652 1.778) (xy -0.9652 1.778)
			)
			(stroke
				(width 0)
				(type default)
			)
			(fill no)
			(layer "F.Fab")
		)
		(pad "1" smd rect
			(at 0 -0.9652 270)
			(size 1.397 1.143)
			(layers "F.Cu" "F.Mask" "F.Paste")
			(net "P12V_HDD1")
		)
		(pad "2" smd rect
			(at 0 0.9652 270)
			(size 1.397 1.143)
			(layers "F.Cu" "F.Mask" "F.Paste")
			(net "GND")
		)
	)
	(footprint ""
		(layer "F.Cu")
		(at 129.413762 -154.70505)
		(property "Reference" "TP96"
			(at 0 0 0)
			(layer "F.SilkS")
			(hide yes)
			(effects
				(font
					(size 1.27 1.27)
				)
			)
		)
		(property "Value" "*"
			(at -0.0508 -1.6764 0)
			(unlocked yes)
			(layer "F.Fab")
			(hide yes)
			(effects
				(font
					(size 1.016 1.016)
					(thickness 0.1524)
				)
			)
		)
		(property "Device Type" "TPAD32"
			(at -0.0508 -3.2004 0)
			(unlocked yes)
			(layer "F.Fab")
			(hide yes)
			(effects
				(font
					(size 1.016 1.016)
					(thickness 0.1524)
				)
			)
		)
		(duplicate_pad_numbers_are_jumpers no)
		(fp_poly
			(pts
				(arc
					(start 0.4064 0)
					(mid -0.4064 0)
					(end 0.4064 0)
				)
			)
			(stroke
				(width 0)
				(type default)
			)
			(fill no)
			(layer "F.CrtYd")
		)
		(fp_poly
			(pts
				(arc
					(start 0.7112 0)
					(mid -0.7112 0)
					(end 0.7112 0)
				)
			)
			(stroke
				(width 0)
				(type default)
			)
			(fill no)
			(layer "F.Fab")
		)
		(pad "1" smd circle
			(at 0 0)
			(size 0.8128 0.8128)
			(layers "F.Cu" "F.Mask" "F.Paste")
			(net "ACT_HDD_15")
		)
	)
	(footprint ""
		(layer "F.Cu")
		(at 265.0617 -379.174756 -90)
		(property "Reference" "R1066"
			(at 0 0 270)
			(layer "F.SilkS")
			(hide yes)
			(effects
				(font
					(size 1.27 1.27)
				)
			)
		)
		(property "Value" "0R2J-2-GP"
			(at 0.064008 -3.993896 270)
			(unlocked yes)
			(layer "F.Fab")
			(hide yes)
			(effects
				(font
					(size 1.016 1.016)
					(thickness 0.1524)
				)
			)
		)
		(property "Device Type" "R402H16"
			(at 0.064008 -5.517896 270)
			(unlocked yes)
			(layer "F.Fab")
			(hide yes)
			(effects
				(font
					(size 1.016 1.016)
					(thickness 0.1524)
				)
			)
		)
		(duplicate_pad_numbers_are_jumpers no)
		(fp_line
			(start -0.508 -0.9398)
			(end -0.508 0.9398)
			(stroke
				(width 0.1524)
				(type default)
			)
			(layer "F.SilkS")
		)
		(fp_line
			(start 0.508 -0.9398)
			(end -0.508 -0.9398)
			(stroke
				(width 0.1524)
				(type default)
			)
			(layer "F.SilkS")
		)
		(fp_rect
			(start -0.508 0.9398)
			(end 0.508 -0.9398)
			(stroke
				(width 0)
				(type default)
			)
			(fill no)
			(layer "F.CrtYd")
		)
		(fp_rect
			(start -0.508 0.9398)
			(end 0.508 -0.9398)
			(stroke
				(width 0)
				(type default)
			)
			(fill no)
			(layer "F.Fab")
		)
		(pad "1" smd custom
			(at 0 -0.4445 270)
			(size 0.1397 0.1397)
			(layers "F.Cu" "F.Mask" "F.Paste")
			(net "IR_SWITCH_E")
			(options
				(clearance outline)
				(anchor circle)
			)
			(primitives
				(gr_poly
					(pts
						(arc
							(start -0.1778 -0.2794)
							(mid -0.249642 -0.249642)
							(end -0.2794 -0.1778)
						)
						(arc
							(start -0.2794 0.1778)
							(mid -0.249642 0.249642)
							(end -0.1778 0.2794)
						)
						(arc
							(start 0.1778 0.2794)
							(mid 0.249642 0.249642)
							(end 0.2794 0.1778)
						)
						(arc
							(start 0.2794 -0.1778)
							(mid 0.249642 -0.249642)
							(end 0.1778 -0.2794)
						)
					)
					(width 0)
					(fill yes)
				)
			)
		)
		(pad "2" smd custom
			(at 0 0.4445 270)
			(size 0.1397 0.1397)
			(layers "F.Cu" "F.Mask" "F.Paste")
			(net "DRAWER_OUT_NET")
			(options
				(clearance outline)
				(anchor circle)
			)
			(primitives
				(gr_poly
					(pts
						(arc
							(start -0.1778 -0.2794)
							(mid -0.249642 -0.249642)
							(end -0.2794 -0.1778)
						)
						(arc
							(start -0.2794 0.1778)
							(mid -0.249642 0.249642)
							(end -0.1778 0.2794)
						)
						(arc
							(start 0.1778 0.2794)
							(mid 0.249642 0.249642)
							(end 0.2794 0.1778)
						)
						(arc
							(start 0.2794 -0.1778)
							(mid 0.249642 -0.249642)
							(end 0.1778 -0.2794)
						)
					)
					(width 0)
					(fill yes)
				)
			)
		)
	)
	(footprint ""
		(layer "F.Cu")
		(at 32.463486 -130.21945 90)
		(property "Reference" "C184"
			(at 0 0 90)
			(layer "F.SilkS")
			(hide yes)
			(effects
				(font
					(size 1.27 1.27)
				)
			)
		)
		(property "Value" "SCD01U16V1KX-GP"
			(at -2.8321 -1.7399 90)
			(unlocked yes)
			(layer "F.Fab")
			(hide yes)
			(effects
				(font
					(size 1.016 1.016)
					(thickness 0.1524)
				)
			)
		)
		(property "Device Type" "C0201H13"
			(at -2.8321 -3.2639 90)
			(unlocked yes)
			(layer "F.Fab")
			(hide yes)
			(effects
				(font
					(size 1.016 1.016)
					(thickness 0.1524)
				)
			)
		)
		(duplicate_pad_numbers_are_jumpers no)
		(fp_rect
			(start -0.2794 0.6477)
			(end 0.2794 -0.6477)
			(stroke
				(width 0)
				(type default)
			)
			(fill no)
			(layer "F.CrtYd")
		)
		(fp_rect
			(start -0.2794 0.6477)
			(end 0.2794 -0.6477)
			(stroke
				(width 0)
				(type default)
			)
			(fill no)
			(layer "F.Fab")
		)
		(pad "1" smd custom
			(at 0 -0.2794 90)
			(size 0.0762 0.0762)
			(layers "F.Cu" "F.Mask" "F.Paste")
			(net "SAS_HDD_RX_N12")
			(options
				(clearance outline)
				(anchor circle)
			)
			(primitives
				(gr_poly
					(pts
						(arc
							(start 0.1524 -0.127)
							(mid 0.137521 -0.162921)
							(end 0.1016 -0.1778)
						)
						(arc
							(start -0.1016 -0.1778)
							(mid -0.137521 -0.162921)
							(end -0.1524 -0.127)
						)
						(arc
							(start -0.1524 0.127)
							(mid -0.137521 0.162921)
							(end -0.1016 0.1778)
						)
						(arc
							(start 0.1016 0.1778)
							(mid 0.137521 0.162921)
							(end 0.1524 0.127)
						)
					)
					(width 0)
					(fill yes)
				)
			)
		)
		(pad "2" smd custom
			(at 0 0.2794 90)
			(size 0.0762 0.0762)
			(layers "F.Cu" "F.Mask" "F.Paste")
			(net "PHY_SCC_B_TO_DRV_B_12_DN")
			(options
				(clearance outline)
				(anchor circle)
			)
			(primitives
				(gr_poly
					(pts
						(arc
							(start 0.1524 -0.127)
							(mid 0.137521 -0.162921)
							(end 0.1016 -0.1778)
						)
						(arc
							(start -0.1016 -0.1778)
							(mid -0.137521 -0.162921)
							(end -0.1524 -0.127)
						)
						(arc
							(start -0.1524 0.127)
							(mid -0.137521 0.162921)
							(end -0.1016 0.1778)
						)
						(arc
							(start 0.1016 0.1778)
							(mid 0.137521 0.162921)
							(end 0.1524 0.127)
						)
					)
					(width 0)
					(fill yes)
				)
			)
		)
	)
	(footprint ""
		(layer "F.Cu")
		(at 265.586972 -355.444806 90)
		(property "Reference" "R1056"
			(at 0 0 90)
			(layer "F.SilkS")
			(hide yes)
			(effects
				(font
					(size 1.27 1.27)
				)
			)
		)
		(property "Value" "0R5J-5-GP"
			(at 0 -8.9535 90)
			(unlocked yes)
			(layer "F.Fab")
			(hide yes)
			(effects
				(font
					(size 1.27 1.016)
					(thickness 0.1524)
				)
			)
		)
		(property "Device Type" "R805H24"
			(at 0 -10.6299 90)
			(unlocked yes)
			(layer "F.Fab")
			(hide yes)
			(effects
				(font
					(size 1.27 1.016)
					(thickness 0.1524)
				)
			)
		)
		(duplicate_pad_numbers_are_jumpers no)
		(fp_line
			(start 0.889 -1.7018)
			(end -0.889 -1.7018)
			(stroke
				(width 0.1524)
				(type default)
			)
			(layer "F.SilkS")
		)
		(fp_line
			(start 0.889 -1.7018)
			(end 0.889 -0.381)
			(stroke
				(width 0.1524)
				(type default)
			)
			(layer "F.SilkS")
		)
		(fp_line
			(start -0.889 -1.7018)
			(end -0.889 0.2794)
			(stroke
				(width 0.1524)
				(type default)
			)
			(layer "F.SilkS")
		)
		(fp_line
			(start -0.889 0.0762)
			(end -0.889 1.7018)
			(stroke
				(width 0.1524)
				(type default)
			)
			(layer "F.SilkS")
		)
		(fp_line
			(start 0.889 1.7018)
			(end 0.889 -0.508)
			(stroke
				(width 0.1524)
				(type default)
			)
			(layer "F.SilkS")
		)
		(fp_line
			(start -0.889 1.7018)
			(end 0.889 1.7018)
			(stroke
				(width 0.1524)
				(type default)
			)
			(layer "F.SilkS")
		)
		(fp_poly
			(pts
				(xy 0.9652 -1.778) (xy 0.9652 1.778) (xy -0.9652 1.778) (xy -0.9652 -1.778)
			)
			(stroke
				(width 0)
				(type default)
			)
			(fill no)
			(layer "F.CrtYd")
		)
		(fp_rect
			(start -0.9652 1.778)
			(end 0.9652 -1.778)
			(stroke
				(width 0)
				(type default)
			)
			(fill no)
			(layer "F.Fab")
		)
		(pad "1" smd rect
			(at 0 -0.9652 90)
			(size 1.397 1.143)
			(layers "F.Cu" "F.Mask" "F.Paste")
			(net "MB3_CM_GATE")
		)
		(pad "2" smd rect
			(at 0 0.9652 90)
			(size 1.397 1.143)
			(layers "F.Cu" "F.Mask" "F.Paste")
			(net "MB3_CM_GATE_R")
		)
	)
	(footprint ""
		(layer "F.Cu")
		(at 16.891 -247.65 180)
		(property "Reference" "D36"
			(at 0 0 180)
			(layer "F.SilkS")
			(hide yes)
			(effects
				(font
					(size 1.27 1.27)
				)
			)
		)
		(property "Value" "RB551V30-GP"
			(at 0 -6.7818 180)
			(unlocked yes)
			(layer "F.Fab")
			(hide yes)
			(effects
				(font
					(size 1.016 1.016)
					(thickness 0.1524)
				)
			)
		)
		(property "Device Type" "SOD323AKH38"
			(at 0 -8.6868 180)
			(unlocked yes)
			(layer "F.Fab")
			(hide yes)
			(effects
				(font
					(size 1.016 1.016)
					(thickness 0.1524)
				)
			)
		)
		(duplicate_pad_numbers_are_jumpers no)
		(fp_line
			(start 0.889 2.159)
			(end -0.889 2.159)
			(stroke
				(width 0.1524)
				(type default)
			)
			(layer "F.SilkS")
		)
		(fp_line
			(start 0.889 -1.9304)
			(end 0.889 2.159)
			(stroke
				(width 0.1524)
				(type default)
			)
			(layer "F.SilkS")
		)
		(fp_line
			(start 0.762 2.0574)
			(end -0.762 2.0574)
			(stroke
				(width 0.508)
				(type default)
			)
			(layer "F.SilkS")
		)
		(fp_line
			(start -0.889 2.159)
			(end -0.889 -1.9304)
			(stroke
				(width 0.1524)
				(type default)
			)
			(layer "F.SilkS")
		)
		(fp_line
			(start -0.889 -1.9304)
			(end 0.889 -1.9304)
			(stroke
				(width 0.1524)
				(type default)
			)
			(layer "F.SilkS")
		)
		(fp_rect
			(start -1.016 2.3114)
			(end 1.016 -2.0066)
			(stroke
				(width 0)
				(type default)
			)
			(fill no)
			(layer "F.CrtYd")
		)
		(fp_poly
			(pts
				(xy -1.016 -2.0066) (xy 1.016 -2.0066) (xy 1.016 2.3114) (xy -1.016 2.3114)
			)
			(stroke
				(width 0)
				(type default)
			)
			(fill no)
			(layer "F.Fab")
		)
		(pad "A" smd rect
			(at 0 -1.143 180)
			(size 0.5588 1.016)
			(layers "F.Cu" "F.Mask" "F.Paste")
			(net "SW_HDD_R0")
		)
		(pad "K" smd rect
			(at 0 1.143 180)
			(size 0.5588 1.016)
			(layers "F.Cu" "F.Mask" "F.Paste")
			(net "SW_HDD_N0")
		)
	)
	(footprint ""
		(layer "F.Cu")
		(at 14.732 -265.684 -90)
		(property "Reference" "C502"
			(at 0 0 270)
			(layer "F.SilkS")
			(hide yes)
			(effects
				(font
					(size 1.27 1.27)
				)
			)
		)
		(property "Value" "SC4D7U25V5KX-1-GP"
			(at -0.0762 -6.1214 270)
			(unlocked yes)
			(layer "F.Fab")
			(hide yes)
			(effects
				(font
					(size 1.016 1.016)
					(thickness 0.1524)
				)
			)
		)
		(property "Device Type" "C805H58"
			(at -0.0762 -8.1534 270)
			(unlocked yes)
			(layer "F.Fab")
			(hide yes)
			(effects
				(font
					(size 1.016 1.016)
					(thickness 0.1524)
				)
			)
		)
		(duplicate_pad_numbers_are_jumpers no)
		(fp_line
			(start 0.635 0)
			(end -0.635 0)
			(stroke
				(width 0.508)
				(type default)
			)
			(layer "F.SilkS")
		)
		(fp_rect
			(start -0.9652 1.778)
			(end 0.9652 -1.778)
			(stroke
				(width 0)
				(type default)
			)
			(fill no)
			(layer "F.CrtYd")
		)
		(fp_poly
			(pts
				(xy -0.9652 -1.778) (xy 0.9652 -1.778) (xy 0.9652 1.778) (xy -0.9652 1.778)
			)
			(stroke
				(width 0)
				(type default)
			)
			(fill no)
			(layer "F.Fab")
		)
		(pad "1" smd rect
			(at 0 -0.9652 270)
			(size 1.397 1.143)
			(layers "F.Cu" "F.Mask" "F.Paste")
			(net "P12V_HDD0")
		)
		(pad "2" smd rect
			(at 0 0.9652 270)
			(size 1.397 1.143)
			(layers "F.Cu" "F.Mask" "F.Paste")
			(net "GND")
		)
	)
	(footprint ""
		(layer "F.Cu")
		(at 52.324 -256.286 180)
		(property "Reference" "Q2"
			(at 0 0 180)
			(layer "F.SilkS")
			(hide yes)
			(effects
				(font
					(size 1.27 1.27)
				)
			)
		)
		(property "Value" "AO4406AL-GP"
			(at -3.707384 -1.5367 180)
			(unlocked yes)
			(layer "F.Fab")
			(hide yes)
			(effects
				(font
					(size 1.016 1.016)
					(thickness 0.1524)
				)
			)
		)
		(property "Device Type" "SOIC8H69"
			(at -3.707384 -3.0607 180)
			(unlocked yes)
			(layer "F.Fab")
			(hide yes)
			(effects
				(font
					(size 1.016 1.016)
					(thickness 0.1524)
				)
			)
		)
		(duplicate_pad_numbers_are_jumpers no)
		(fp_line
			(start 2.1336 1.4224)
			(end 2.1336 -1.4224)
			(stroke
				(width 0.1524)
				(type default)
			)
			(layer "F.SilkS")
		)
		(fp_line
			(start 2.1336 -1.4224)
			(end -2.7432 -1.4224)
			(stroke
				(width 0.1524)
				(type default)
			)
			(layer "F.SilkS")
		)
		(fp_line
			(start -2.1844 -0.0508)
			(end -2.7178 0.508)
			(stroke
				(width 0.1524)
				(type default)
			)
			(layer "F.SilkS")
		)
		(fp_line
			(start -2.6289 3.4417)
			(end -2.6289 1.4732)
			(stroke
				(width 0.381)
				(type default)
			)
			(layer "F.SilkS")
		)
		(fp_line
			(start -2.7178 -0.508)
			(end -2.1844 -0.0508)
			(stroke
				(width 0.1524)
				(type default)
			)
			(layer "F.SilkS")
		)
		(fp_line
			(start -2.7432 1.4224)
			(end 2.1336 1.4224)
			(stroke
				(width 0.1524)
				(type default)
			)
			(layer "F.SilkS")
		)
		(fp_line
			(start -2.7432 1.4224)
			(end -2.6416 1.4224)
			(stroke
				(width 0.1524)
				(type default)
			)
			(layer "F.SilkS")
		)
		(fp_line
			(start -2.7432 -1.4224)
			(end -2.7432 1.4224)
			(stroke
				(width 0.1524)
				(type default)
			)
			(layer "F.SilkS")
		)
		(fp_poly
			(pts
				(xy -2.2098 -1.4224) (xy -2.2098 1.4224) (xy 2.2098 1.4224) (xy 2.2098 -1.4224)
			)
			(stroke
				(width 0)
				(type default)
			)
			(fill yes)
			(layer "F.SilkS")
		)
		(fp_rect
			(start -2.450084 2.999994)
			(end 2.450084 -2.999994)
			(stroke
				(width 0)
				(type default)
			)
			(fill no)
			(layer "F.CrtYd")
		)
		(fp_poly
			(pts
				(xy -2.8194 3.6322) (xy -2.8194 -3.6322) (xy 2.8194 -3.6322) (xy 2.8194 1.18364) (xy 2.450084 1.18364)
				(xy 2.450084 -2.999994) (xy -2.450084 -2.999994) (xy -2.450084 2.999994) (xy 2.450084 2.999994)
				(xy 2.450084 1.18618) (xy 2.8194 1.18618) (xy 2.8194 3.6322)
			)
			(stroke
				(width 0)
				(type default)
			)
			(fill no)
			(layer "F.CrtYd")
		)
		(fp_rect
			(start -2.8194 3.6322)
			(end 2.8194 -3.6322)
			(stroke
				(width 0)
				(type default)
			)
			(fill no)
			(layer "F.Fab")
		)
		(pad "1" smd rect
			(at -1.905 2.54 180)
			(size 0.635 1.651)
			(layers "F.Cu" "F.Mask" "F.Paste")
			(net "P5V_HDD1")
		)
		(pad "2" smd rect
			(at -0.635 2.54 180)
			(size 0.635 1.651)
			(layers "F.Cu" "F.Mask" "F.Paste")
			(net "P5V_HDD1")
		)
		(pad "3" smd rect
			(at 0.635 2.54 180)
			(size 0.635 1.651)
			(layers "F.Cu" "F.Mask" "F.Paste")
			(net "P5V_HDD1")
		)
		(pad "4" smd rect
			(at 1.905 2.54 180)
			(size 0.635 1.651)
			(layers "F.Cu" "F.Mask" "F.Paste")
			(net "SW_HDD_P1")
		)
		(pad "5" smd rect
			(at 1.905 -2.54 180)
			(size 0.635 1.651)
			(layers "F.Cu" "F.Mask" "F.Paste")
			(net "P5V_B_1")
		)
		(pad "6" smd rect
			(at 0.635 -2.54 180)
			(size 0.635 1.651)
			(layers "F.Cu" "F.Mask" "F.Paste")
			(net "P5V_B_1")
		)
		(pad "7" smd rect
			(at -0.635 -2.54 180)
			(size 0.635 1.651)
			(layers "F.Cu" "F.Mask" "F.Paste")
			(net "P5V_B_1")
		)
		(pad "8" smd rect
			(at -1.905 -2.54 180)
			(size 0.635 1.651)
			(layers "F.Cu" "F.Mask" "F.Paste")
			(net "P5V_B_1")
		)
	)
	(footprint ""
		(layer "F.Cu")
		(at 109.347 -150.622 -90)
		(property "Reference" "C229"
			(at 0 0 270)
			(layer "F.SilkS")
			(hide yes)
			(effects
				(font
					(size 1.27 1.27)
				)
			)
		)
		(property "Value" "SC4D7U25V5KX-1-GP"
			(at -0.0762 -6.1214 270)
			(unlocked yes)
			(layer "F.Fab")
			(hide yes)
			(effects
				(font
					(size 1.016 1.016)
					(thickness 0.1524)
				)
			)
		)
		(property "Device Type" "C805H58"
			(at -0.0762 -8.1534 270)
			(unlocked yes)
			(layer "F.Fab")
			(hide yes)
			(effects
				(font
					(size 1.016 1.016)
					(thickness 0.1524)
				)
			)
		)
		(duplicate_pad_numbers_are_jumpers no)
		(fp_line
			(start 0.635 0)
			(end -0.635 0)
			(stroke
				(width 0.508)
				(type default)
			)
			(layer "F.SilkS")
		)
		(fp_rect
			(start -0.9652 1.778)
			(end 0.9652 -1.778)
			(stroke
				(width 0)
				(type default)
			)
			(fill no)
			(layer "F.CrtYd")
		)
		(fp_poly
			(pts
				(xy -0.9652 -1.778) (xy 0.9652 -1.778) (xy 0.9652 1.778) (xy -0.9652 1.778)
			)
			(stroke
				(width 0)
				(type default)
			)
			(fill no)
			(layer "F.Fab")
		)
		(pad "1" smd rect
			(at 0 -0.9652 270)
			(size 1.397 1.143)
			(layers "F.Cu" "F.Mask" "F.Paste")
			(net "P12V_HDD15")
		)
		(pad "2" smd rect
			(at 0 0.9652 270)
			(size 1.397 1.143)
			(layers "F.Cu" "F.Mask" "F.Paste")
			(net "GND")
		)
	)
	(footprint ""
		(layer "F.Cu")
		(at 175.514 -363.22 90)
		(property "Reference" "R1007"
			(at 0 0 90)
			(layer "F.SilkS")
			(hide yes)
			(effects
				(font
					(size 1.27 1.27)
				)
			)
		)
		(property "Value" "100KR2F-L1-GP"
			(at 0.064008 -3.993896 90)
			(unlocked yes)
			(layer "F.Fab")
			(hide yes)
			(effects
				(font
					(size 1.016 1.016)
					(thickness 0.1524)
				)
			)
		)
		(property "Device Type" "R402H16"
			(at 0.064008 -5.517896 90)
			(unlocked yes)
			(layer "F.Fab")
			(hide yes)
			(effects
				(font
					(size 1.016 1.016)
					(thickness 0.1524)
				)
			)
		)
		(duplicate_pad_numbers_are_jumpers no)
		(fp_line
			(start 0.508 -0.9398)
			(end -0.508 -0.9398)
			(stroke
				(width 0.1524)
				(type default)
			)
			(layer "F.SilkS")
		)
		(fp_line
			(start -0.508 -0.9398)
			(end -0.508 0.9398)
			(stroke
				(width 0.1524)
				(type default)
			)
			(layer "F.SilkS")
		)
		(fp_rect
			(start -0.508 0.9398)
			(end 0.508 -0.9398)
			(stroke
				(width 0)
				(type default)
			)
			(fill no)
			(layer "F.CrtYd")
		)
		(fp_rect
			(start -0.508 0.9398)
			(end 0.508 -0.9398)
			(stroke
				(width 0)
				(type default)
			)
			(fill no)
			(layer "F.Fab")
		)
		(pad "1" smd custom
			(at 0 -0.4445 90)
			(size 0.1397 0.1397)
			(layers "F.Cu" "F.Mask" "F.Paste")
			(net "MB0_VCAP_R")
			(options
				(clearance outline)
				(anchor circle)
			)
			(primitives
				(gr_poly
					(pts
						(arc
							(start -0.1778 -0.2794)
							(mid -0.249642 -0.249642)
							(end -0.2794 -0.1778)
						)
						(arc
							(start -0.2794 0.1778)
							(mid -0.249642 0.249642)
							(end -0.1778 0.2794)
						)
						(arc
							(start 0.1778 0.2794)
							(mid 0.249642 0.249642)
							(end 0.2794 0.1778)
						)
						(arc
							(start 0.2794 -0.1778)
							(mid 0.249642 -0.249642)
							(end 0.1778 -0.2794)
						)
					)
					(width 0)
					(fill yes)
				)
			)
		)
		(pad "2" smd custom
			(at 0 0.4445 90)
			(size 0.1397 0.1397)
			(layers "F.Cu" "F.Mask" "F.Paste")
			(net "MB0_ISTART_R")
			(options
				(clearance outline)
				(anchor circle)
			)
			(primitives
				(gr_poly
					(pts
						(arc
							(start -0.1778 -0.2794)
							(mid -0.249642 -0.249642)
							(end -0.2794 -0.1778)
						)
						(arc
							(start -0.2794 0.1778)
							(mid -0.249642 0.249642)
							(end -0.1778 0.2794)
						)
						(arc
							(start 0.1778 0.2794)
							(mid 0.249642 0.249642)
							(end 0.2794 0.1778)
						)
						(arc
							(start 0.2794 -0.1778)
							(mid 0.249642 -0.249642)
							(end 0.1778 -0.2794)
						)
					)
					(width 0)
					(fill yes)
				)
			)
		)
	)
	(footprint ""
		(layer "F.Cu")
		(at 384.8608 -146.6342)
		(property "Reference" "C297"
			(at 0 0 0)
			(layer "F.SilkS")
			(hide yes)
			(effects
				(font
					(size 1.27 1.27)
				)
			)
		)
		(property "Value" "SCD01U50V2KX-1GP"
			(at 1.1811 -2.7051 0)
			(unlocked yes)
			(layer "F.Fab")
			(hide yes)
			(effects
				(font
					(size 1.016 1.016)
					(thickness 0.1524)
				)
			)
		)
		(property "Device Type" "C402H22"
			(at 1.1811 -4.2291 0)
			(unlocked yes)
			(layer "F.Fab")
			(hide yes)
			(effects
				(font
					(size 1.016 1.016)
					(thickness 0.1524)
				)
			)
		)
		(duplicate_pad_numbers_are_jumpers no)
		(fp_rect
			(start -0.4318 0.9525)
			(end 0.4318 -0.9525)
			(stroke
				(width 0)
				(type default)
			)
			(fill no)
			(layer "F.CrtYd")
		)
		(fp_rect
			(start -0.4318 0.9525)
			(end 0.4318 -0.9525)
			(stroke
				(width 0)
				(type default)
			)
			(fill no)
			(layer "F.Fab")
		)
		(pad "1" smd custom
			(at 0 -0.4445)
			(size 0.1524 0.1524)
			(layers "F.Cu" "F.Mask" "F.Paste")
			(net "HDD_PRSNT_20")
			(options
				(clearance outline)
				(anchor circle)
			)
			(primitives
				(gr_poly
					(pts
						(arc
							(start 0.3048 -0.2032)
							(mid 0.275042 -0.275042)
							(end 0.2032 -0.3048)
						)
						(arc
							(start -0.2032 -0.3048)
							(mid -0.275042 -0.275042)
							(end -0.3048 -0.2032)
						)
						(arc
							(start -0.3048 0.2032)
							(mid -0.275042 0.275042)
							(end -0.2032 0.3048)
						)
						(arc
							(start 0.2032 0.3048)
							(mid 0.275042 0.275042)
							(end 0.3048 0.2032)
						)
					)
					(width 0)
					(fill yes)
				)
			)
		)
		(pad "2" smd custom
			(at 0 0.4445)
			(size 0.1524 0.1524)
			(layers "F.Cu" "F.Mask" "F.Paste")
			(net "GND")
			(options
				(clearance outline)
				(anchor circle)
			)
			(primitives
				(gr_poly
					(pts
						(arc
							(start 0.3048 -0.2032)
							(mid 0.275042 -0.275042)
							(end 0.2032 -0.3048)
						)
						(arc
							(start -0.2032 -0.3048)
							(mid -0.275042 -0.275042)
							(end -0.3048 -0.2032)
						)
						(arc
							(start -0.3048 0.2032)
							(mid -0.275042 0.275042)
							(end -0.2032 0.3048)
						)
						(arc
							(start 0.2032 0.3048)
							(mid 0.275042 0.275042)
							(end 0.3048 0.2032)
						)
					)
					(width 0)
					(fill yes)
				)
			)
		)
	)
	(footprint ""
		(layer "F.Cu")
		(at 172.466 -265.684 -90)
		(property "Reference" "C99"
			(at 0 0 270)
			(layer "F.SilkS")
			(hide yes)
			(effects
				(font
					(size 1.27 1.27)
				)
			)
		)
		(property "Value" "SC4D7U25V5KX-1-GP"
			(at -0.0762 -6.1214 270)
			(unlocked yes)
			(layer "F.Fab")
			(hide yes)
			(effects
				(font
					(size 1.016 1.016)
					(thickness 0.1524)
				)
			)
		)
		(property "Device Type" "C805H58"
			(at -0.0762 -8.1534 270)
			(unlocked yes)
			(layer "F.Fab")
			(hide yes)
			(effects
				(font
					(size 1.016 1.016)
					(thickness 0.1524)
				)
			)
		)
		(duplicate_pad_numbers_are_jumpers no)
		(fp_line
			(start 0.635 0)
			(end -0.635 0)
			(stroke
				(width 0.508)
				(type default)
			)
			(layer "F.SilkS")
		)
		(fp_rect
			(start -0.9652 1.778)
			(end 0.9652 -1.778)
			(stroke
				(width 0)
				(type default)
			)
			(fill no)
			(layer "F.CrtYd")
		)
		(fp_poly
			(pts
				(xy -0.9652 -1.778) (xy 0.9652 -1.778) (xy 0.9652 1.778) (xy -0.9652 1.778)
			)
			(stroke
				(width 0)
				(type default)
			)
			(fill no)
			(layer "F.Fab")
		)
		(pad "1" smd rect
			(at 0 -0.9652 270)
			(size 1.397 1.143)
			(layers "F.Cu" "F.Mask" "F.Paste")
			(net "P12V_HDD5")
		)
		(pad "2" smd rect
			(at 0 0.9652 270)
			(size 1.397 1.143)
			(layers "F.Cu" "F.Mask" "F.Paste")
			(net "GND")
		)
	)
	(footprint ""
		(layer "F.Cu")
		(at 151.33447 -217.642186 -90)
		(property "Reference" "R210"
			(at 0 0 270)
			(layer "F.SilkS")
			(hide yes)
			(effects
				(font
					(size 1.27 1.27)
				)
			)
		)
		(property "Value" "4K7R2F-GP"
			(at 0.064008 -3.993896 270)
			(unlocked yes)
			(layer "F.Fab")
			(hide yes)
			(effects
				(font
					(size 1.016 1.016)
					(thickness 0.1524)
				)
			)
		)
		(property "Device Type" "R402H16"
			(at 0.064008 -5.517896 270)
			(unlocked yes)
			(layer "F.Fab")
			(hide yes)
			(effects
				(font
					(size 1.016 1.016)
					(thickness 0.1524)
				)
			)
		)
		(duplicate_pad_numbers_are_jumpers no)
		(fp_line
			(start -0.508 -0.9398)
			(end -0.508 0.9398)
			(stroke
				(width 0.1524)
				(type default)
			)
			(layer "F.SilkS")
		)
		(fp_line
			(start 0.508 -0.9398)
			(end -0.508 -0.9398)
			(stroke
				(width 0.1524)
				(type default)
			)
			(layer "F.SilkS")
		)
		(fp_rect
			(start -0.508 0.9398)
			(end 0.508 -0.9398)
			(stroke
				(width 0)
				(type default)
			)
			(fill no)
			(layer "F.CrtYd")
		)
		(fp_rect
			(start -0.508 0.9398)
			(end 0.508 -0.9398)
			(stroke
				(width 0)
				(type default)
			)
			(fill no)
			(layer "F.Fab")
		)
		(pad "1" smd custom
			(at 0 -0.4445 270)
			(size 0.1397 0.1397)
			(layers "F.Cu" "F.Mask" "F.Paste")
			(net "DRIVE_B_4_FLT_LED")
			(options
				(clearance outline)
				(anchor circle)
			)
			(primitives
				(gr_poly
					(pts
						(arc
							(start -0.1778 -0.2794)
							(mid -0.249642 -0.249642)
							(end -0.2794 -0.1778)
						)
						(arc
							(start -0.2794 0.1778)
							(mid -0.249642 0.249642)
							(end -0.1778 0.2794)
						)
						(arc
							(start 0.1778 0.2794)
							(mid 0.249642 0.249642)
							(end 0.2794 0.1778)
						)
						(arc
							(start 0.2794 -0.1778)
							(mid 0.249642 -0.249642)
							(end 0.1778 -0.2794)
						)
					)
					(width 0)
					(fill yes)
				)
			)
		)
		(pad "2" smd custom
			(at 0 0.4445 270)
			(size 0.1397 0.1397)
			(layers "F.Cu" "F.Mask" "F.Paste")
			(net "GND")
			(options
				(clearance outline)
				(anchor circle)
			)
			(primitives
				(gr_poly
					(pts
						(arc
							(start -0.1778 -0.2794)
							(mid -0.249642 -0.249642)
							(end -0.2794 -0.1778)
						)
						(arc
							(start -0.2794 0.1778)
							(mid -0.249642 0.249642)
							(end -0.1778 0.2794)
						)
						(arc
							(start 0.1778 0.2794)
							(mid 0.249642 0.249642)
							(end 0.2794 0.1778)
						)
						(arc
							(start 0.2794 -0.1778)
							(mid 0.249642 -0.249642)
							(end 0.1778 -0.2794)
						)
					)
					(width 0)
					(fill yes)
				)
			)
		)
	)
	(footprint ""
		(layer "F.Cu")
		(at 14.859 -131.572 90)
		(property "Reference" "R360"
			(at 0 0 90)
			(layer "F.SilkS")
			(hide yes)
			(effects
				(font
					(size 1.27 1.27)
				)
			)
		)
		(property "Value" "4K7R2J-2-GP"
			(at 0.064008 -3.993896 90)
			(unlocked yes)
			(layer "F.Fab")
			(hide yes)
			(effects
				(font
					(size 1.016 1.016)
					(thickness 0.1524)
				)
			)
		)
		(property "Device Type" "R402H16"
			(at 0.064008 -5.517896 90)
			(unlocked yes)
			(layer "F.Fab")
			(hide yes)
			(effects
				(font
					(size 1.016 1.016)
					(thickness 0.1524)
				)
			)
		)
		(duplicate_pad_numbers_are_jumpers no)
		(fp_line
			(start 0.508 -0.9398)
			(end -0.508 -0.9398)
			(stroke
				(width 0.1524)
				(type default)
			)
			(layer "F.SilkS")
		)
		(fp_line
			(start -0.508 -0.9398)
			(end -0.508 0.9398)
			(stroke
				(width 0.1524)
				(type default)
			)
			(layer "F.SilkS")
		)
		(fp_rect
			(start -0.508 0.9398)
			(end 0.508 -0.9398)
			(stroke
				(width 0)
				(type default)
			)
			(fill no)
			(layer "F.CrtYd")
		)
		(fp_rect
			(start -0.508 0.9398)
			(end 0.508 -0.9398)
			(stroke
				(width 0)
				(type default)
			)
			(fill no)
			(layer "F.Fab")
		)
		(pad "1" smd custom
			(at 0 -0.4445 90)
			(size 0.1397 0.1397)
			(layers "F.Cu" "F.Mask" "F.Paste")
			(net "P12V_B")
			(options
				(clearance outline)
				(anchor circle)
			)
			(primitives
				(gr_poly
					(pts
						(arc
							(start -0.1778 -0.2794)
							(mid -0.249642 -0.249642)
							(end -0.2794 -0.1778)
						)
						(arc
							(start -0.2794 0.1778)
							(mid -0.249642 0.249642)
							(end -0.1778 0.2794)
						)
						(arc
							(start 0.1778 0.2794)
							(mid 0.249642 0.249642)
							(end 0.2794 0.1778)
						)
						(arc
							(start 0.2794 -0.1778)
							(mid 0.249642 -0.249642)
							(end 0.1778 -0.2794)
						)
					)
					(width 0)
					(fill yes)
				)
			)
		)
		(pad "2" smd custom
			(at 0 0.4445 90)
			(size 0.1397 0.1397)
			(layers "F.Cu" "F.Mask" "F.Paste")
			(net "SW_HDD_R12")
			(options
				(clearance outline)
				(anchor circle)
			)
			(primitives
				(gr_poly
					(pts
						(arc
							(start -0.1778 -0.2794)
							(mid -0.249642 -0.249642)
							(end -0.2794 -0.1778)
						)
						(arc
							(start -0.2794 0.1778)
							(mid -0.249642 0.249642)
							(end -0.1778 0.2794)
						)
						(arc
							(start 0.1778 0.2794)
							(mid 0.249642 0.249642)
							(end 0.2794 0.1778)
						)
						(arc
							(start 0.2794 -0.1778)
							(mid 0.249642 -0.249642)
							(end 0.1778 -0.2794)
						)
					)
					(width 0)
					(fill yes)
				)
			)
		)
	)
	(footprint ""
		(layer "F.Cu")
		(at 87.376 -160.401 180)
		(property "Reference" "C219"
			(at 0 0 180)
			(layer "F.SilkS")
			(hide yes)
			(effects
				(font
					(size 1.27 1.27)
				)
			)
		)
		(property "Value" "SC1U25V3KX-GP"
			(at 0 -2.8194 180)
			(unlocked yes)
			(layer "F.Fab")
			(hide yes)
			(effects
				(font
					(size 1.016 1.016)
					(thickness 0.1524)
				)
			)
		)
		(property "Device Type" "C603H36"
			(at 0 -4.3434 180)
			(unlocked yes)
			(layer "F.Fab")
			(hide yes)
			(effects
				(font
					(size 1.016 1.016)
					(thickness 0.1524)
				)
			)
		)
		(duplicate_pad_numbers_are_jumpers no)
		(fp_line
			(start 0.508 0)
			(end -0.508 0)
			(stroke
				(width 0.2032)
				(type default)
			)
			(layer "F.SilkS")
		)
		(fp_rect
			(start -0.5842 1.3335)
			(end 0.5842 -1.3335)
			(stroke
				(width 0)
				(type default)
			)
			(fill no)
			(layer "F.CrtYd")
		)
		(fp_rect
			(start -0.5842 1.3335)
			(end 0.5842 -1.3335)
			(stroke
				(width 0)
				(type default)
			)
			(fill no)
			(layer "F.Fab")
		)
		(pad "1" smd custom
			(at 0 -0.762 180)
			(size 0.2159 0.2159)
			(layers "F.Cu" "F.Mask" "F.Paste")
			(net "P12V_HDD14")
			(options
				(clearance outline)
				(anchor circle)
			)
			(primitives
				(gr_poly
					(pts
						(arc
							(start -0.3302 -0.4318)
							(mid -0.402042 -0.402042)
							(end -0.4318 -0.3302)
						)
						(arc
							(start -0.4318 0.3302)
							(mid -0.402042 0.402042)
							(end -0.3302 0.4318)
						)
						(arc
							(start 0.3302 0.4318)
							(mid 0.402042 0.402042)
							(end 0.4318 0.3302)
						)
						(arc
							(start 0.4318 -0.3302)
							(mid 0.402042 -0.402042)
							(end 0.3302 -0.4318)
						)
					)
					(width 0)
					(fill yes)
				)
			)
		)
		(pad "2" smd custom
			(at 0 0.762 180)
			(size 0.2159 0.2159)
			(layers "F.Cu" "F.Mask" "F.Paste")
			(net "GND")
			(options
				(clearance outline)
				(anchor circle)
			)
			(primitives
				(gr_poly
					(pts
						(arc
							(start -0.3302 -0.4318)
							(mid -0.402042 -0.402042)
							(end -0.4318 -0.3302)
						)
						(arc
							(start -0.4318 0.3302)
							(mid -0.402042 0.402042)
							(end -0.3302 0.4318)
						)
						(arc
							(start 0.3302 0.4318)
							(mid 0.402042 0.402042)
							(end 0.4318 0.3302)
						)
						(arc
							(start 0.4318 -0.3302)
							(mid 0.402042 -0.402042)
							(end 0.3302 -0.4318)
						)
					)
					(width 0)
					(fill yes)
				)
			)
		)
	)
	(footprint ""
		(layer "F.Cu")
		(at 177.6984 -9.9314)
		(property "Reference" "R752"
			(at 0 0 0)
			(layer "F.SilkS")
			(hide yes)
			(effects
				(font
					(size 1.27 1.27)
				)
			)
		)
		(property "Value" "300KR2F-GP"
			(at 0.064008 -3.993896 0)
			(unlocked yes)
			(layer "F.Fab")
			(hide yes)
			(effects
				(font
					(size 1.016 1.016)
					(thickness 0.1524)
				)
			)
		)
		(property "Device Type" "R402H16"
			(at 0.064008 -5.517896 0)
			(unlocked yes)
			(layer "F.Fab")
			(hide yes)
			(effects
				(font
					(size 1.016 1.016)
					(thickness 0.1524)
				)
			)
		)
		(duplicate_pad_numbers_are_jumpers no)
		(fp_line
			(start -0.508 -0.9398)
			(end -0.508 0.9398)
			(stroke
				(width 0.1524)
				(type default)
			)
			(layer "F.SilkS")
		)
		(fp_line
			(start 0.508 -0.9398)
			(end -0.508 -0.9398)
			(stroke
				(width 0.1524)
				(type default)
			)
			(layer "F.SilkS")
		)
		(fp_rect
			(start -0.508 0.9398)
			(end 0.508 -0.9398)
			(stroke
				(width 0)
				(type default)
			)
			(fill no)
			(layer "F.CrtYd")
		)
		(fp_rect
			(start -0.508 0.9398)
			(end 0.508 -0.9398)
			(stroke
				(width 0)
				(type default)
			)
			(fill no)
			(layer "F.Fab")
		)
		(pad "1" smd custom
			(at 0 -0.4445)
			(size 0.1397 0.1397)
			(layers "F.Cu" "F.Mask" "F.Paste")
			(net "SW_HDD_N29")
			(options
				(clearance outline)
				(anchor circle)
			)
			(primitives
				(gr_poly
					(pts
						(arc
							(start -0.1778 -0.2794)
							(mid -0.249642 -0.249642)
							(end -0.2794 -0.1778)
						)
						(arc
							(start -0.2794 0.1778)
							(mid -0.249642 0.249642)
							(end -0.1778 0.2794)
						)
						(arc
							(start 0.1778 0.2794)
							(mid 0.249642 0.249642)
							(end 0.2794 0.1778)
						)
						(arc
							(start 0.2794 -0.1778)
							(mid 0.249642 -0.249642)
							(end 0.1778 -0.2794)
						)
					)
					(width 0)
					(fill yes)
				)
			)
		)
		(pad "2" smd custom
			(at 0 0.4445)
			(size 0.1397 0.1397)
			(layers "F.Cu" "F.Mask" "F.Paste")
			(net "P12V_B")
			(options
				(clearance outline)
				(anchor circle)
			)
			(primitives
				(gr_poly
					(pts
						(arc
							(start -0.1778 -0.2794)
							(mid -0.249642 -0.249642)
							(end -0.2794 -0.1778)
						)
						(arc
							(start -0.2794 0.1778)
							(mid -0.249642 0.249642)
							(end -0.1778 0.2794)
						)
						(arc
							(start 0.1778 0.2794)
							(mid 0.249642 0.249642)
							(end 0.2794 0.1778)
						)
						(arc
							(start 0.2794 -0.1778)
							(mid 0.249642 -0.249642)
							(end 0.1778 -0.2794)
						)
					)
					(width 0)
					(fill yes)
				)
			)
		)
	)
	(footprint ""
		(layer "F.Cu")
		(at 127 -372.618)
		(property "Reference" "R937"
			(at 0 0 0)
			(layer "F.SilkS")
			(hide yes)
			(effects
				(font
					(size 1.27 1.27)
				)
			)
		)
		(property "Value" "10KR2F-2-GP"
			(at 0.064008 -3.993896 0)
			(unlocked yes)
			(layer "F.Fab")
			(hide yes)
			(effects
				(font
					(size 1.016 1.016)
					(thickness 0.1524)
				)
			)
		)
		(property "Device Type" "R402H16"
			(at 0.064008 -5.517896 0)
			(unlocked yes)
			(layer "F.Fab")
			(hide yes)
			(effects
				(font
					(size 1.016 1.016)
					(thickness 0.1524)
				)
			)
		)
		(duplicate_pad_numbers_are_jumpers no)
		(fp_line
			(start -0.508 -0.9398)
			(end -0.508 0.9398)
			(stroke
				(width 0.1524)
				(type default)
			)
			(layer "F.SilkS")
		)
		(fp_line
			(start 0.508 -0.9398)
			(end -0.508 -0.9398)
			(stroke
				(width 0.1524)
				(type default)
			)
			(layer "F.SilkS")
		)
		(fp_rect
			(start -0.508 0.9398)
			(end 0.508 -0.9398)
			(stroke
				(width 0)
				(type default)
			)
			(fill no)
			(layer "F.CrtYd")
		)
		(fp_rect
			(start -0.508 0.9398)
			(end 0.508 -0.9398)
			(stroke
				(width 0)
				(type default)
			)
			(fill no)
			(layer "F.Fab")
		)
		(pad "1" smd custom
			(at 0 -0.4445)
			(size 0.1397 0.1397)
			(layers "F.Cu" "F.Mask" "F.Paste")
			(net "GND")
			(options
				(clearance outline)
				(anchor circle)
			)
			(primitives
				(gr_poly
					(pts
						(arc
							(start -0.1778 -0.2794)
							(mid -0.249642 -0.249642)
							(end -0.2794 -0.1778)
						)
						(arc
							(start -0.2794 0.1778)
							(mid -0.249642 0.249642)
							(end -0.1778 0.2794)
						)
						(arc
							(start 0.1778 0.2794)
							(mid 0.249642 0.249642)
							(end 0.2794 0.1778)
						)
						(arc
							(start 0.2794 -0.1778)
							(mid 0.249642 -0.249642)
							(end 0.1778 -0.2794)
						)
					)
					(width 0)
					(fill yes)
				)
			)
		)
		(pad "2" smd custom
			(at 0 0.4445)
			(size 0.1397 0.1397)
			(layers "F.Cu" "F.Mask" "F.Paste")
			(net "FANTACH_R1")
			(options
				(clearance outline)
				(anchor circle)
			)
			(primitives
				(gr_poly
					(pts
						(arc
							(start -0.1778 -0.2794)
							(mid -0.249642 -0.249642)
							(end -0.2794 -0.1778)
						)
						(arc
							(start -0.2794 0.1778)
							(mid -0.249642 0.249642)
							(end -0.1778 0.2794)
						)
						(arc
							(start 0.1778 0.2794)
							(mid 0.249642 0.249642)
							(end 0.2794 0.1778)
						)
						(arc
							(start 0.2794 -0.1778)
							(mid 0.249642 -0.249642)
							(end 0.1778 -0.2794)
						)
					)
					(width 0)
					(fill yes)
				)
			)
		)
	)
	(footprint ""
		(layer "F.Cu")
		(at 177.8 -262.001 -90)
		(property "Reference" "C96"
			(at 0 0 270)
			(layer "F.SilkS")
			(hide yes)
			(effects
				(font
					(size 1.27 1.27)
				)
			)
		)
		(property "Value" "SC10U16V6KX-2GP"
			(at -0.0762 -5.1308 270)
			(unlocked yes)
			(layer "F.Fab")
			(hide yes)
			(effects
				(font
					(size 1.016 1.016)
					(thickness 0.1524)
				)
			)
		)
		(property "Device Type" "C1206H71"
			(at -0.127 -6.6548 270)
			(unlocked yes)
			(layer "F.Fab")
			(hide yes)
			(effects
				(font
					(size 1.016 1.016)
					(thickness 0.1524)
				)
			)
		)
		(duplicate_pad_numbers_are_jumpers no)
		(fp_line
			(start -1.016 2.2352)
			(end -1.016 0.8382)
			(stroke
				(width 0.1524)
				(type default)
			)
			(layer "F.SilkS")
		)
		(fp_line
			(start 1.016 2.2352)
			(end -1.016 2.2352)
			(stroke
				(width 0.1524)
				(type default)
			)
			(layer "F.SilkS")
		)
		(fp_line
			(start 1.016 0.8382)
			(end 1.016 2.2352)
			(stroke
				(width 0.1524)
				(type default)
			)
			(layer "F.SilkS")
		)
		(fp_line
			(start -1.016 -0.8382)
			(end -1.016 -2.2352)
			(stroke
				(width 0.1524)
				(type default)
			)
			(layer "F.SilkS")
		)
		(fp_line
			(start -1.016 -2.2352)
			(end 1.016 -2.2352)
			(stroke
				(width 0.1524)
				(type default)
			)
			(layer "F.SilkS")
		)
		(fp_line
			(start 1.016 -2.2352)
			(end 1.016 -0.8382)
			(stroke
				(width 0.1524)
				(type default)
			)
			(layer "F.SilkS")
		)
		(fp_rect
			(start -1.0922 2.3114)
			(end 1.0922 -2.3114)
			(stroke
				(width 0)
				(type default)
			)
			(fill no)
			(layer "F.CrtYd")
		)
		(fp_poly
			(pts
				(xy 1.0922 -2.3114) (xy 1.0922 2.3114) (xy -1.0922 2.3114) (xy -1.0922 -2.3114)
			)
			(stroke
				(width 0)
				(type default)
			)
			(fill no)
			(layer "F.Fab")
		)
		(pad "1" smd rect
			(at 0 -1.397 270)
			(size 1.651 1.27)
			(layers "F.Cu" "F.Mask" "F.Paste")
			(net "P5V_HDD5")
		)
		(pad "2" smd rect
			(at 0 1.397 270)
			(size 1.651 1.27)
			(layers "F.Cu" "F.Mask" "F.Paste")
			(net "GND")
		)
	)
	(footprint ""
		(layer "F.Cu")
		(at 190.8556 -263.144 -90)
		(property "Reference" "R239"
			(at 0 0 270)
			(layer "F.SilkS")
			(hide yes)
			(effects
				(font
					(size 1.27 1.27)
				)
			)
		)
		(property "Value" "10KR2F-2-GP"
			(at 0.064008 -3.993896 270)
			(unlocked yes)
			(layer "F.Fab")
			(hide yes)
			(effects
				(font
					(size 1.016 1.016)
					(thickness 0.1524)
				)
			)
		)
		(property "Device Type" "R402H16"
			(at 0.064008 -5.517896 270)
			(unlocked yes)
			(layer "F.Fab")
			(hide yes)
			(effects
				(font
					(size 1.016 1.016)
					(thickness 0.1524)
				)
			)
		)
		(duplicate_pad_numbers_are_jumpers no)
		(fp_line
			(start -0.508 -0.9398)
			(end -0.508 0.9398)
			(stroke
				(width 0.1524)
				(type default)
			)
			(layer "F.SilkS")
		)
		(fp_line
			(start 0.508 -0.9398)
			(end -0.508 -0.9398)
			(stroke
				(width 0.1524)
				(type default)
			)
			(layer "F.SilkS")
		)
		(fp_rect
			(start -0.508 0.9398)
			(end 0.508 -0.9398)
			(stroke
				(width 0)
				(type default)
			)
			(fill no)
			(layer "F.CrtYd")
		)
		(fp_rect
			(start -0.508 0.9398)
			(end 0.508 -0.9398)
			(stroke
				(width 0)
				(type default)
			)
			(fill no)
			(layer "F.Fab")
		)
		(pad "1" smd custom
			(at 0 -0.4445 270)
			(size 0.1397 0.1397)
			(layers "F.Cu" "F.Mask" "F.Paste")
			(net "P3V3_STBY_B")
			(options
				(clearance outline)
				(anchor circle)
			)
			(primitives
				(gr_poly
					(pts
						(arc
							(start -0.1778 -0.2794)
							(mid -0.249642 -0.249642)
							(end -0.2794 -0.1778)
						)
						(arc
							(start -0.2794 0.1778)
							(mid -0.249642 0.249642)
							(end -0.1778 0.2794)
						)
						(arc
							(start 0.1778 0.2794)
							(mid 0.249642 0.249642)
							(end 0.2794 0.1778)
						)
						(arc
							(start 0.2794 -0.1778)
							(mid 0.249642 -0.249642)
							(end 0.1778 -0.2794)
						)
					)
					(width 0)
					(fill yes)
				)
			)
		)
		(pad "2" smd custom
			(at 0 0.4445 270)
			(size 0.1397 0.1397)
			(layers "F.Cu" "F.Mask" "F.Paste")
			(net "HDD_PRSNT_5")
			(options
				(clearance outline)
				(anchor circle)
			)
			(primitives
				(gr_poly
					(pts
						(arc
							(start -0.1778 -0.2794)
							(mid -0.249642 -0.249642)
							(end -0.2794 -0.1778)
						)
						(arc
							(start -0.2794 0.1778)
							(mid -0.249642 0.249642)
							(end -0.1778 0.2794)
						)
						(arc
							(start 0.1778 0.2794)
							(mid 0.249642 0.249642)
							(end 0.2794 0.1778)
						)
						(arc
							(start 0.2794 -0.1778)
							(mid 0.249642 -0.249642)
							(end 0.1778 -0.2794)
						)
					)
					(width 0)
					(fill yes)
				)
			)
		)
	)
	(footprint ""
		(layer "F.Cu")
		(at 207.3402 -198.374 90)
		(property "Reference" "R31"
			(at 0 0 90)
			(layer "F.SilkS")
			(hide yes)
			(effects
				(font
					(size 1.27 1.27)
				)
			)
		)
		(property "Value" "4K7R2F-GP"
			(at 0.064008 -3.993896 90)
			(unlocked yes)
			(layer "F.Fab")
			(hide yes)
			(effects
				(font
					(size 1.016 1.016)
					(thickness 0.1524)
				)
			)
		)
		(property "Device Type" "R402H16"
			(at 0.064008 -5.517896 90)
			(unlocked yes)
			(layer "F.Fab")
			(hide yes)
			(effects
				(font
					(size 1.016 1.016)
					(thickness 0.1524)
				)
			)
		)
		(duplicate_pad_numbers_are_jumpers no)
		(fp_line
			(start 0.508 -0.9398)
			(end -0.508 -0.9398)
			(stroke
				(width 0.1524)
				(type default)
			)
			(layer "F.SilkS")
		)
		(fp_line
			(start -0.508 -0.9398)
			(end -0.508 0.9398)
			(stroke
				(width 0.1524)
				(type default)
			)
			(layer "F.SilkS")
		)
		(fp_rect
			(start -0.508 0.9398)
			(end 0.508 -0.9398)
			(stroke
				(width 0)
				(type default)
			)
			(fill no)
			(layer "F.CrtYd")
		)
		(fp_rect
			(start -0.508 0.9398)
			(end 0.508 -0.9398)
			(stroke
				(width 0)
				(type default)
			)
			(fill no)
			(layer "F.Fab")
		)
		(pad "1" smd custom
			(at 0 -0.4445 90)
			(size 0.1397 0.1397)
			(layers "F.Cu" "F.Mask" "F.Paste")
			(net "P3V3_STBY_B")
			(options
				(clearance outline)
				(anchor circle)
			)
			(primitives
				(gr_poly
					(pts
						(arc
							(start -0.1778 -0.2794)
							(mid -0.249642 -0.249642)
							(end -0.2794 -0.1778)
						)
						(arc
							(start -0.2794 0.1778)
							(mid -0.249642 0.249642)
							(end -0.1778 0.2794)
						)
						(arc
							(start 0.1778 0.2794)
							(mid 0.249642 0.249642)
							(end 0.2794 0.1778)
						)
						(arc
							(start 0.2794 -0.1778)
							(mid 0.249642 -0.249642)
							(end 0.1778 -0.2794)
						)
					)
					(width 0)
					(fill yes)
				)
			)
		)
		(pad "2" smd custom
			(at 0 0.4445 90)
			(size 0.1397 0.1397)
			(layers "F.Cu" "F.Mask" "F.Paste")
			(net "IO_EXP2_HDD_FAULT_A1")
			(options
				(clearance outline)
				(anchor circle)
			)
			(primitives
				(gr_poly
					(pts
						(arc
							(start -0.1778 -0.2794)
							(mid -0.249642 -0.249642)
							(end -0.2794 -0.1778)
						)
						(arc
							(start -0.2794 0.1778)
							(mid -0.249642 0.249642)
							(end -0.1778 0.2794)
						)
						(arc
							(start 0.1778 0.2794)
							(mid 0.249642 0.249642)
							(end 0.2794 0.1778)
						)
						(arc
							(start 0.2794 -0.1778)
							(mid 0.249642 -0.249642)
							(end 0.1778 -0.2794)
						)
					)
					(width 0)
					(fill yes)
				)
			)
		)
	)
	(footprint ""
		(layer "F.Cu")
		(at 338.709 -143.891 90)
		(property "Reference" "C273"
			(at 0 0 90)
			(layer "F.SilkS")
			(hide yes)
			(effects
				(font
					(size 1.27 1.27)
				)
			)
		)
		(property "Value" "SCD033U25V2KX-GP"
			(at 1.1811 -2.7051 90)
			(unlocked yes)
			(layer "F.Fab")
			(hide yes)
			(effects
				(font
					(size 1.016 1.016)
					(thickness 0.1524)
				)
			)
		)
		(property "Device Type" "C402H22"
			(at 1.1811 -4.2291 90)
			(unlocked yes)
			(layer "F.Fab")
			(hide yes)
			(effects
				(font
					(size 1.016 1.016)
					(thickness 0.1524)
				)
			)
		)
		(duplicate_pad_numbers_are_jumpers no)
		(fp_rect
			(start -0.4318 0.9525)
			(end 0.4318 -0.9525)
			(stroke
				(width 0)
				(type default)
			)
			(fill no)
			(layer "F.CrtYd")
		)
		(fp_rect
			(start -0.4318 0.9525)
			(end 0.4318 -0.9525)
			(stroke
				(width 0)
				(type default)
			)
			(fill no)
			(layer "F.Fab")
		)
		(pad "1" smd custom
			(at 0 -0.4445 90)
			(size 0.1524 0.1524)
			(layers "F.Cu" "F.Mask" "F.Paste")
			(net "P12V_B")
			(options
				(clearance outline)
				(anchor circle)
			)
			(primitives
				(gr_poly
					(pts
						(arc
							(start 0.3048 -0.2032)
							(mid 0.275042 -0.275042)
							(end 0.2032 -0.3048)
						)
						(arc
							(start -0.2032 -0.3048)
							(mid -0.275042 -0.275042)
							(end -0.3048 -0.2032)
						)
						(arc
							(start -0.3048 0.2032)
							(mid -0.275042 0.275042)
							(end -0.2032 0.3048)
						)
						(arc
							(start 0.2032 0.3048)
							(mid 0.275042 0.275042)
							(end 0.3048 0.2032)
						)
					)
					(width 0)
					(fill yes)
				)
			)
		)
		(pad "2" smd custom
			(at 0 0.4445 90)
			(size 0.1524 0.1524)
			(layers "F.Cu" "F.Mask" "F.Paste")
			(net "SW_HDD_N18")
			(options
				(clearance outline)
				(anchor circle)
			)
			(primitives
				(gr_poly
					(pts
						(arc
							(start 0.3048 -0.2032)
							(mid 0.275042 -0.275042)
							(end 0.2032 -0.3048)
						)
						(arc
							(start -0.2032 -0.3048)
							(mid -0.275042 -0.275042)
							(end -0.3048 -0.2032)
						)
						(arc
							(start -0.3048 0.2032)
							(mid -0.275042 0.275042)
							(end -0.2032 0.3048)
						)
						(arc
							(start 0.2032 0.3048)
							(mid 0.275042 0.275042)
							(end 0.3048 0.2032)
						)
					)
					(width 0)
					(fill yes)
				)
			)
		)
	)
	(footprint ""
		(layer "F.Cu")
		(at 357.100124 -28.910026 -90)
		(property "Reference" "HDDSAS31"
			(at 0 0 270)
			(layer "F.SilkS")
			(hide yes)
			(effects
				(font
					(size 1.27 1.27)
				)
			)
		)
		(property "Value" "SKT-SAS15P-14P-45-GP"
			(at -20.7645 -8.9789 270)
			(unlocked yes)
			(layer "F.Fab")
			(hide yes)
			(effects
				(font
					(size 1.016 1.016)
					(thickness 0.1524)
				)
			)
		)
		(property "Device Type" "10120818-001C-TRLF"
			(at -20.7645 -10.5029 270)
			(unlocked yes)
			(layer "F.Fab")
			(hide yes)
			(effects
				(font
					(size 1.016 1.016)
					(thickness 0.1524)
				)
			)
		)
		(duplicate_pad_numbers_are_jumpers no)
		(fp_line
			(start 1.651 4.2926)
			(end 1.651 3.0099)
			(stroke
				(width 0.1524)
				(type default)
			)
			(layer "F.SilkS")
		)
		(fp_line
			(start 8.509 4.2926)
			(end 1.651 4.2926)
			(stroke
				(width 0.1524)
				(type default)
			)
			(layer "F.SilkS")
		)
		(fp_line
			(start -23.4188 3.0099)
			(end -23.4188 -3.2512)
			(stroke
				(width 0.1524)
				(type default)
			)
			(layer "F.SilkS")
		)
		(fp_line
			(start 1.651 3.0099)
			(end -23.4188 3.0099)
			(stroke
				(width 0.1524)
				(type default)
			)
			(layer "F.SilkS")
		)
		(fp_line
			(start 8.509 3.0099)
			(end 8.509 4.2926)
			(stroke
				(width 0.1524)
				(type default)
			)
			(layer "F.SilkS")
		)
		(fp_line
			(start 23.4188 3.0099)
			(end 8.509 3.0099)
			(stroke
				(width 0.1524)
				(type default)
			)
			(layer "F.SilkS")
		)
		(fp_line
			(start -23.4188 -3.2512)
			(end 23.4188 -3.2512)
			(stroke
				(width 0.1524)
				(type default)
			)
			(layer "F.SilkS")
		)
		(fp_line
			(start 23.4188 -3.2512)
			(end 23.4188 3.0099)
			(stroke
				(width 0.1524)
				(type default)
			)
			(layer "F.SilkS")
		)
		(fp_line
			(start 15.5067 -3.3401)
			(end 16.2687 -3.3401)
			(stroke
				(width 0.3302)
				(type default)
			)
			(layer "F.SilkS")
		)
		(fp_poly
			(pts
				(xy 15.868904 -3.230372) (xy 16.503904 -3.865372) (xy 15.233904 -3.865372)
			)
			(stroke
				(width 0)
				(type default)
			)
			(fill yes)
			(layer "F.SilkS")
		)
		(fp_poly
			(pts
				(xy -22.8727 -2.7559) (xy 22.8727 -2.7559) (xy 22.8727 2.7559) (xy 8.255 2.7559) (xy 8.255 3.5179)
				(xy 1.905 3.5179) (xy 1.905 2.7559) (xy -22.8727 2.7559)
			)
			(stroke
				(width 0)
				(type default)
			)
			(fill no)
			(layer "F.CrtYd")
		)
		(fp_poly
			(pts
				(xy 1.397 4.5466) (xy 1.397 3.2639) (xy -23.6728 3.2639) (xy -23.6728 -3.5052) (xy 23.6728 -3.5052)
				(xy 23.6728 -0.00635) (xy 22.8727 -0.00635) (xy 22.8727 -2.7559) (xy -22.8727 -2.7559) (xy -22.8727 2.7559)
				(xy 1.905 2.7559) (xy 1.905 3.5179) (xy 8.255 3.5179) (xy 8.255 2.7559) (xy 22.8727 2.7559) (xy 22.8727 0.00635)
				(xy 23.6728 0.00635) (xy 23.6728 3.2639) (xy 8.763 3.2639) (xy 8.763 4.5466)
			)
			(stroke
				(width 0)
				(type default)
			)
			(fill no)
			(layer "F.CrtYd")
		)
		(fp_poly
			(pts
				(xy 1.397 4.5466) (xy 1.397 3.2639) (xy -23.6728 3.2639) (xy -23.6728 -3.5052) (xy 23.6728 -3.5052)
				(xy 23.6728 3.2639) (xy 8.763 3.2639) (xy 8.763 4.5466)
			)
			(stroke
				(width 0)
				(type default)
			)
			(fill no)
			(layer "F.Fab")
		)
		(pad "" np_thru_hole circle
			(at -18.874994 0 270)
			(size 0.254 0.254)
			(drill 1.3462)
			(layers "*.Cu" "*.Mask")
			(clearance 0.9017)
			(thermal_gap 0.9017)
		)
		(pad "" np_thru_hole circle
			(at 18.874994 0 270)
			(size 0.254 0.254)
			(drill 0.9398)
			(layers "*.Cu" "*.Mask")
			(clearance 0.6985)
			(thermal_gap 0.6985)
		)
		(pad "G1" smd rect
			(at 21.874988 0 270)
			(size 2.5908 2.5908)
			(layers "F.Cu" "F.Mask" "F.Paste")
			(net "GND")
		)
		(pad "G2" smd rect
			(at -21.874988 0 270)
			(size 2.5908 2.5908)
			(layers "F.Cu" "F.Mask" "F.Paste")
			(net "GND")
		)
		(pad "P1" smd rect
			(at 1.905 -1.82499 270)
			(size 0.6096 2.3622)
			(layers "F.Cu" "F.Mask" "F.Paste")
			(net "Net_1639")
		)
		(pad "P2" smd rect
			(at 0.635 -1.82499 270)
			(size 0.6096 2.3622)
			(layers "F.Cu" "F.Mask" "F.Paste")
			(net "Net_1640")
		)
		(pad "P3" smd rect
			(at -0.635 -1.82499 270)
			(size 0.6096 2.3622)
			(layers "F.Cu" "F.Mask" "F.Paste")
			(net "Net_1641")
		)
		(pad "P4" smd rect
			(at -1.905 -1.82499 270)
			(size 0.6096 2.3622)
			(layers "F.Cu" "F.Mask" "F.Paste")
			(net "GND")
		)
		(pad "P5" smd rect
			(at -3.175 -1.82499 270)
			(size 0.6096 2.3622)
			(layers "F.Cu" "F.Mask" "F.Paste")
			(net "HDD_PRSNT_31")
		)
		(pad "P6" smd rect
			(at -4.445 -1.82499 270)
			(size 0.6096 2.3622)
			(layers "F.Cu" "F.Mask" "F.Paste")
			(net "GND")
		)
		(pad "P7" smd rect
			(at -5.715 -1.82499 270)
			(size 0.6096 2.3622)
			(layers "F.Cu" "F.Mask" "F.Paste")
			(net "5V_PRE_31")
		)
		(pad "P8" smd rect
			(at -6.985 -1.82499 270)
			(size 0.6096 2.3622)
			(layers "F.Cu" "F.Mask" "F.Paste")
			(net "P5V_HDD31")
		)
		(pad "P9" smd rect
			(at -8.255 -1.82499 270)
			(size 0.6096 2.3622)
			(layers "F.Cu" "F.Mask" "F.Paste")
			(net "P5V_HDD31")
		)
		(pad "P10" smd rect
			(at -9.525 -1.82499 270)
			(size 0.6096 2.3622)
			(layers "F.Cu" "F.Mask" "F.Paste")
			(net "GND")
		)
		(pad "P11" smd rect
			(at -10.795 -1.82499 270)
			(size 0.6096 2.3622)
			(layers "F.Cu" "F.Mask" "F.Paste")
			(net "ACT_HDD_31")
		)
		(pad "P12" smd rect
			(at -12.065 -1.82499 270)
			(size 0.6096 2.3622)
			(layers "F.Cu" "F.Mask" "F.Paste")
			(net "GND")
		)
		(pad "P13" smd rect
			(at -13.335 -1.82499 270)
			(size 0.6096 2.3622)
			(layers "F.Cu" "F.Mask" "F.Paste")
			(net "12V_PRE_31")
		)
		(pad "P14" smd rect
			(at -14.605 -1.82499 270)
			(size 0.6096 2.3622)
			(layers "F.Cu" "F.Mask" "F.Paste")
			(net "P12V_HDD31")
		)
		(pad "P15" smd rect
			(at -15.875 -1.82499 270)
			(size 0.6096 2.3622)
			(layers "F.Cu" "F.Mask" "F.Paste")
			(net "P12V_HDD31")
		)
		(pad "S1" smd rect
			(at 15.875 -1.82499 270)
			(size 0.6096 2.3622)
			(layers "F.Cu" "F.Mask" "F.Paste")
			(net "GND")
		)
		(pad "S2" smd rect
			(at 14.605 -1.82499 270)
			(size 0.6096 2.3622)
			(layers "F.Cu" "F.Mask" "F.Paste")
			(net "SAS_HDD_RX_P31")
		)
		(pad "S3" smd rect
			(at 13.335 -1.82499 270)
			(size 0.6096 2.3622)
			(layers "F.Cu" "F.Mask" "F.Paste")
			(net "SAS_HDD_RX_N31")
		)
		(pad "S4" smd rect
			(at 12.065 -1.82499 270)
			(size 0.6096 2.3622)
			(layers "F.Cu" "F.Mask" "F.Paste")
			(net "GND")
		)
		(pad "S5" smd rect
			(at 10.795 -1.82499 270)
			(size 0.6096 2.3622)
			(layers "F.Cu" "F.Mask" "F.Paste")
			(net "PHY_DRV_B_TO_SCC_B_31_DN")
		)
		(pad "S6" smd rect
			(at 9.525 -1.82499 270)
			(size 0.6096 2.3622)
			(layers "F.Cu" "F.Mask" "F.Paste")
			(net "PHY_DRV_B_TO_SCC_B_31_DP")
		)
		(pad "S7" smd rect
			(at 8.255 -1.82499 270)
			(size 0.6096 2.3622)
			(layers "F.Cu" "F.Mask" "F.Paste")
			(net "GND")
		)
		(pad "S8" smd rect
			(at 7.480046 2.845054 270)
			(size 0.508 2.3622)
			(layers "F.Cu" "F.Mask" "F.Paste")
			(net "GND")
		)
		(pad "S9" smd rect
			(at 6.679946 2.845054 270)
			(size 0.508 2.3622)
			(layers "F.Cu" "F.Mask" "F.Paste")
			(net "Net_456")
		)
		(pad "S10" smd rect
			(at 5.8801 2.845054 270)
			(size 0.508 2.3622)
			(layers "F.Cu" "F.Mask" "F.Paste")
			(net "Net_348")
		)
		(pad "S11" smd rect
			(at 5.08 2.845054 270)
			(size 0.508 2.3622)
			(layers "F.Cu" "F.Mask" "F.Paste")
			(net "GND")
		)
		(pad "S12" smd rect
			(at 4.2799 2.845054 270)
			(size 0.508 2.3622)
			(layers "F.Cu" "F.Mask" "F.Paste")
			(net "Net_384")
		)
		(pad "S13" smd rect
			(at 3.480054 2.845054 270)
			(size 0.508 2.3622)
			(layers "F.Cu" "F.Mask" "F.Paste")
			(net "Net_420")
		)
		(pad "S14" smd rect
			(at 2.679954 2.845054 270)
			(size 0.508 2.3622)
			(layers "F.Cu" "F.Mask" "F.Paste")
			(net "GND")
		)
		(zone
			(layer "F.Cu")
			(hatch none 0.5)
			(connect_pads
				(clearance 0)
			)
			(min_thickness 0.25)
			(keepout
				(tracks not_allowed)
				(vias allowed)
				(pads allowed)
				(copperpour not_allowed)
				(footprints allowed)
			)
			(placement
				(enabled no)
				(sheetname "")
			)
			(fill
				(thermal_gap 0.5)
				(thermal_bridge_width 0.5)
				(island_removal_mode 0)
			)
			(polygon
				(pts
					(xy 360.757724 -45.648626) (xy 353.683824 -45.648626) (xy 353.683824 -52.582826) (xy 354.788724 -52.582826)
					(xy 354.788724 -48.468026) (xy 359.411524 -48.468026) (xy 359.411524 -52.582826) (xy 360.757724 -52.582826)
				)
			)
		)
		(zone
			(layer "F.Cu")
			(hatch none 0.5)
			(connect_pads
				(clearance 0)
			)
			(min_thickness 0.25)
			(keepout
				(tracks allowed)
				(vias not_allowed)
				(pads allowed)
				(copperpour not_allowed)
				(footprints allowed)
			)
			(placement
				(enabled no)
				(sheetname "")
			)
			(fill
				(thermal_gap 0.5)
				(thermal_bridge_width 0.5)
				(island_removal_mode 0)
			)
			(polygon
				(pts
					(xy 360.757724 -45.648626) (xy 353.683824 -45.648626) (xy 353.683824 -52.582826) (xy 354.788724 -52.582826)
					(xy 354.788724 -48.468026) (xy 359.411524 -48.468026) (xy 359.411524 -52.582826) (xy 360.757724 -52.582826)
				)
			)
		)
		(zone
			(layer "F.Cu")
			(hatch none 0.5)
			(connect_pads
				(clearance 0)
			)
			(min_thickness 0.25)
			(keepout
				(tracks allowed)
				(vias not_allowed)
				(pads allowed)
				(copperpour not_allowed)
				(footprints allowed)
			)
			(placement
				(enabled no)
				(sheetname "")
			)
			(fill
				(thermal_gap 0.5)
				(thermal_bridge_width 0.5)
				(island_removal_mode 0)
			)
			(polygon
				(pts
					(xy 360.757724 -12.171426) (xy 353.683824 -12.171426) (xy 353.683824 -5.237226) (xy 354.788724 -5.237226)
					(xy 354.788724 -9.352026) (xy 359.411524 -9.352026) (xy 359.411524 -5.237226) (xy 360.757724 -5.237226)
				)
			)
		)
		(zone
			(layer "F.Cu")
			(hatch none 0.5)
			(connect_pads
				(clearance 0)
			)
			(min_thickness 0.25)
			(keepout
				(tracks not_allowed)
				(vias allowed)
				(pads allowed)
				(copperpour not_allowed)
				(footprints allowed)
			)
			(placement
				(enabled no)
				(sheetname "")
			)
			(fill
				(thermal_gap 0.5)
				(thermal_bridge_width 0.5)
				(island_removal_mode 0)
			)
			(polygon
				(pts
					(xy 360.757724 -12.171426) (xy 353.683824 -12.171426) (xy 353.683824 -5.237226) (xy 354.788724 -5.237226)
					(xy 354.788724 -9.352026) (xy 359.411524 -9.352026) (xy 359.411524 -5.237226) (xy 360.757724 -5.237226)
				)
			)
		)
		(zone
			(layers "F.Cu" "B.Cu" "In1.Cu" "In2.Cu" "In3.Cu" "In4.Cu" "In5.Cu" "In6.Cu")
			(hatch none 0.5)
			(connect_pads
				(clearance 0)
			)
			(min_thickness 0.25)
			(keepout
				(tracks not_allowed)
				(vias allowed)
				(pads allowed)
				(copperpour not_allowed)
				(footprints allowed)
			)
			(placement
				(enabled no)
				(sheetname "")
			)
			(fill
				(thermal_gap 0.5)
				(thermal_bridge_width 0.5)
				(island_removal_mode 0)
			)
			(polygon
				(pts
					(arc
						(start 357.874824 -10.035032)
						(mid 356.325424 -10.035032)
						(end 357.874824 -10.035032)
					)
				)
			)
		)
		(zone
			(layers "F.Cu" "B.Cu" "In1.Cu" "In2.Cu" "In3.Cu" "In4.Cu" "In5.Cu" "In6.Cu")
			(hatch none 0.5)
			(connect_pads
				(clearance 0)
			)
			(min_thickness 0.25)
			(keepout
				(tracks not_allowed)
				(vias allowed)
				(pads allowed)
				(copperpour not_allowed)
				(footprints allowed)
			)
			(placement
				(enabled no)
				(sheetname "")
			)
			(fill
				(thermal_gap 0.5)
				(thermal_bridge_width 0.5)
				(island_removal_mode 0)
			)
			(polygon
				(pts
					(arc
						(start 358.078024 -47.78502)
						(mid 356.122224 -47.78502)
						(end 358.078024 -47.78502)
					)
				)
			)
		)
	)
	(footprint ""
		(layer "F.Cu")
		(at 438.999884 -379.899926 180)
		(property "Reference" "FAN4"
			(at 0 0 180)
			(layer "F.SilkS")
			(hide yes)
			(effects
				(font
					(size 1.27 1.27)
				)
			)
		)
		(property "Value" "MLX-CONN10D-7-GP"
			(at -15.641574 4.697984 180)
			(unlocked yes)
			(layer "F.Fab")
			(hide yes)
			(effects
				(font
					(size 1.016 1.016)
					(thickness 0.1524)
				)
			)
		)
		(property "Device Type" "15-24-6103"
			(at -15.641574 3.173984 180)
			(unlocked yes)
			(layer "F.Fab")
			(hide yes)
			(effects
				(font
					(size 1.016 1.016)
					(thickness 0.1524)
				)
			)
		)
		(duplicate_pad_numbers_are_jumpers no)
		(fp_line
			(start 14.0462 8.1534)
			(end -14.0462 8.1534)
			(stroke
				(width 0.1524)
				(type default)
			)
			(layer "F.SilkS")
		)
		(fp_line
			(start 14.0462 -6.4516)
			(end 14.0462 8.1534)
			(stroke
				(width 0.1524)
				(type default)
			)
			(layer "F.SilkS")
		)
		(fp_line
			(start 9.9314 -6.4516)
			(end 14.0462 -6.4516)
			(stroke
				(width 0.1524)
				(type default)
			)
			(layer "F.SilkS")
		)
		(fp_line
			(start 9.9314 -14.3256)
			(end 9.9314 -6.4516)
			(stroke
				(width 0.1524)
				(type default)
			)
			(layer "F.SilkS")
		)
		(fp_line
			(start -9.9314 -6.4516)
			(end -9.9314 -14.3256)
			(stroke
				(width 0.1524)
				(type default)
			)
			(layer "F.SilkS")
		)
		(fp_line
			(start -9.9314 -14.3256)
			(end 9.9314 -14.3256)
			(stroke
				(width 0.1524)
				(type default)
			)
			(layer "F.SilkS")
		)
		(fp_line
			(start -14.0462 8.1534)
			(end -14.0462 -6.4516)
			(stroke
				(width 0.1524)
				(type default)
			)
			(layer "F.SilkS")
		)
		(fp_line
			(start -14.0462 -6.4516)
			(end -9.9314 -6.4516)
			(stroke
				(width 0.1524)
				(type default)
			)
			(layer "F.SilkS")
		)
		(fp_circle
			(center 8.400034 -7.29996)
			(end 6.761734 -7.29996)
			(stroke
				(width 0.3048)
				(type default)
			)
			(fill no)
			(layer "F.SilkS")
		)
		(fp_circle
			(center 8.400034 -12.800076)
			(end 6.761734 -12.800076)
			(stroke
				(width 0.3048)
				(type default)
			)
			(fill no)
			(layer "F.SilkS")
		)
		(fp_circle
			(center 4.19989 -7.29996)
			(end 2.56159 -7.29996)
			(stroke
				(width 0.3048)
				(type default)
			)
			(fill no)
			(layer "F.SilkS")
		)
		(fp_circle
			(center 4.19989 -12.800076)
			(end 2.56159 -12.800076)
			(stroke
				(width 0.3048)
				(type default)
			)
			(fill no)
			(layer "F.SilkS")
		)
		(fp_circle
			(center 0 -7.29996)
			(end -1.6383 -7.29996)
			(stroke
				(width 0.3048)
				(type default)
			)
			(fill no)
			(layer "F.SilkS")
		)
		(fp_circle
			(center 0 -12.800076)
			(end -1.6383 -12.800076)
			(stroke
				(width 0.3048)
				(type default)
			)
			(fill no)
			(layer "F.SilkS")
		)
		(fp_circle
			(center -4.19989 -7.29996)
			(end -5.83819 -7.29996)
			(stroke
				(width 0.3048)
				(type default)
			)
			(fill no)
			(layer "F.SilkS")
		)
		(fp_circle
			(center -4.19989 -12.800076)
			(end -5.83819 -12.800076)
			(stroke
				(width 0.3048)
				(type default)
			)
			(fill no)
			(layer "F.SilkS")
		)
		(fp_circle
			(center -8.400034 -7.29996)
			(end -10.038334 -7.29996)
			(stroke
				(width 0.3048)
				(type default)
			)
			(fill no)
			(layer "F.SilkS")
		)
		(fp_circle
			(center -8.400034 -12.800076)
			(end -10.038334 -12.800076)
			(stroke
				(width 0.3048)
				(type default)
			)
			(fill no)
			(layer "F.SilkS")
		)
		(fp_poly
			(pts
				(xy -13.7922 7.8994) (xy -13.7922 -6.1976) (xy -9.2964 -6.1976) (xy -9.2964 -13.6906) (xy 9.2964 -13.6906)
				(xy 9.2964 -6.1976) (xy 13.7922 -6.1976) (xy 13.7922 7.8994)
			)
			(stroke
				(width 0)
				(type default)
			)
			(fill no)
			(layer "F.CrtYd")
		)
		(fp_poly
			(pts
				(xy -14.3002 8.4074) (xy -14.3002 -6.7056) (xy -10.1854 -6.7056) (xy -10.1854 -14.5796) (xy 10.1854 -14.5796)
				(xy 10.1854 -6.7056) (xy 14.3002 -6.7056) (xy 14.3002 -0.00635) (xy 13.7922 -0.00635) (xy 13.7922 -6.1976)
				(xy 9.2964 -6.1976) (xy 9.2964 -13.6906) (xy -9.2964 -13.6906) (xy -9.2964 -6.1976) (xy -13.7922 -6.1976)
				(xy -13.7922 7.8994) (xy 13.7922 7.8994) (xy 13.7922 0.00635) (xy 14.3002 0.00635) (xy 14.3002 8.4074)
			)
			(stroke
				(width 0)
				(type default)
			)
			(fill no)
			(layer "F.CrtYd")
		)
		(fp_poly
			(pts
				(xy -14.3002 8.4074) (xy -14.3002 -6.7056) (xy -10.1854 -6.7056) (xy -10.1854 -14.5796) (xy 10.1854 -14.5796)
				(xy 10.1854 -6.7056) (xy 14.3002 -6.7056) (xy 14.3002 8.4074)
			)
			(stroke
				(width 0)
				(type default)
			)
			(fill no)
			(layer "F.Fab")
		)
		(pad "" np_thru_hole circle
			(at -8.400034 0 180)
			(size 0.254 0.254)
			(drill 3.0226)
			(layers "*.Cu" "*.Mask")
			(clearance 1.7399)
			(thermal_gap 1.7399)
		)
		(pad "" np_thru_hole circle
			(at 8.400034 0 180)
			(size 0.254 0.254)
			(drill 3.0226)
			(layers "*.Cu" "*.Mask")
			(clearance 1.7399)
			(thermal_gap 1.7399)
		)
		(pad "1" thru_hole circle
			(at 8.400034 -7.29996 180)
			(size 2.5654 2.5654)
			(drill 1.8034)
			(layers "*.Cu" "*.Mask")
			(remove_unused_layers no)
			(net "FAN_3_TACH0")
			(clearance 0.127)
			(thermal_gap 0.127)
		)
		(pad "2" thru_hole circle
			(at 8.400034 -12.800076 180)
			(size 2.5654 2.5654)
			(drill 1.8034)
			(layers "*.Cu" "*.Mask")
			(remove_unused_layers no)
			(net "FAN_3_TACH1")
			(clearance 0.127)
			(thermal_gap 0.127)
		)
		(pad "3" thru_hole circle
			(at 4.19989 -7.29996 180)
			(size 2.5654 2.5654)
			(drill 1.8034)
			(layers "*.Cu" "*.Mask")
			(remove_unused_layers no)
			(net "FAN_3_PWM")
			(clearance 0.127)
			(thermal_gap 0.127)
		)
		(pad "4" thru_hole circle
			(at 4.19989 -12.800076 180)
			(size 2.5654 2.5654)
			(drill 1.8034)
			(layers "*.Cu" "*.Mask")
			(remove_unused_layers no)
			(net "FAN_3_PWM")
			(clearance 0.127)
			(thermal_gap 0.127)
		)
		(pad "5" thru_hole circle
			(at 0 -7.29996 180)
			(size 2.5654 2.5654)
			(drill 1.8034)
			(layers "*.Cu" "*.Mask")
			(remove_unused_layers no)
			(net "FAN_3_INS_N")
			(clearance 0.127)
			(thermal_gap 0.127)
		)
		(pad "6" thru_hole circle
			(at 0 -12.800076 180)
			(size 2.5654 2.5654)
			(drill 1.8034)
			(layers "*.Cu" "*.Mask")
			(remove_unused_layers no)
			(net "Net_1769")
			(clearance 0.127)
			(thermal_gap 0.127)
		)
		(pad "7" thru_hole circle
			(at -4.19989 -7.29996 180)
			(size 2.5654 2.5654)
			(drill 1.8034)
			(layers "*.Cu" "*.Mask")
			(remove_unused_layers no)
			(net "P12V_FAN3")
			(clearance 0.127)
			(thermal_gap 0.127)
		)
		(pad "8" thru_hole circle
			(at -4.19989 -12.800076 180)
			(size 2.5654 2.5654)
			(drill 1.8034)
			(layers "*.Cu" "*.Mask")
			(remove_unused_layers no)
			(net "P12V_FAN3")
			(clearance 0.127)
			(thermal_gap 0.127)
		)
		(pad "9" thru_hole circle
			(at -8.400034 -7.29996 180)
			(size 2.5654 2.5654)
			(drill 1.8034)
			(layers "*.Cu" "*.Mask")
			(remove_unused_layers no)
			(net "GND")
			(clearance 0.127)
			(thermal_gap 0.127)
		)
		(pad "10" thru_hole circle
			(at -8.400034 -12.800076 180)
			(size 2.5654 2.5654)
			(drill 1.8034)
			(layers "*.Cu" "*.Mask")
			(remove_unused_layers no)
			(net "GND")
			(clearance 0.127)
			(thermal_gap 0.127)
		)
		(zone
			(layers "F.Cu" "B.Cu" "In1.Cu" "In2.Cu" "In3.Cu" "In4.Cu" "In5.Cu" "In6.Cu")
			(hatch none 0.5)
			(connect_pads
				(clearance 0)
			)
			(min_thickness 0.25)
			(keepout
				(tracks not_allowed)
				(vias allowed)
				(pads allowed)
				(copperpour not_allowed)
				(footprints allowed)
			)
			(placement
				(enabled no)
				(sheetname "")
			)
			(fill
				(thermal_gap 0.5)
				(thermal_bridge_width 0.5)
				(island_removal_mode 0)
			)
			(polygon
				(pts
					(arc
						(start 432.41595 -379.899926)
						(mid 428.78375 -379.899926)
						(end 432.41595 -379.899926)
					)
				)
			)
		)
		(zone
			(layers "F.Cu" "B.Cu" "In1.Cu" "In2.Cu" "In3.Cu" "In4.Cu" "In5.Cu" "In6.Cu")
			(hatch none 0.5)
			(connect_pads
				(clearance 0)
			)
			(min_thickness 0.25)
			(keepout
				(tracks not_allowed)
				(vias allowed)
				(pads allowed)
				(copperpour not_allowed)
				(footprints allowed)
			)
			(placement
				(enabled no)
				(sheetname "")
			)
			(fill
				(thermal_gap 0.5)
				(thermal_bridge_width 0.5)
				(island_removal_mode 0)
			)
			(polygon
				(pts
					(arc
						(start 449.216018 -379.899926)
						(mid 445.583818 -379.899926)
						(end 449.216018 -379.899926)
					)
				)
			)
		)
	)
	(footprint ""
		(layer "F.Cu")
		(at 181.3814 -374.8532 90)
		(property "Reference" "R1002"
			(at 0 0 90)
			(layer "F.SilkS")
			(hide yes)
			(effects
				(font
					(size 1.27 1.27)
				)
			)
		)
		(property "Value" "3K83R2F-GP"
			(at 0.064008 -3.993896 90)
			(unlocked yes)
			(layer "F.Fab")
			(hide yes)
			(effects
				(font
					(size 1.016 1.016)
					(thickness 0.1524)
				)
			)
		)
		(property "Device Type" "R402H16"
			(at 0.064008 -5.517896 90)
			(unlocked yes)
			(layer "F.Fab")
			(hide yes)
			(effects
				(font
					(size 1.016 1.016)
					(thickness 0.1524)
				)
			)
		)
		(duplicate_pad_numbers_are_jumpers no)
		(fp_line
			(start 0.508 -0.9398)
			(end -0.508 -0.9398)
			(stroke
				(width 0.1524)
				(type default)
			)
			(layer "F.SilkS")
		)
		(fp_line
			(start -0.508 -0.9398)
			(end -0.508 0.9398)
			(stroke
				(width 0.1524)
				(type default)
			)
			(layer "F.SilkS")
		)
		(fp_rect
			(start -0.508 0.9398)
			(end 0.508 -0.9398)
			(stroke
				(width 0)
				(type default)
			)
			(fill no)
			(layer "F.CrtYd")
		)
		(fp_rect
			(start -0.508 0.9398)
			(end 0.508 -0.9398)
			(stroke
				(width 0)
				(type default)
			)
			(fill no)
			(layer "F.Fab")
		)
		(pad "1" smd custom
			(at 0 -0.4445 90)
			(size 0.1397 0.1397)
			(layers "F.Cu" "F.Mask" "F.Paste")
			(net "P12V_IN_PGOOD")
			(options
				(clearance outline)
				(anchor circle)
			)
			(primitives
				(gr_poly
					(pts
						(arc
							(start -0.1778 -0.2794)
							(mid -0.249642 -0.249642)
							(end -0.2794 -0.1778)
						)
						(arc
							(start -0.2794 0.1778)
							(mid -0.249642 0.249642)
							(end -0.1778 0.2794)
						)
						(arc
							(start 0.1778 0.2794)
							(mid 0.249642 0.249642)
							(end 0.2794 0.1778)
						)
						(arc
							(start 0.2794 -0.1778)
							(mid 0.249642 -0.249642)
							(end 0.1778 -0.2794)
						)
					)
					(width 0)
					(fill yes)
				)
			)
		)
		(pad "2" smd custom
			(at 0 0.4445 90)
			(size 0.1397 0.1397)
			(layers "F.Cu" "F.Mask" "F.Paste")
			(net "GND")
			(options
				(clearance outline)
				(anchor circle)
			)
			(primitives
				(gr_poly
					(pts
						(arc
							(start -0.1778 -0.2794)
							(mid -0.249642 -0.249642)
							(end -0.2794 -0.1778)
						)
						(arc
							(start -0.2794 0.1778)
							(mid -0.249642 0.249642)
							(end -0.1778 0.2794)
						)
						(arc
							(start 0.1778 0.2794)
							(mid 0.249642 0.249642)
							(end 0.2794 0.1778)
						)
						(arc
							(start 0.2794 -0.1778)
							(mid 0.249642 -0.249642)
							(end 0.1778 -0.2794)
						)
					)
					(width 0)
					(fill yes)
				)
			)
		)
	)
	(footprint ""
		(layer "F.Cu")
		(at 303.604676 -233.195114 90)
		(property "Reference" "R919"
			(at 0 0 90)
			(layer "F.SilkS")
			(hide yes)
			(effects
				(font
					(size 1.27 1.27)
				)
			)
		)
		(property "Value" "0R2J-2-GP"
			(at 0.064008 -3.993896 90)
			(unlocked yes)
			(layer "F.Fab")
			(hide yes)
			(effects
				(font
					(size 1.016 1.016)
					(thickness 0.1524)
				)
			)
		)
		(property "Device Type" "R402H16"
			(at 0.064008 -5.517896 90)
			(unlocked yes)
			(layer "F.Fab")
			(hide yes)
			(effects
				(font
					(size 1.016 1.016)
					(thickness 0.1524)
				)
			)
		)
		(duplicate_pad_numbers_are_jumpers no)
		(fp_line
			(start 0.508 -0.9398)
			(end -0.508 -0.9398)
			(stroke
				(width 0.1524)
				(type default)
			)
			(layer "F.SilkS")
		)
		(fp_line
			(start -0.508 -0.9398)
			(end -0.508 0.9398)
			(stroke
				(width 0.1524)
				(type default)
			)
			(layer "F.SilkS")
		)
		(fp_rect
			(start -0.508 0.9398)
			(end 0.508 -0.9398)
			(stroke
				(width 0)
				(type default)
			)
			(fill no)
			(layer "F.CrtYd")
		)
		(fp_rect
			(start -0.508 0.9398)
			(end 0.508 -0.9398)
			(stroke
				(width 0)
				(type default)
			)
			(fill no)
			(layer "F.Fab")
		)
		(pad "1" smd custom
			(at 0 -0.4445 90)
			(size 0.1397 0.1397)
			(layers "F.Cu" "F.Mask" "F.Paste")
			(net "SCC_B_SLOT_ID_1")
			(options
				(clearance outline)
				(anchor circle)
			)
			(primitives
				(gr_poly
					(pts
						(arc
							(start -0.1778 -0.2794)
							(mid -0.249642 -0.249642)
							(end -0.2794 -0.1778)
						)
						(arc
							(start -0.2794 0.1778)
							(mid -0.249642 0.249642)
							(end -0.1778 0.2794)
						)
						(arc
							(start 0.1778 0.2794)
							(mid 0.249642 0.249642)
							(end 0.2794 0.1778)
						)
						(arc
							(start 0.2794 -0.1778)
							(mid 0.249642 -0.249642)
							(end 0.1778 -0.2794)
						)
					)
					(width 0)
					(fill yes)
				)
			)
		)
		(pad "2" smd custom
			(at 0 0.4445 90)
			(size 0.1397 0.1397)
			(layers "F.Cu" "F.Mask" "F.Paste")
			(net "GND")
			(options
				(clearance outline)
				(anchor circle)
			)
			(primitives
				(gr_poly
					(pts
						(arc
							(start -0.1778 -0.2794)
							(mid -0.249642 -0.249642)
							(end -0.2794 -0.1778)
						)
						(arc
							(start -0.2794 0.1778)
							(mid -0.249642 0.249642)
							(end -0.1778 0.2794)
						)
						(arc
							(start 0.1778 0.2794)
							(mid 0.249642 0.249642)
							(end 0.2794 0.1778)
						)
						(arc
							(start 0.2794 -0.1778)
							(mid 0.249642 -0.249642)
							(end 0.1778 -0.2794)
						)
					)
					(width 0)
					(fill yes)
				)
			)
		)
	)
	(footprint ""
		(layer "F.Cu")
		(at 105.484168 -99.798378 90)
		(property "Reference" "Q258"
			(at 0 0 90)
			(layer "F.SilkS")
			(hide yes)
			(effects
				(font
					(size 1.27 1.27)
				)
			)
		)
		(property "Value" "SSM3K324R-GP"
			(at 0.127 -8.9662 90)
			(unlocked yes)
			(layer "F.Fab")
			(hide yes)
			(effects
				(font
					(size 1.016 1.016)
					(thickness 0.1524)
				)
			)
		)
		(property "Device Type" "SOT23DGS2D4H35"
			(at 0.127 -10.4902 90)
			(unlocked yes)
			(layer "F.Fab")
			(hide yes)
			(effects
				(font
					(size 1.016 1.016)
					(thickness 0.1524)
				)
			)
		)
		(duplicate_pad_numbers_are_jumpers no)
		(fp_line
			(start 1.651 -1.778)
			(end -1.651 -1.778)
			(stroke
				(width 0.1524)
				(type default)
			)
			(layer "F.SilkS")
		)
		(fp_line
			(start -1.651 -1.778)
			(end -1.651 1.778)
			(stroke
				(width 0.1524)
				(type default)
			)
			(layer "F.SilkS")
		)
		(fp_line
			(start 1.651 1.778)
			(end 1.651 -1.778)
			(stroke
				(width 0.1524)
				(type default)
			)
			(layer "F.SilkS")
		)
		(fp_line
			(start -1.651 1.778)
			(end 1.651 1.778)
			(stroke
				(width 0.1524)
				(type default)
			)
			(layer "F.SilkS")
		)
		(fp_poly
			(pts
				(xy -1.778 1.8796) (xy -1.778 -1.8796) (xy 1.778 -1.8796) (xy 1.778 1.8796)
			)
			(stroke
				(width 0)
				(type default)
			)
			(fill no)
			(layer "F.CrtYd")
		)
		(fp_poly
			(pts
				(xy -1.778 1.8796) (xy -1.778 -1.8796) (xy 1.778 -1.8796) (xy 1.778 1.8796)
			)
			(stroke
				(width 0)
				(type default)
			)
			(fill no)
			(layer "F.Fab")
		)
		(pad "D" smd custom
			(at 0 -0.9525 90)
			(size 0.1905 0.1905)
			(layers "F.Cu" "F.Mask" "F.Paste")
			(net "DRV_ACT_15_N")
			(options
				(clearance outline)
				(anchor circle)
			)
			(primitives
				(gr_poly
					(pts
						(arc
							(start -0.1778 0.5715)
							(mid -0.321484 0.511984)
							(end -0.381 0.3683)
						)
						(arc
							(start -0.381 -0.3683)
							(mid -0.321484 -0.511984)
							(end -0.1778 -0.5715)
						)
						(arc
							(start 0.1778 -0.5715)
							(mid 0.321484 -0.511984)
							(end 0.381 -0.3683)
						)
						(arc
							(start 0.381 0.3683)
							(mid 0.321484 0.511984)
							(end 0.1778 0.5715)
						)
					)
					(width 0)
					(fill yes)
				)
			)
		)
		(pad "G" smd custom
			(at -0.98425 0.9525 90)
			(size 0.1905 0.1905)
			(layers "F.Cu" "F.Mask" "F.Paste")
			(net "DRIVE_B_15_ACT")
			(options
				(clearance outline)
				(anchor circle)
			)
			(primitives
				(gr_poly
					(pts
						(arc
							(start -0.1778 0.5715)
							(mid -0.321484 0.511984)
							(end -0.381 0.3683)
						)
						(arc
							(start -0.381 -0.3683)
							(mid -0.321484 -0.511984)
							(end -0.1778 -0.5715)
						)
						(arc
							(start 0.1778 -0.5715)
							(mid 0.321484 -0.511984)
							(end 0.381 -0.3683)
						)
						(arc
							(start 0.381 0.3683)
							(mid 0.321484 0.511984)
							(end 0.1778 0.5715)
						)
					)
					(width 0)
					(fill yes)
				)
			)
		)
		(pad "S" smd custom
			(at 0.98425 0.9525 90)
			(size 0.1905 0.1905)
			(layers "F.Cu" "F.Mask" "F.Paste")
			(net "GND")
			(options
				(clearance outline)
				(anchor circle)
			)
			(primitives
				(gr_poly
					(pts
						(arc
							(start -0.1778 0.5715)
							(mid -0.321484 0.511984)
							(end -0.381 0.3683)
						)
						(arc
							(start -0.381 -0.3683)
							(mid -0.321484 -0.511984)
							(end -0.1778 -0.5715)
						)
						(arc
							(start 0.1778 -0.5715)
							(mid 0.321484 -0.511984)
							(end 0.381 -0.3683)
						)
						(arc
							(start 0.381 0.3683)
							(mid 0.321484 0.511984)
							(end 0.1778 0.5715)
						)
					)
					(width 0)
					(fill yes)
				)
			)
		)
	)
	(footprint ""
		(layer "F.Cu")
		(at 268.097 -226.568)
		(property "Reference" "R9"
			(at 0 0 0)
			(layer "F.SilkS")
			(hide yes)
			(effects
				(font
					(size 1.27 1.27)
				)
			)
		)
		(property "Value" "1KR2F-3-GP"
			(at 0.064008 -3.993896 0)
			(unlocked yes)
			(layer "F.Fab")
			(hide yes)
			(effects
				(font
					(size 1.016 1.016)
					(thickness 0.1524)
				)
			)
		)
		(property "Device Type" "R402H16"
			(at 0.064008 -5.517896 0)
			(unlocked yes)
			(layer "F.Fab")
			(hide yes)
			(effects
				(font
					(size 1.016 1.016)
					(thickness 0.1524)
				)
			)
		)
		(duplicate_pad_numbers_are_jumpers no)
		(fp_line
			(start -0.508 -0.9398)
			(end -0.508 0.9398)
			(stroke
				(width 0.1524)
				(type default)
			)
			(layer "F.SilkS")
		)
		(fp_line
			(start 0.508 -0.9398)
			(end -0.508 -0.9398)
			(stroke
				(width 0.1524)
				(type default)
			)
			(layer "F.SilkS")
		)
		(fp_rect
			(start -0.508 0.9398)
			(end 0.508 -0.9398)
			(stroke
				(width 0)
				(type default)
			)
			(fill no)
			(layer "F.CrtYd")
		)
		(fp_rect
			(start -0.508 0.9398)
			(end 0.508 -0.9398)
			(stroke
				(width 0)
				(type default)
			)
			(fill no)
			(layer "F.Fab")
		)
		(pad "1" smd custom
			(at 0 -0.4445)
			(size 0.1397 0.1397)
			(layers "F.Cu" "F.Mask" "F.Paste")
			(net "P3V3_IN")
			(options
				(clearance outline)
				(anchor circle)
			)
			(primitives
				(gr_poly
					(pts
						(arc
							(start -0.1778 -0.2794)
							(mid -0.249642 -0.249642)
							(end -0.2794 -0.1778)
						)
						(arc
							(start -0.2794 0.1778)
							(mid -0.249642 0.249642)
							(end -0.1778 0.2794)
						)
						(arc
							(start 0.1778 0.2794)
							(mid 0.249642 0.249642)
							(end 0.2794 0.1778)
						)
						(arc
							(start 0.2794 -0.1778)
							(mid 0.249642 -0.249642)
							(end 0.1778 -0.2794)
						)
					)
					(width 0)
					(fill yes)
				)
			)
		)
		(pad "2" smd custom
			(at 0 0.4445)
			(size 0.1397 0.1397)
			(layers "F.Cu" "F.Mask" "F.Paste")
			(net "I2C_CLIP_B_SDA")
			(options
				(clearance outline)
				(anchor circle)
			)
			(primitives
				(gr_poly
					(pts
						(arc
							(start -0.1778 -0.2794)
							(mid -0.249642 -0.249642)
							(end -0.2794 -0.1778)
						)
						(arc
							(start -0.2794 0.1778)
							(mid -0.249642 0.249642)
							(end -0.1778 0.2794)
						)
						(arc
							(start 0.1778 0.2794)
							(mid 0.249642 0.249642)
							(end 0.2794 0.1778)
						)
						(arc
							(start 0.2794 -0.1778)
							(mid 0.249642 -0.249642)
							(end 0.1778 -0.2794)
						)
					)
					(width 0)
					(fill yes)
				)
			)
		)
	)
	(footprint ""
		(layer "F.Cu")
		(at 459.3082 -13.2588)
		(property "Reference" "R138"
			(at 0 0 0)
			(layer "F.SilkS")
			(hide yes)
			(effects
				(font
					(size 1.27 1.27)
				)
			)
		)
		(property "Value" "0R2J-2-GP"
			(at 0.064008 -3.993896 0)
			(unlocked yes)
			(layer "F.Fab")
			(hide yes)
			(effects
				(font
					(size 1.016 1.016)
					(thickness 0.1524)
				)
			)
		)
		(property "Device Type" "R402H16"
			(at 0.064008 -5.517896 0)
			(unlocked yes)
			(layer "F.Fab")
			(hide yes)
			(effects
				(font
					(size 1.016 1.016)
					(thickness 0.1524)
				)
			)
		)
		(duplicate_pad_numbers_are_jumpers no)
		(fp_line
			(start -0.508 -0.9398)
			(end -0.508 0.9398)
			(stroke
				(width 0.1524)
				(type default)
			)
			(layer "F.SilkS")
		)
		(fp_line
			(start 0.508 -0.9398)
			(end -0.508 -0.9398)
			(stroke
				(width 0.1524)
				(type default)
			)
			(layer "F.SilkS")
		)
		(fp_rect
			(start -0.508 0.9398)
			(end 0.508 -0.9398)
			(stroke
				(width 0)
				(type default)
			)
			(fill no)
			(layer "F.CrtYd")
		)
		(fp_rect
			(start -0.508 0.9398)
			(end 0.508 -0.9398)
			(stroke
				(width 0)
				(type default)
			)
			(fill no)
			(layer "F.Fab")
		)
		(pad "1" smd custom
			(at 0 -0.4445)
			(size 0.1397 0.1397)
			(layers "F.Cu" "F.Mask" "F.Paste")
			(net "I2C_DPB_B_SDA_BUF")
			(options
				(clearance outline)
				(anchor circle)
			)
			(primitives
				(gr_poly
					(pts
						(arc
							(start -0.1778 -0.2794)
							(mid -0.249642 -0.249642)
							(end -0.2794 -0.1778)
						)
						(arc
							(start -0.2794 0.1778)
							(mid -0.249642 0.249642)
							(end -0.1778 0.2794)
						)
						(arc
							(start 0.1778 0.2794)
							(mid 0.249642 0.249642)
							(end 0.2794 0.1778)
						)
						(arc
							(start 0.2794 -0.1778)
							(mid 0.249642 -0.249642)
							(end 0.1778 -0.2794)
						)
					)
					(width 0)
					(fill yes)
				)
			)
		)
		(pad "2" smd custom
			(at 0 0.4445)
			(size 0.1397 0.1397)
			(layers "F.Cu" "F.Mask" "F.Paste")
			(net "TEMP2_SDA")
			(options
				(clearance outline)
				(anchor circle)
			)
			(primitives
				(gr_poly
					(pts
						(arc
							(start -0.1778 -0.2794)
							(mid -0.249642 -0.249642)
							(end -0.2794 -0.1778)
						)
						(arc
							(start -0.2794 0.1778)
							(mid -0.249642 0.249642)
							(end -0.1778 0.2794)
						)
						(arc
							(start 0.1778 0.2794)
							(mid 0.249642 0.249642)
							(end 0.2794 0.1778)
						)
						(arc
							(start 0.2794 -0.1778)
							(mid 0.249642 -0.249642)
							(end 0.1778 -0.2794)
						)
					)
					(width 0)
					(fill yes)
				)
			)
		)
	)
	(footprint ""
		(layer "F.Cu")
		(at 18.415 -246.634)
		(property "Reference" "R915"
			(at 0 0 0)
			(layer "F.SilkS")
			(hide yes)
			(effects
				(font
					(size 1.27 1.27)
				)
			)
		)
		(property "Value" "0R2J-2-GP"
			(at 0.064008 -3.993896 0)
			(unlocked yes)
			(layer "F.Fab")
			(hide yes)
			(effects
				(font
					(size 1.016 1.016)
					(thickness 0.1524)
				)
			)
		)
		(property "Device Type" "R402H16"
			(at 0.064008 -5.517896 0)
			(unlocked yes)
			(layer "F.Fab")
			(hide yes)
			(effects
				(font
					(size 1.016 1.016)
					(thickness 0.1524)
				)
			)
		)
		(duplicate_pad_numbers_are_jumpers no)
		(fp_line
			(start -0.508 -0.9398)
			(end -0.508 0.9398)
			(stroke
				(width 0.1524)
				(type default)
			)
			(layer "F.SilkS")
		)
		(fp_line
			(start 0.508 -0.9398)
			(end -0.508 -0.9398)
			(stroke
				(width 0.1524)
				(type default)
			)
			(layer "F.SilkS")
		)
		(fp_rect
			(start -0.508 0.9398)
			(end 0.508 -0.9398)
			(stroke
				(width 0)
				(type default)
			)
			(fill no)
			(layer "F.CrtYd")
		)
		(fp_rect
			(start -0.508 0.9398)
			(end 0.508 -0.9398)
			(stroke
				(width 0)
				(type default)
			)
			(fill no)
			(layer "F.Fab")
		)
		(pad "1" smd custom
			(at 0 -0.4445)
			(size 0.1397 0.1397)
			(layers "F.Cu" "F.Mask" "F.Paste")
			(net "SW_HDD_G0")
			(options
				(clearance outline)
				(anchor circle)
			)
			(primitives
				(gr_poly
					(pts
						(arc
							(start -0.1778 -0.2794)
							(mid -0.249642 -0.249642)
							(end -0.2794 -0.1778)
						)
						(arc
							(start -0.2794 0.1778)
							(mid -0.249642 0.249642)
							(end -0.1778 0.2794)
						)
						(arc
							(start 0.1778 0.2794)
							(mid 0.249642 0.249642)
							(end 0.2794 0.1778)
						)
						(arc
							(start 0.2794 -0.1778)
							(mid 0.249642 -0.249642)
							(end 0.1778 -0.2794)
						)
					)
					(width 0)
					(fill yes)
				)
			)
		)
		(pad "2" smd custom
			(at 0 0.4445)
			(size 0.1397 0.1397)
			(layers "F.Cu" "F.Mask" "F.Paste")
			(net "SW_HDD_R0")
			(options
				(clearance outline)
				(anchor circle)
			)
			(primitives
				(gr_poly
					(pts
						(arc
							(start -0.1778 -0.2794)
							(mid -0.249642 -0.249642)
							(end -0.2794 -0.1778)
						)
						(arc
							(start -0.2794 0.1778)
							(mid -0.249642 0.249642)
							(end -0.1778 0.2794)
						)
						(arc
							(start 0.1778 0.2794)
							(mid 0.249642 0.249642)
							(end 0.2794 0.1778)
						)
						(arc
							(start 0.2794 -0.1778)
							(mid 0.249642 -0.249642)
							(end 0.1778 -0.2794)
						)
					)
					(width 0)
					(fill yes)
				)
			)
		)
	)
	(footprint ""
		(layer "F.Cu")
		(at 77.978 -24.511 -90)
		(property "Reference" "R683"
			(at 0 0 270)
			(layer "F.SilkS")
			(hide yes)
			(effects
				(font
					(size 1.27 1.27)
				)
			)
		)
		(property "Value" "300KR2F-GP"
			(at 0.064008 -3.993896 270)
			(unlocked yes)
			(layer "F.Fab")
			(hide yes)
			(effects
				(font
					(size 1.016 1.016)
					(thickness 0.1524)
				)
			)
		)
		(property "Device Type" "R402H16"
			(at 0.064008 -5.517896 270)
			(unlocked yes)
			(layer "F.Fab")
			(hide yes)
			(effects
				(font
					(size 1.016 1.016)
					(thickness 0.1524)
				)
			)
		)
		(duplicate_pad_numbers_are_jumpers no)
		(fp_line
			(start -0.508 -0.9398)
			(end -0.508 0.9398)
			(stroke
				(width 0.1524)
				(type default)
			)
			(layer "F.SilkS")
		)
		(fp_line
			(start 0.508 -0.9398)
			(end -0.508 -0.9398)
			(stroke
				(width 0.1524)
				(type default)
			)
			(layer "F.SilkS")
		)
		(fp_rect
			(start -0.508 0.9398)
			(end 0.508 -0.9398)
			(stroke
				(width 0)
				(type default)
			)
			(fill no)
			(layer "F.CrtYd")
		)
		(fp_rect
			(start -0.508 0.9398)
			(end 0.508 -0.9398)
			(stroke
				(width 0)
				(type default)
			)
			(fill no)
			(layer "F.Fab")
		)
		(pad "1" smd custom
			(at 0 -0.4445 270)
			(size 0.1397 0.1397)
			(layers "F.Cu" "F.Mask" "F.Paste")
			(net "SW_HDD_N26")
			(options
				(clearance outline)
				(anchor circle)
			)
			(primitives
				(gr_poly
					(pts
						(arc
							(start -0.1778 -0.2794)
							(mid -0.249642 -0.249642)
							(end -0.2794 -0.1778)
						)
						(arc
							(start -0.2794 0.1778)
							(mid -0.249642 0.249642)
							(end -0.1778 0.2794)
						)
						(arc
							(start 0.1778 0.2794)
							(mid 0.249642 0.249642)
							(end 0.2794 0.1778)
						)
						(arc
							(start 0.2794 -0.1778)
							(mid 0.249642 -0.249642)
							(end 0.1778 -0.2794)
						)
					)
					(width 0)
					(fill yes)
				)
			)
		)
		(pad "2" smd custom
			(at 0 0.4445 270)
			(size 0.1397 0.1397)
			(layers "F.Cu" "F.Mask" "F.Paste")
			(net "P12V_B")
			(options
				(clearance outline)
				(anchor circle)
			)
			(primitives
				(gr_poly
					(pts
						(arc
							(start -0.1778 -0.2794)
							(mid -0.249642 -0.249642)
							(end -0.2794 -0.1778)
						)
						(arc
							(start -0.2794 0.1778)
							(mid -0.249642 0.249642)
							(end -0.1778 0.2794)
						)
						(arc
							(start 0.1778 0.2794)
							(mid 0.249642 0.249642)
							(end 0.2794 0.1778)
						)
						(arc
							(start 0.2794 -0.1778)
							(mid 0.249642 -0.249642)
							(end 0.1778 -0.2794)
						)
					)
					(width 0)
					(fill yes)
				)
			)
		)
	)
	(footprint ""
		(layer "F.Cu")
		(at 459.613 -44.958 180)
		(property "Reference" "C478"
			(at 0 0 180)
			(layer "F.SilkS")
			(hide yes)
			(effects
				(font
					(size 1.27 1.27)
				)
			)
		)
		(property "Value" "SC4D7U25V5KX-1-GP"
			(at -0.0762 -6.1214 180)
			(unlocked yes)
			(layer "F.Fab")
			(hide yes)
			(effects
				(font
					(size 1.016 1.016)
					(thickness 0.1524)
				)
			)
		)
		(property "Device Type" "C805H58"
			(at -0.0762 -8.1534 180)
			(unlocked yes)
			(layer "F.Fab")
			(hide yes)
			(effects
				(font
					(size 1.016 1.016)
					(thickness 0.1524)
				)
			)
		)
		(duplicate_pad_numbers_are_jumpers no)
		(fp_line
			(start 0.635 0)
			(end -0.635 0)
			(stroke
				(width 0.508)
				(type default)
			)
			(layer "F.SilkS")
		)
		(fp_rect
			(start -0.9652 1.778)
			(end 0.9652 -1.778)
			(stroke
				(width 0)
				(type default)
			)
			(fill no)
			(layer "F.CrtYd")
		)
		(fp_poly
			(pts
				(xy -0.9652 -1.778) (xy 0.9652 -1.778) (xy 0.9652 1.778) (xy -0.9652 1.778)
			)
			(stroke
				(width 0)
				(type default)
			)
			(fill no)
			(layer "F.Fab")
		)
		(pad "1" smd rect
			(at 0 -0.9652 180)
			(size 1.397 1.143)
			(layers "F.Cu" "F.Mask" "F.Paste")
			(net "P12V_HDD34")
		)
		(pad "2" smd rect
			(at 0 0.9652 180)
			(size 1.397 1.143)
			(layers "F.Cu" "F.Mask" "F.Paste")
			(net "GND")
		)
	)
	(footprint ""
		(layer "F.Cu")
		(at 52.197 -11.4554 -90)
		(property "Reference" "R661"
			(at 0 0 270)
			(layer "F.SilkS")
			(hide yes)
			(effects
				(font
					(size 1.27 1.27)
				)
			)
		)
		(property "Value" "200KR2F-L-GP"
			(at 0.064008 -3.993896 270)
			(unlocked yes)
			(layer "F.Fab")
			(hide yes)
			(effects
				(font
					(size 1.016 1.016)
					(thickness 0.1524)
				)
			)
		)
		(property "Device Type" "R402H16"
			(at 0.064008 -5.517896 270)
			(unlocked yes)
			(layer "F.Fab")
			(hide yes)
			(effects
				(font
					(size 1.016 1.016)
					(thickness 0.1524)
				)
			)
		)
		(duplicate_pad_numbers_are_jumpers no)
		(fp_line
			(start -0.508 -0.9398)
			(end -0.508 0.9398)
			(stroke
				(width 0.1524)
				(type default)
			)
			(layer "F.SilkS")
		)
		(fp_line
			(start 0.508 -0.9398)
			(end -0.508 -0.9398)
			(stroke
				(width 0.1524)
				(type default)
			)
			(layer "F.SilkS")
		)
		(fp_rect
			(start -0.508 0.9398)
			(end 0.508 -0.9398)
			(stroke
				(width 0)
				(type default)
			)
			(fill no)
			(layer "F.CrtYd")
		)
		(fp_rect
			(start -0.508 0.9398)
			(end 0.508 -0.9398)
			(stroke
				(width 0)
				(type default)
			)
			(fill no)
			(layer "F.Fab")
		)
		(pad "1" smd custom
			(at 0 -0.4445 270)
			(size 0.1397 0.1397)
			(layers "F.Cu" "F.Mask" "F.Paste")
			(net "SW_HDD_R25")
			(options
				(clearance outline)
				(anchor circle)
			)
			(primitives
				(gr_poly
					(pts
						(arc
							(start -0.1778 -0.2794)
							(mid -0.249642 -0.249642)
							(end -0.2794 -0.1778)
						)
						(arc
							(start -0.2794 0.1778)
							(mid -0.249642 0.249642)
							(end -0.1778 0.2794)
						)
						(arc
							(start 0.1778 0.2794)
							(mid 0.249642 0.249642)
							(end 0.2794 0.1778)
						)
						(arc
							(start 0.2794 -0.1778)
							(mid 0.249642 -0.249642)
							(end 0.1778 -0.2794)
						)
					)
					(width 0)
					(fill yes)
				)
			)
		)
		(pad "2" smd custom
			(at 0 0.4445 270)
			(size 0.1397 0.1397)
			(layers "F.Cu" "F.Mask" "F.Paste")
			(net "SW_HDD_N25")
			(options
				(clearance outline)
				(anchor circle)
			)
			(primitives
				(gr_poly
					(pts
						(arc
							(start -0.1778 -0.2794)
							(mid -0.249642 -0.249642)
							(end -0.2794 -0.1778)
						)
						(arc
							(start -0.2794 0.1778)
							(mid -0.249642 0.249642)
							(end -0.1778 0.2794)
						)
						(arc
							(start 0.1778 0.2794)
							(mid 0.249642 0.249642)
							(end 0.2794 0.1778)
						)
						(arc
							(start 0.2794 -0.1778)
							(mid 0.249642 -0.249642)
							(end 0.1778 -0.2794)
						)
					)
					(width 0)
					(fill yes)
				)
			)
		)
	)
	(footprint ""
		(layer "F.Cu")
		(at 477.52 -19.685 -90)
		(property "Reference" "R875"
			(at 0 0 270)
			(layer "F.SilkS")
			(hide yes)
			(effects
				(font
					(size 1.27 1.27)
				)
			)
		)
		(property "Value" "10KR2F-2-GP"
			(at 0.064008 -3.993896 270)
			(unlocked yes)
			(layer "F.Fab")
			(hide yes)
			(effects
				(font
					(size 1.016 1.016)
					(thickness 0.1524)
				)
			)
		)
		(property "Device Type" "R402H16"
			(at 0.064008 -5.517896 270)
			(unlocked yes)
			(layer "F.Fab")
			(hide yes)
			(effects
				(font
					(size 1.016 1.016)
					(thickness 0.1524)
				)
			)
		)
		(duplicate_pad_numbers_are_jumpers no)
		(fp_line
			(start -0.508 -0.9398)
			(end -0.508 0.9398)
			(stroke
				(width 0.1524)
				(type default)
			)
			(layer "F.SilkS")
		)
		(fp_line
			(start 0.508 -0.9398)
			(end -0.508 -0.9398)
			(stroke
				(width 0.1524)
				(type default)
			)
			(layer "F.SilkS")
		)
		(fp_rect
			(start -0.508 0.9398)
			(end 0.508 -0.9398)
			(stroke
				(width 0)
				(type default)
			)
			(fill no)
			(layer "F.CrtYd")
		)
		(fp_rect
			(start -0.508 0.9398)
			(end 0.508 -0.9398)
			(stroke
				(width 0)
				(type default)
			)
			(fill no)
			(layer "F.Fab")
		)
		(pad "1" smd custom
			(at 0 -0.4445 270)
			(size 0.1397 0.1397)
			(layers "F.Cu" "F.Mask" "F.Paste")
			(net "P3V3_STBY_B")
			(options
				(clearance outline)
				(anchor circle)
			)
			(primitives
				(gr_poly
					(pts
						(arc
							(start -0.1778 -0.2794)
							(mid -0.249642 -0.249642)
							(end -0.2794 -0.1778)
						)
						(arc
							(start -0.2794 0.1778)
							(mid -0.249642 0.249642)
							(end -0.1778 0.2794)
						)
						(arc
							(start 0.1778 0.2794)
							(mid 0.249642 0.249642)
							(end 0.2794 0.1778)
						)
						(arc
							(start 0.2794 -0.1778)
							(mid 0.249642 -0.249642)
							(end 0.1778 -0.2794)
						)
					)
					(width 0)
					(fill yes)
				)
			)
		)
		(pad "2" smd custom
			(at 0 0.4445 270)
			(size 0.1397 0.1397)
			(layers "F.Cu" "F.Mask" "F.Paste")
			(net "HDD_PRSNT_35")
			(options
				(clearance outline)
				(anchor circle)
			)
			(primitives
				(gr_poly
					(pts
						(arc
							(start -0.1778 -0.2794)
							(mid -0.249642 -0.249642)
							(end -0.2794 -0.1778)
						)
						(arc
							(start -0.2794 0.1778)
							(mid -0.249642 0.249642)
							(end -0.1778 0.2794)
						)
						(arc
							(start 0.1778 0.2794)
							(mid 0.249642 0.249642)
							(end 0.2794 0.1778)
						)
						(arc
							(start 0.2794 -0.1778)
							(mid 0.249642 -0.249642)
							(end 0.1778 -0.2794)
						)
					)
					(width 0)
					(fill yes)
				)
			)
		)
	)
	(footprint ""
		(layer "F.Cu")
		(at 35.299396 -362.5596 180)
		(property "Reference" "R932"
			(at 0 0 180)
			(layer "F.SilkS")
			(hide yes)
			(effects
				(font
					(size 1.27 1.27)
				)
			)
		)
		(property "Value" "100KR2F-L1-GP"
			(at 0.064008 -3.993896 180)
			(unlocked yes)
			(layer "F.Fab")
			(hide yes)
			(effects
				(font
					(size 1.016 1.016)
					(thickness 0.1524)
				)
			)
		)
		(property "Device Type" "R402H16"
			(at 0.064008 -5.517896 180)
			(unlocked yes)
			(layer "F.Fab")
			(hide yes)
			(effects
				(font
					(size 1.016 1.016)
					(thickness 0.1524)
				)
			)
		)
		(duplicate_pad_numbers_are_jumpers no)
		(fp_line
			(start 0.508 -0.9398)
			(end -0.508 -0.9398)
			(stroke
				(width 0.1524)
				(type default)
			)
			(layer "F.SilkS")
		)
		(fp_line
			(start -0.508 -0.9398)
			(end -0.508 0.9398)
			(stroke
				(width 0.1524)
				(type default)
			)
			(layer "F.SilkS")
		)
		(fp_rect
			(start -0.508 0.9398)
			(end 0.508 -0.9398)
			(stroke
				(width 0)
				(type default)
			)
			(fill no)
			(layer "F.CrtYd")
		)
		(fp_rect
			(start -0.508 0.9398)
			(end 0.508 -0.9398)
			(stroke
				(width 0)
				(type default)
			)
			(fill no)
			(layer "F.Fab")
		)
		(pad "1" smd custom
			(at 0 -0.4445 180)
			(size 0.1397 0.1397)
			(layers "F.Cu" "F.Mask" "F.Paste")
			(net "SCC_A_FULL_PWR_EN")
			(options
				(clearance outline)
				(anchor circle)
			)
			(primitives
				(gr_poly
					(pts
						(arc
							(start -0.1778 -0.2794)
							(mid -0.249642 -0.249642)
							(end -0.2794 -0.1778)
						)
						(arc
							(start -0.2794 0.1778)
							(mid -0.249642 0.249642)
							(end -0.1778 0.2794)
						)
						(arc
							(start 0.1778 0.2794)
							(mid 0.249642 0.249642)
							(end 0.2794 0.1778)
						)
						(arc
							(start 0.2794 -0.1778)
							(mid 0.249642 -0.249642)
							(end 0.1778 -0.2794)
						)
					)
					(width 0)
					(fill yes)
				)
			)
		)
		(pad "2" smd custom
			(at 0 0.4445 180)
			(size 0.1397 0.1397)
			(layers "F.Cu" "F.Mask" "F.Paste")
			(net "GND")
			(options
				(clearance outline)
				(anchor circle)
			)
			(primitives
				(gr_poly
					(pts
						(arc
							(start -0.1778 -0.2794)
							(mid -0.249642 -0.249642)
							(end -0.2794 -0.1778)
						)
						(arc
							(start -0.2794 0.1778)
							(mid -0.249642 0.249642)
							(end -0.1778 0.2794)
						)
						(arc
							(start 0.1778 0.2794)
							(mid 0.249642 0.249642)
							(end 0.2794 0.1778)
						)
						(arc
							(start 0.2794 -0.1778)
							(mid 0.249642 -0.249642)
							(end 0.1778 -0.2794)
						)
					)
					(width 0)
					(fill yes)
				)
			)
		)
	)
	(footprint ""
		(layer "F.Cu")
		(at 257.331972 -335.277206 90)
		(property "Reference" "Q203"
			(at 0 0 90)
			(layer "F.SilkS")
			(hide yes)
			(effects
				(font
					(size 1.27 1.27)
				)
			)
		)
		(property "Value" "IRFH8201TRPBF-GP"
			(at -4.2164 -4.3688 90)
			(unlocked yes)
			(layer "F.Fab")
			(hide yes)
			(effects
				(font
					(size 1.016 1.016)
					(thickness 0.1524)
				)
			)
		)
		(property "Device Type" "PPAK-5PH42"
			(at -4.2164 -5.8928 90)
			(unlocked yes)
			(layer "F.Fab")
			(hide yes)
			(effects
				(font
					(size 1.016 1.016)
					(thickness 0.1524)
				)
			)
		)
		(duplicate_pad_numbers_are_jumpers no)
		(fp_line
			(start 2.8956 -2.794)
			(end 2.8956 4.826)
			(stroke
				(width 0.1524)
				(type default)
			)
			(layer "F.SilkS")
		)
		(fp_line
			(start -2.8956 -2.794)
			(end 2.8956 -2.794)
			(stroke
				(width 0.1524)
				(type default)
			)
			(layer "F.SilkS")
		)
		(fp_line
			(start 2.8956 4.826)
			(end -2.8956 4.826)
			(stroke
				(width 0.1524)
				(type default)
			)
			(layer "F.SilkS")
		)
		(fp_line
			(start -2.8956 4.826)
			(end -2.8956 -2.794)
			(stroke
				(width 0.1524)
				(type default)
			)
			(layer "F.SilkS")
		)
		(fp_line
			(start -1.9431 4.9276)
			(end -3.0353 4.9276)
			(stroke
				(width 0.3302)
				(type default)
			)
			(layer "F.SilkS")
		)
		(fp_line
			(start -3.0353 4.9276)
			(end -3.0353 3.9624)
			(stroke
				(width 0.3302)
				(type default)
			)
			(layer "F.SilkS")
		)
		(fp_poly
			(pts
				(xy -2.3622 5.334) (xy -1.4986 5.334) (xy -1.9304 4.9022)
			)
			(stroke
				(width 0)
				(type default)
			)
			(fill yes)
			(layer "F.SilkS")
		)
		(fp_poly
			(pts
				(xy 0.3556 -0.3556) (xy 2.6416 -0.3556) (xy 2.6416 -2.54) (xy 0.3556 -2.54)
			)
			(stroke
				(width 0)
				(type default)
			)
			(fill yes)
			(layer "F.Paste")
		)
		(fp_poly
			(pts
				(xy -2.6416 -0.3556) (xy -0.3556 -0.3556) (xy -0.3556 -2.54) (xy -2.6416 -2.54)
			)
			(stroke
				(width 0)
				(type default)
			)
			(fill yes)
			(layer "F.Paste")
		)
		(fp_poly
			(pts
				(xy 0.3556 2.54) (xy 2.6416 2.54) (xy 2.6416 0.3556) (xy 0.3556 0.3556)
			)
			(stroke
				(width 0)
				(type default)
			)
			(fill yes)
			(layer "F.Paste")
		)
		(fp_poly
			(pts
				(xy -2.6416 2.54) (xy -0.3556 2.54) (xy -0.3556 0.3556) (xy -2.6416 0.3556)
			)
			(stroke
				(width 0)
				(type default)
			)
			(fill yes)
			(layer "F.Paste")
		)
		(fp_rect
			(start -2.5781 3.9878)
			(end 2.5781 -2.1082)
			(stroke
				(width 0)
				(type default)
			)
			(fill no)
			(layer "F.CrtYd")
		)
		(fp_poly
			(pts
				(xy -3.1496 5.08) (xy -3.1496 -3.048) (xy 3.1496 -3.048) (xy 3.1496 3.9751) (xy 2.5781 3.9751) (xy 2.5781 -2.1082)
				(xy -2.5781 -2.1082) (xy -2.5781 3.9878) (xy 3.1496 3.9878) (xy 3.1496 5.08)
			)
			(stroke
				(width 0)
				(type default)
			)
			(fill no)
			(layer "F.CrtYd")
		)
		(fp_rect
			(start -3.1496 5.08)
			(end 3.1496 -3.048)
			(stroke
				(width 0)
				(type default)
			)
			(fill no)
			(layer "F.Fab")
		)
		(pad "1" smd rect
			(at -1.905 3.81 90)
			(size 0.762 1.524)
			(layers "F.Cu" "F.Mask" "F.Paste")
			(net "P12V_B")
		)
		(pad "2" smd rect
			(at -0.635 3.81 90)
			(size 0.762 1.524)
			(layers "F.Cu" "F.Mask" "F.Paste")
			(net "P12V_B")
		)
		(pad "3" smd rect
			(at 0.635 3.81 90)
			(size 0.762 1.524)
			(layers "F.Cu" "F.Mask" "F.Paste")
			(net "P12V_B")
		)
		(pad "4" smd rect
			(at 1.905 3.81 90)
			(size 0.762 1.524)
			(layers "F.Cu" "F.Mask" "F.Paste")
			(net "MB3_12V_CTRL_GATE3")
		)
		(pad "5" smd rect
			(at 0 0 90)
			(size 5.2832 5.08)
			(layers "F.Cu" "F.Mask" "F.Paste")
			(net "MB3_P12V_IN_R")
		)
		(pad "6" smd rect
			(at 0.635 -2.032 90)
			(size 0.0254 0.0254)
			(layers "F.Cu" "F.Mask" "F.Paste")
			(net "MB3_P12V_IN_R")
		)
		(pad "7" smd rect
			(at -0.635 -2.032 90)
			(size 0.0254 0.0254)
			(layers "F.Cu" "F.Mask" "F.Paste")
			(net "MB3_P12V_IN_R")
		)
		(pad "8" smd rect
			(at -1.905 -2.032 90)
			(size 0.0254 0.0254)
			(layers "F.Cu" "F.Mask" "F.Paste")
			(net "MB3_P12V_IN_R")
		)
	)
	(footprint ""
		(layer "F.Cu")
		(at 207.3402 -194.945 -90)
		(property "Reference" "R32"
			(at 0 0 270)
			(layer "F.SilkS")
			(hide yes)
			(effects
				(font
					(size 1.27 1.27)
				)
			)
		)
		(property "Value" "4K7R2F-GP"
			(at 0.064008 -3.993896 270)
			(unlocked yes)
			(layer "F.Fab")
			(hide yes)
			(effects
				(font
					(size 1.016 1.016)
					(thickness 0.1524)
				)
			)
		)
		(property "Device Type" "R402H16"
			(at 0.064008 -5.517896 270)
			(unlocked yes)
			(layer "F.Fab")
			(hide yes)
			(effects
				(font
					(size 1.016 1.016)
					(thickness 0.1524)
				)
			)
		)
		(duplicate_pad_numbers_are_jumpers no)
		(fp_line
			(start -0.508 -0.9398)
			(end -0.508 0.9398)
			(stroke
				(width 0.1524)
				(type default)
			)
			(layer "F.SilkS")
		)
		(fp_line
			(start 0.508 -0.9398)
			(end -0.508 -0.9398)
			(stroke
				(width 0.1524)
				(type default)
			)
			(layer "F.SilkS")
		)
		(fp_rect
			(start -0.508 0.9398)
			(end 0.508 -0.9398)
			(stroke
				(width 0)
				(type default)
			)
			(fill no)
			(layer "F.CrtYd")
		)
		(fp_rect
			(start -0.508 0.9398)
			(end 0.508 -0.9398)
			(stroke
				(width 0)
				(type default)
			)
			(fill no)
			(layer "F.Fab")
		)
		(pad "1" smd custom
			(at 0 -0.4445 270)
			(size 0.1397 0.1397)
			(layers "F.Cu" "F.Mask" "F.Paste")
			(net "IO_EXP2_HDD_FAULT_A2")
			(options
				(clearance outline)
				(anchor circle)
			)
			(primitives
				(gr_poly
					(pts
						(arc
							(start -0.1778 -0.2794)
							(mid -0.249642 -0.249642)
							(end -0.2794 -0.1778)
						)
						(arc
							(start -0.2794 0.1778)
							(mid -0.249642 0.249642)
							(end -0.1778 0.2794)
						)
						(arc
							(start 0.1778 0.2794)
							(mid 0.249642 0.249642)
							(end 0.2794 0.1778)
						)
						(arc
							(start 0.2794 -0.1778)
							(mid 0.249642 -0.249642)
							(end 0.1778 -0.2794)
						)
					)
					(width 0)
					(fill yes)
				)
			)
		)
		(pad "2" smd custom
			(at 0 0.4445 270)
			(size 0.1397 0.1397)
			(layers "F.Cu" "F.Mask" "F.Paste")
			(net "GND")
			(options
				(clearance outline)
				(anchor circle)
			)
			(primitives
				(gr_poly
					(pts
						(arc
							(start -0.1778 -0.2794)
							(mid -0.249642 -0.249642)
							(end -0.2794 -0.1778)
						)
						(arc
							(start -0.2794 0.1778)
							(mid -0.249642 0.249642)
							(end -0.1778 0.2794)
						)
						(arc
							(start 0.1778 0.2794)
							(mid 0.249642 0.249642)
							(end 0.2794 0.1778)
						)
						(arc
							(start 0.2794 -0.1778)
							(mid 0.249642 -0.249642)
							(end 0.1778 -0.2794)
						)
					)
					(width 0)
					(fill yes)
				)
			)
		)
	)
	(footprint ""
		(layer "F.Cu")
		(at 394.6398 -17.6022 90)
		(property "Reference" "R813"
			(at 0 0 90)
			(layer "F.SilkS")
			(hide yes)
			(effects
				(font
					(size 1.27 1.27)
				)
			)
		)
		(property "Value" "4K7R2J-2-GP"
			(at 0.064008 -3.993896 90)
			(unlocked yes)
			(layer "F.Fab")
			(hide yes)
			(effects
				(font
					(size 1.016 1.016)
					(thickness 0.1524)
				)
			)
		)
		(property "Device Type" "R402H16"
			(at 0.064008 -5.517896 90)
			(unlocked yes)
			(layer "F.Fab")
			(hide yes)
			(effects
				(font
					(size 1.016 1.016)
					(thickness 0.1524)
				)
			)
		)
		(duplicate_pad_numbers_are_jumpers no)
		(fp_line
			(start 0.508 -0.9398)
			(end -0.508 -0.9398)
			(stroke
				(width 0.1524)
				(type default)
			)
			(layer "F.SilkS")
		)
		(fp_line
			(start -0.508 -0.9398)
			(end -0.508 0.9398)
			(stroke
				(width 0.1524)
				(type default)
			)
			(layer "F.SilkS")
		)
		(fp_rect
			(start -0.508 0.9398)
			(end 0.508 -0.9398)
			(stroke
				(width 0)
				(type default)
			)
			(fill no)
			(layer "F.CrtYd")
		)
		(fp_rect
			(start -0.508 0.9398)
			(end 0.508 -0.9398)
			(stroke
				(width 0)
				(type default)
			)
			(fill no)
			(layer "F.Fab")
		)
		(pad "1" smd custom
			(at 0 -0.4445 90)
			(size 0.1397 0.1397)
			(layers "F.Cu" "F.Mask" "F.Paste")
			(net "P12V_B")
			(options
				(clearance outline)
				(anchor circle)
			)
			(primitives
				(gr_poly
					(pts
						(arc
							(start -0.1778 -0.2794)
							(mid -0.249642 -0.249642)
							(end -0.2794 -0.1778)
						)
						(arc
							(start -0.2794 0.1778)
							(mid -0.249642 0.249642)
							(end -0.1778 0.2794)
						)
						(arc
							(start 0.1778 0.2794)
							(mid 0.249642 0.249642)
							(end 0.2794 0.1778)
						)
						(arc
							(start 0.2794 -0.1778)
							(mid 0.249642 -0.249642)
							(end 0.1778 -0.2794)
						)
					)
					(width 0)
					(fill yes)
				)
			)
		)
		(pad "2" smd custom
			(at 0 0.4445 90)
			(size 0.1397 0.1397)
			(layers "F.Cu" "F.Mask" "F.Paste")
			(net "SW_HDD_P32")
			(options
				(clearance outline)
				(anchor circle)
			)
			(primitives
				(gr_poly
					(pts
						(arc
							(start -0.1778 -0.2794)
							(mid -0.249642 -0.249642)
							(end -0.2794 -0.1778)
						)
						(arc
							(start -0.2794 0.1778)
							(mid -0.249642 0.249642)
							(end -0.1778 0.2794)
						)
						(arc
							(start 0.1778 0.2794)
							(mid 0.249642 0.249642)
							(end 0.2794 0.1778)
						)
						(arc
							(start 0.2794 -0.1778)
							(mid 0.249642 -0.249642)
							(end 0.1778 -0.2794)
						)
					)
					(width 0)
					(fill yes)
				)
			)
		)
	)
	(footprint ""
		(layer "F.Cu")
		(at 66.313812 -269.705074)
		(property "Reference" "TP26"
			(at 0 0 0)
			(layer "F.SilkS")
			(hide yes)
			(effects
				(font
					(size 1.27 1.27)
				)
			)
		)
		(property "Value" "*"
			(at -0.0508 -1.6764 0)
			(unlocked yes)
			(layer "F.Fab")
			(hide yes)
			(effects
				(font
					(size 1.016 1.016)
					(thickness 0.1524)
				)
			)
		)
		(property "Device Type" "TPAD32"
			(at -0.0508 -3.2004 0)
			(unlocked yes)
			(layer "F.Fab")
			(hide yes)
			(effects
				(font
					(size 1.016 1.016)
					(thickness 0.1524)
				)
			)
		)
		(duplicate_pad_numbers_are_jumpers no)
		(fp_poly
			(pts
				(arc
					(start 0.4064 0)
					(mid -0.4064 0)
					(end 0.4064 0)
				)
			)
			(stroke
				(width 0)
				(type default)
			)
			(fill no)
			(layer "F.CrtYd")
		)
		(fp_poly
			(pts
				(arc
					(start 0.7112 0)
					(mid -0.7112 0)
					(end 0.7112 0)
				)
			)
			(stroke
				(width 0)
				(type default)
			)
			(fill no)
			(layer "F.Fab")
		)
		(pad "1" smd circle
			(at 0 0)
			(size 0.8128 0.8128)
			(layers "F.Cu" "F.Mask" "F.Paste")
			(net "ACT_HDD_1")
		)
	)
	(footprint ""
		(layer "F.Cu")
		(at 456.674982 -178.799998)
		(property "Reference" ""
			(at 0 0 0)
			(layer "F.SilkS")
			(hide yes)
			(effects
				(font
					(size 1.27 1.27)
				)
			)
		)
		(property "Value" "*"
			(at -8.398764 -8.057642 0)
			(unlocked yes)
			(layer "F.Fab")
			(hide yes)
			(effects
				(font
					(size 1.016 1.016)
					(thickness 0.1524)
				)
			)
		)
		(duplicate_pad_numbers_are_jumpers no)
		(fp_poly
			(pts
				(arc
					(start 7.3152 0)
					(mid 0 7.3152)
					(end -7.3152 0)
				)
				(arc
					(start -7.3152 -5.9944)
					(mid 0 -13.3096)
					(end 7.3152 -5.9944)
				)
			)
			(stroke
				(width 0)
				(type default)
			)
			(fill no)
			(layer "B.CrtYd")
		)
		(fp_poly
			(pts
				(arc
					(start 7.3152 0)
					(mid 0 7.3152)
					(end -7.3152 0)
				)
				(arc
					(start -7.3152 -5.9944)
					(mid 0 -13.3096)
					(end 7.3152 -5.9944)
				)
			)
			(stroke
				(width 0)
				(type default)
			)
			(fill no)
			(layer "F.CrtYd")
		)
		(fp_poly
			(pts
				(arc
					(start 7.3152 0)
					(mid 0 7.3152)
					(end -7.3152 0)
				)
				(arc
					(start -7.3152 -5.9944)
					(mid 0 -13.3096)
					(end 7.3152 -5.9944)
				)
			)
			(stroke
				(width 0)
				(type default)
			)
			(fill no)
			(layer "B.Fab")
		)
		(fp_poly
			(pts
				(arc
					(start 7.3152 0)
					(mid 0 7.3152)
					(end -7.3152 0)
				)
				(arc
					(start -7.3152 -5.9944)
					(mid 0 -13.3096)
					(end 7.3152 -5.9944)
				)
			)
			(stroke
				(width 0)
				(type default)
			)
			(fill no)
			(layer "F.Fab")
		)
		(pad "1" thru_hole oval
			(at 0 0)
			(size 14.0208 20.0152)
			(drill 0.0254
				(offset 0 -2.9972)
			)
			(layers "*.Cu" "*.Mask")
			(remove_unused_layers no)
			(net "Net_42")
			(clearance -1.002284)
			(thermal_gap 0.1524)
			(padstack
				(mode front_inner_back)
				(layer "Inner"
					(shape custom)
					(size 2.928012 2.928012)
					(options
						(anchor circle)
					)
					(primitives
						(gr_poly
							(pts
								(arc
									(start 4.571746 -2.084324)
									(mid 0.000333 7.430372)
									(end -4.571492 -2.084324)
								)
								(arc
									(start -4.571492 -2.084324)
									(mid -3.570296 -3.611977)
									(end -2.875026 -5.30098)
								)
								(arc
									(start -2.875026 -5.30098)
									(mid 0.000217 -7.43089)
									(end 2.87528 -5.30098)
								)
								(arc
									(start 2.87528 -5.30098)
									(mid 3.570511 -3.611956)
									(end 4.571746 -2.084324)
								)
							)
							(width 0)
							(fill yes)
						)
					)
					(clearance 0.1524)
				)
				(layer "B.Cu"
					(shape oval)
					(size 14.0208 20.0152)
					(offset 0 -2.9972)
					(clearance -1.002284)
				)
			)
		)
		(zone
			(layers "F.Cu" "B.Cu" "In1.Cu" "In2.Cu" "In3.Cu" "In4.Cu" "In5.Cu" "In6.Cu")
			(hatch none 0.5)
			(connect_pads
				(clearance 0)
			)
			(min_thickness 0.25)
			(keepout
				(tracks not_allowed)
				(vias allowed)
				(pads allowed)
				(copperpour not_allowed)
				(footprints allowed)
			)
			(placement
				(enabled no)
				(sheetname "")
			)
			(fill
				(thermal_gap 0.5)
				(thermal_bridge_width 0.5)
				(island_removal_mode 0)
			)
			(polygon
				(pts
					(arc
						(start 449.664582 -184.794398)
						(mid 456.674982 -191.804798)
						(end 463.685382 -184.794398)
					)
					(arc
						(start 463.685382 -178.799998)
						(mid 456.674982 -171.789598)
						(end 449.664582 -178.799998)
					)
				)
			)
		)
	)
	(footprint ""
		(layer "F.Cu")
		(at 331.089 -12.827 -90)
		(property "Reference" "Q155"
			(at 0 0 270)
			(layer "F.SilkS")
			(hide yes)
			(effects
				(font
					(size 1.27 1.27)
				)
			)
		)
		(property "Value" "2N7002KDW-GP"
			(at -2.3622 -8.2042 270)
			(unlocked yes)
			(layer "F.Fab")
			(hide yes)
			(effects
				(font
					(size 1.016 1.016)
					(thickness 0.1524)
				)
			)
		)
		(property "Device Type" "SOT-363H44"
			(at -2.3622 -10.1092 270)
			(unlocked yes)
			(layer "F.Fab")
			(hide yes)
			(effects
				(font
					(size 1.016 1.016)
					(thickness 0.1524)
				)
			)
		)
		(duplicate_pad_numbers_are_jumpers no)
		(fp_line
			(start -1.4478 1.7018)
			(end 1.4478 1.7018)
			(stroke
				(width 0.1524)
				(type default)
			)
			(layer "F.SilkS")
		)
		(fp_line
			(start 1.4478 1.7018)
			(end 1.4478 -1.7018)
			(stroke
				(width 0.1524)
				(type default)
			)
			(layer "F.SilkS")
		)
		(fp_line
			(start -1.27 1.524)
			(end -1.27 0.6604)
			(stroke
				(width 0.4826)
				(type default)
			)
			(layer "F.SilkS")
		)
		(fp_line
			(start -1.4478 -1.7018)
			(end -1.4478 1.7018)
			(stroke
				(width 0.1524)
				(type default)
			)
			(layer "F.SilkS")
		)
		(fp_line
			(start 1.4478 -1.7018)
			(end -1.4478 -1.7018)
			(stroke
				(width 0.1524)
				(type default)
			)
			(layer "F.SilkS")
		)
		(fp_poly
			(pts
				(xy -1.524 -1.778) (xy 1.524 -1.778) (xy 1.524 1.778) (xy -1.524 1.778)
			)
			(stroke
				(width 0)
				(type default)
			)
			(fill no)
			(layer "F.CrtYd")
		)
		(fp_poly
			(pts
				(xy -1.524 -1.778) (xy 1.524 -1.778) (xy 1.524 1.778) (xy -1.524 1.778)
			)
			(stroke
				(width 0)
				(type default)
			)
			(fill no)
			(layer "F.Fab")
		)
		(pad "1" smd rect
			(at -0.65024 0.9398 270)
			(size 0.4064 1.016)
			(layers "F.Cu" "F.Mask" "F.Paste")
			(net "GND")
		)
		(pad "2" smd rect
			(at 0 0.9398 270)
			(size 0.4064 1.016)
			(layers "F.Cu" "F.Mask" "F.Paste")
			(net "SW_PWR_R_HDD30")
		)
		(pad "3" smd rect
			(at 0.65024 0.9398 270)
			(size 0.4064 1.016)
			(layers "F.Cu" "F.Mask" "F.Paste")
			(net "SW_HDD_P30")
		)
		(pad "4" smd rect
			(at 0.65024 -0.9398 270)
			(size 0.4064 1.016)
			(layers "F.Cu" "F.Mask" "F.Paste")
			(net "GND")
		)
		(pad "5" smd rect
			(at 0 -0.9398 270)
			(size 0.4064 1.016)
			(layers "F.Cu" "F.Mask" "F.Paste")
			(net "SW_HDD_G30")
		)
		(pad "6" smd rect
			(at -0.65024 -0.9398 270)
			(size 0.4064 1.016)
			(layers "F.Cu" "F.Mask" "F.Paste")
			(net "SW_HDD_R30")
		)
	)
	(footprint ""
		(layer "F.Cu")
		(at 95.563436 -129.66065 90)
		(property "Reference" "C211"
			(at 0 0 90)
			(layer "F.SilkS")
			(hide yes)
			(effects
				(font
					(size 1.27 1.27)
				)
			)
		)
		(property "Value" "SCD01U16V1KX-GP"
			(at -2.8321 -1.7399 90)
			(unlocked yes)
			(layer "F.Fab")
			(hide yes)
			(effects
				(font
					(size 1.016 1.016)
					(thickness 0.1524)
				)
			)
		)
		(property "Device Type" "C0201H13"
			(at -2.8321 -3.2639 90)
			(unlocked yes)
			(layer "F.Fab")
			(hide yes)
			(effects
				(font
					(size 1.016 1.016)
					(thickness 0.1524)
				)
			)
		)
		(duplicate_pad_numbers_are_jumpers no)
		(fp_rect
			(start -0.2794 0.6477)
			(end 0.2794 -0.6477)
			(stroke
				(width 0)
				(type default)
			)
			(fill no)
			(layer "F.CrtYd")
		)
		(fp_rect
			(start -0.2794 0.6477)
			(end 0.2794 -0.6477)
			(stroke
				(width 0)
				(type default)
			)
			(fill no)
			(layer "F.Fab")
		)
		(pad "1" smd custom
			(at 0 -0.2794 90)
			(size 0.0762 0.0762)
			(layers "F.Cu" "F.Mask" "F.Paste")
			(net "SAS_HDD_RX_P14")
			(options
				(clearance outline)
				(anchor circle)
			)
			(primitives
				(gr_poly
					(pts
						(arc
							(start 0.1524 -0.127)
							(mid 0.137521 -0.162921)
							(end 0.1016 -0.1778)
						)
						(arc
							(start -0.1016 -0.1778)
							(mid -0.137521 -0.162921)
							(end -0.1524 -0.127)
						)
						(arc
							(start -0.1524 0.127)
							(mid -0.137521 0.162921)
							(end -0.1016 0.1778)
						)
						(arc
							(start 0.1016 0.1778)
							(mid 0.137521 0.162921)
							(end 0.1524 0.127)
						)
					)
					(width 0)
					(fill yes)
				)
			)
		)
		(pad "2" smd custom
			(at 0 0.2794 90)
			(size 0.0762 0.0762)
			(layers "F.Cu" "F.Mask" "F.Paste")
			(net "PHY_SCC_B_TO_DRV_B_14_DP")
			(options
				(clearance outline)
				(anchor circle)
			)
			(primitives
				(gr_poly
					(pts
						(arc
							(start 0.1524 -0.127)
							(mid 0.137521 -0.162921)
							(end 0.1016 -0.1778)
						)
						(arc
							(start -0.1016 -0.1778)
							(mid -0.137521 -0.162921)
							(end -0.1524 -0.127)
						)
						(arc
							(start -0.1524 0.127)
							(mid -0.137521 0.162921)
							(end -0.1016 0.1778)
						)
						(arc
							(start 0.1016 0.1778)
							(mid 0.137521 0.162921)
							(end 0.1524 0.127)
						)
					)
					(width 0)
					(fill yes)
				)
			)
		)
	)
	(footprint ""
		(layer "F.Cu")
		(at 441.162186 -120.321578 -90)
		(property "Reference" "R1157"
			(at 0 0 270)
			(layer "F.SilkS")
			(hide yes)
			(effects
				(font
					(size 1.27 1.27)
				)
			)
		)
		(property "Value" "10KR2F-2-GP"
			(at 0.064008 -3.993896 270)
			(unlocked yes)
			(layer "F.Fab")
			(hide yes)
			(effects
				(font
					(size 1.016 1.016)
					(thickness 0.1524)
				)
			)
		)
		(property "Device Type" "R402H16"
			(at 0.064008 -5.517896 270)
			(unlocked yes)
			(layer "F.Fab")
			(hide yes)
			(effects
				(font
					(size 1.016 1.016)
					(thickness 0.1524)
				)
			)
		)
		(duplicate_pad_numbers_are_jumpers no)
		(fp_line
			(start -0.508 -0.9398)
			(end -0.508 0.9398)
			(stroke
				(width 0.1524)
				(type default)
			)
			(layer "F.SilkS")
		)
		(fp_line
			(start 0.508 -0.9398)
			(end -0.508 -0.9398)
			(stroke
				(width 0.1524)
				(type default)
			)
			(layer "F.SilkS")
		)
		(fp_rect
			(start -0.508 0.9398)
			(end 0.508 -0.9398)
			(stroke
				(width 0)
				(type default)
			)
			(fill no)
			(layer "F.CrtYd")
		)
		(fp_rect
			(start -0.508 0.9398)
			(end 0.508 -0.9398)
			(stroke
				(width 0)
				(type default)
			)
			(fill no)
			(layer "F.Fab")
		)
		(pad "1" smd custom
			(at 0 -0.4445 270)
			(size 0.1397 0.1397)
			(layers "F.Cu" "F.Mask" "F.Paste")
			(net "P5V_B_4_EN_R")
			(options
				(clearance outline)
				(anchor circle)
			)
			(primitives
				(gr_poly
					(pts
						(arc
							(start -0.1778 -0.2794)
							(mid -0.249642 -0.249642)
							(end -0.2794 -0.1778)
						)
						(arc
							(start -0.2794 0.1778)
							(mid -0.249642 0.249642)
							(end -0.1778 0.2794)
						)
						(arc
							(start 0.1778 0.2794)
							(mid 0.249642 0.249642)
							(end 0.2794 0.1778)
						)
						(arc
							(start 0.2794 -0.1778)
							(mid 0.249642 -0.249642)
							(end 0.1778 -0.2794)
						)
					)
					(width 0)
					(fill yes)
				)
			)
		)
		(pad "2" smd custom
			(at 0 0.4445 270)
			(size 0.1397 0.1397)
			(layers "F.Cu" "F.Mask" "F.Paste")
			(net "GND")
			(options
				(clearance outline)
				(anchor circle)
			)
			(primitives
				(gr_poly
					(pts
						(arc
							(start -0.1778 -0.2794)
							(mid -0.249642 -0.249642)
							(end -0.2794 -0.1778)
						)
						(arc
							(start -0.2794 0.1778)
							(mid -0.249642 0.249642)
							(end -0.1778 0.2794)
						)
						(arc
							(start 0.1778 0.2794)
							(mid 0.249642 0.249642)
							(end 0.2794 0.1778)
						)
						(arc
							(start 0.2794 -0.1778)
							(mid 0.249642 -0.249642)
							(end 0.1778 -0.2794)
						)
					)
					(width 0)
					(fill yes)
				)
			)
		)
	)
	(footprint ""
		(layer "F.Cu")
		(at 261.75081 -224.785174)
		(property "Reference" "R169"
			(at 0 0 0)
			(layer "F.SilkS")
			(hide yes)
			(effects
				(font
					(size 1.27 1.27)
				)
			)
		)
		(property "Value" "10KR2F-2-GP"
			(at 0.064008 -3.993896 0)
			(unlocked yes)
			(layer "F.Fab")
			(hide yes)
			(effects
				(font
					(size 1.016 1.016)
					(thickness 0.1524)
				)
			)
		)
		(property "Device Type" "R402H16"
			(at 0.064008 -5.517896 0)
			(unlocked yes)
			(layer "F.Fab")
			(hide yes)
			(effects
				(font
					(size 1.016 1.016)
					(thickness 0.1524)
				)
			)
		)
		(duplicate_pad_numbers_are_jumpers no)
		(fp_line
			(start -0.508 -0.9398)
			(end -0.508 0.9398)
			(stroke
				(width 0.1524)
				(type default)
			)
			(layer "F.SilkS")
		)
		(fp_line
			(start 0.508 -0.9398)
			(end -0.508 -0.9398)
			(stroke
				(width 0.1524)
				(type default)
			)
			(layer "F.SilkS")
		)
		(fp_rect
			(start -0.508 0.9398)
			(end 0.508 -0.9398)
			(stroke
				(width 0)
				(type default)
			)
			(fill no)
			(layer "F.CrtYd")
		)
		(fp_rect
			(start -0.508 0.9398)
			(end 0.508 -0.9398)
			(stroke
				(width 0)
				(type default)
			)
			(fill no)
			(layer "F.Fab")
		)
		(pad "1" smd custom
			(at 0 -0.4445)
			(size 0.1397 0.1397)
			(layers "F.Cu" "F.Mask" "F.Paste")
			(net "P5V_B_4_SENSE")
			(options
				(clearance outline)
				(anchor circle)
			)
			(primitives
				(gr_poly
					(pts
						(arc
							(start -0.1778 -0.2794)
							(mid -0.249642 -0.249642)
							(end -0.2794 -0.1778)
						)
						(arc
							(start -0.2794 0.1778)
							(mid -0.249642 0.249642)
							(end -0.1778 0.2794)
						)
						(arc
							(start 0.1778 0.2794)
							(mid 0.249642 0.249642)
							(end 0.2794 0.1778)
						)
						(arc
							(start 0.2794 -0.1778)
							(mid 0.249642 -0.249642)
							(end 0.1778 -0.2794)
						)
					)
					(width 0)
					(fill yes)
				)
			)
		)
		(pad "2" smd custom
			(at 0 0.4445)
			(size 0.1397 0.1397)
			(layers "F.Cu" "F.Mask" "F.Paste")
			(net "GND")
			(options
				(clearance outline)
				(anchor circle)
			)
			(primitives
				(gr_poly
					(pts
						(arc
							(start -0.1778 -0.2794)
							(mid -0.249642 -0.249642)
							(end -0.2794 -0.1778)
						)
						(arc
							(start -0.2794 0.1778)
							(mid -0.249642 0.249642)
							(end -0.1778 0.2794)
						)
						(arc
							(start 0.1778 0.2794)
							(mid 0.249642 0.249642)
							(end 0.2794 0.1778)
						)
						(arc
							(start 0.2794 -0.1778)
							(mid 0.249642 -0.249642)
							(end 0.1778 -0.2794)
						)
					)
					(width 0)
					(fill yes)
				)
			)
		)
	)
	(footprint ""
		(layer "F.Cu")
		(at 473.964 -150.622 90)
		(property "Reference" "R600"
			(at 0 0 90)
			(layer "F.SilkS")
			(hide yes)
			(effects
				(font
					(size 1.27 1.27)
				)
			)
		)
		(property "Value" "2R6F-GP"
			(at -0.0508 -4.8514 90)
			(unlocked yes)
			(layer "F.Fab")
			(hide yes)
			(effects
				(font
					(size 1.016 1.016)
					(thickness 0.1524)
				)
			)
		)
		(property "Device Type" "R1206H26"
			(at 0 -6.3754 90)
			(unlocked yes)
			(layer "F.Fab")
			(hide yes)
			(effects
				(font
					(size 1.016 1.016)
					(thickness 0.1524)
				)
			)
		)
		(duplicate_pad_numbers_are_jumpers no)
		(fp_line
			(start 1.016 -2.2352)
			(end 1.016 2.2352)
			(stroke
				(width 0.1524)
				(type default)
			)
			(layer "F.SilkS")
		)
		(fp_line
			(start -1.016 -2.2352)
			(end 1.016 -2.2352)
			(stroke
				(width 0.1524)
				(type default)
			)
			(layer "F.SilkS")
		)
		(fp_line
			(start 1.016 2.2352)
			(end -1.016 2.2352)
			(stroke
				(width 0.1524)
				(type default)
			)
			(layer "F.SilkS")
		)
		(fp_line
			(start -1.016 2.2352)
			(end -1.016 -2.2352)
			(stroke
				(width 0.1524)
				(type default)
			)
			(layer "F.SilkS")
		)
		(fp_rect
			(start -1.0922 2.3114)
			(end 1.0922 -2.3114)
			(stroke
				(width 0)
				(type default)
			)
			(fill no)
			(layer "F.CrtYd")
		)
		(fp_poly
			(pts
				(xy -1.0922 -2.3114) (xy 1.0922 -2.3114) (xy 1.0922 2.3114) (xy -1.0922 2.3114)
			)
			(stroke
				(width 0)
				(type default)
			)
			(fill no)
			(layer "F.Fab")
		)
		(pad "1" smd rect
			(at 0 -1.397 90)
			(size 1.651 1.27)
			(layers "F.Cu" "F.Mask" "F.Paste")
			(net "P12V_HDD23")
		)
		(pad "2" smd rect
			(at 0 1.397 90)
			(size 1.651 1.27)
			(layers "F.Cu" "F.Mask" "F.Paste")
			(net "12V_PRE_23")
		)
	)
	(footprint ""
		(layer "F.Cu")
		(at 161.544 -262.128 90)
		(property "Reference" "C89"
			(at 0 0 90)
			(layer "F.SilkS")
			(hide yes)
			(effects
				(font
					(size 1.27 1.27)
				)
			)
		)
		(property "Value" "SCD01U50V2KX-1GP"
			(at 1.1811 -2.7051 90)
			(unlocked yes)
			(layer "F.Fab")
			(hide yes)
			(effects
				(font
					(size 1.016 1.016)
					(thickness 0.1524)
				)
			)
		)
		(property "Device Type" "C402H22"
			(at 1.1811 -4.2291 90)
			(unlocked yes)
			(layer "F.Fab")
			(hide yes)
			(effects
				(font
					(size 1.016 1.016)
					(thickness 0.1524)
				)
			)
		)
		(duplicate_pad_numbers_are_jumpers no)
		(fp_rect
			(start -0.4318 0.9525)
			(end 0.4318 -0.9525)
			(stroke
				(width 0)
				(type default)
			)
			(fill no)
			(layer "F.CrtYd")
		)
		(fp_rect
			(start -0.4318 0.9525)
			(end 0.4318 -0.9525)
			(stroke
				(width 0)
				(type default)
			)
			(fill no)
			(layer "F.Fab")
		)
		(pad "1" smd custom
			(at 0 -0.4445 90)
			(size 0.1524 0.1524)
			(layers "F.Cu" "F.Mask" "F.Paste")
			(net "HDD_PRSNT_4")
			(options
				(clearance outline)
				(anchor circle)
			)
			(primitives
				(gr_poly
					(pts
						(arc
							(start 0.3048 -0.2032)
							(mid 0.275042 -0.275042)
							(end 0.2032 -0.3048)
						)
						(arc
							(start -0.2032 -0.3048)
							(mid -0.275042 -0.275042)
							(end -0.3048 -0.2032)
						)
						(arc
							(start -0.3048 0.2032)
							(mid -0.275042 0.275042)
							(end -0.2032 0.3048)
						)
						(arc
							(start 0.2032 0.3048)
							(mid 0.275042 0.275042)
							(end 0.3048 0.2032)
						)
					)
					(width 0)
					(fill yes)
				)
			)
		)
		(pad "2" smd custom
			(at 0 0.4445 90)
			(size 0.1524 0.1524)
			(layers "F.Cu" "F.Mask" "F.Paste")
			(net "GND")
			(options
				(clearance outline)
				(anchor circle)
			)
			(primitives
				(gr_poly
					(pts
						(arc
							(start 0.3048 -0.2032)
							(mid 0.275042 -0.275042)
							(end 0.2032 -0.3048)
						)
						(arc
							(start -0.2032 -0.3048)
							(mid -0.275042 -0.275042)
							(end -0.3048 -0.2032)
						)
						(arc
							(start -0.3048 0.2032)
							(mid -0.275042 0.275042)
							(end -0.2032 0.3048)
						)
						(arc
							(start 0.2032 0.3048)
							(mid 0.275042 0.275042)
							(end 0.3048 0.2032)
						)
					)
					(width 0)
					(fill yes)
				)
			)
		)
	)
	(footprint ""
		(layer "F.Cu")
		(at 456.674982 -63.79972)
		(property "Reference" ""
			(at 0 0 0)
			(layer "F.SilkS")
			(hide yes)
			(effects
				(font
					(size 1.27 1.27)
				)
			)
		)
		(property "Value" "*"
			(at -8.398764 -8.057642 0)
			(unlocked yes)
			(layer "F.Fab")
			(hide yes)
			(effects
				(font
					(size 1.016 1.016)
					(thickness 0.1524)
				)
			)
		)
		(duplicate_pad_numbers_are_jumpers no)
		(fp_poly
			(pts
				(arc
					(start 7.3152 0)
					(mid 0 7.3152)
					(end -7.3152 0)
				)
				(arc
					(start -7.3152 -5.9944)
					(mid 0 -13.3096)
					(end 7.3152 -5.9944)
				)
			)
			(stroke
				(width 0)
				(type default)
			)
			(fill no)
			(layer "B.CrtYd")
		)
		(fp_poly
			(pts
				(arc
					(start 7.3152 0)
					(mid 0 7.3152)
					(end -7.3152 0)
				)
				(arc
					(start -7.3152 -5.9944)
					(mid 0 -13.3096)
					(end 7.3152 -5.9944)
				)
			)
			(stroke
				(width 0)
				(type default)
			)
			(fill no)
			(layer "F.CrtYd")
		)
		(fp_poly
			(pts
				(arc
					(start 7.3152 0)
					(mid 0 7.3152)
					(end -7.3152 0)
				)
				(arc
					(start -7.3152 -5.9944)
					(mid 0 -13.3096)
					(end 7.3152 -5.9944)
				)
			)
			(stroke
				(width 0)
				(type default)
			)
			(fill no)
			(layer "B.Fab")
		)
		(fp_poly
			(pts
				(arc
					(start 7.3152 0)
					(mid 0 7.3152)
					(end -7.3152 0)
				)
				(arc
					(start -7.3152 -5.9944)
					(mid 0 -13.3096)
					(end 7.3152 -5.9944)
				)
			)
			(stroke
				(width 0)
				(type default)
			)
			(fill no)
			(layer "F.Fab")
		)
		(pad "1" thru_hole oval
			(at 0 0)
			(size 14.0208 20.0152)
			(drill 0.0254
				(offset 0 -2.9972)
			)
			(layers "*.Cu" "*.Mask")
			(remove_unused_layers no)
			(net "Net_14")
			(clearance -1.002284)
			(thermal_gap 0.1524)
			(padstack
				(mode front_inner_back)
				(layer "Inner"
					(shape custom)
					(size 2.928012 2.928012)
					(options
						(anchor circle)
					)
					(primitives
						(gr_poly
							(pts
								(arc
									(start 4.571746 -2.084324)
									(mid 0.000333 7.430372)
									(end -4.571492 -2.084324)
								)
								(arc
									(start -4.571492 -2.084324)
									(mid -3.570296 -3.611977)
									(end -2.875026 -5.30098)
								)
								(arc
									(start -2.875026 -5.30098)
									(mid 0.000217 -7.43089)
									(end 2.87528 -5.30098)
								)
								(arc
									(start 2.87528 -5.30098)
									(mid 3.570511 -3.611956)
									(end 4.571746 -2.084324)
								)
							)
							(width 0)
							(fill yes)
						)
					)
					(clearance 0.1524)
				)
				(layer "B.Cu"
					(shape oval)
					(size 14.0208 20.0152)
					(offset 0 -2.9972)
					(clearance -1.002284)
				)
			)
		)
		(zone
			(layers "F.Cu" "B.Cu" "In1.Cu" "In2.Cu" "In3.Cu" "In4.Cu" "In5.Cu" "In6.Cu")
			(hatch none 0.5)
			(connect_pads
				(clearance 0)
			)
			(min_thickness 0.25)
			(keepout
				(tracks not_allowed)
				(vias allowed)
				(pads allowed)
				(copperpour not_allowed)
				(footprints allowed)
			)
			(placement
				(enabled no)
				(sheetname "")
			)
			(fill
				(thermal_gap 0.5)
				(thermal_bridge_width 0.5)
				(island_removal_mode 0)
			)
			(polygon
				(pts
					(arc
						(start 449.664582 -69.79412)
						(mid 456.674982 -76.80452)
						(end 463.685382 -69.79412)
					)
					(arc
						(start 463.685382 -63.79972)
						(mid 456.674982 -56.78932)
						(end 449.664582 -63.79972)
					)
				)
			)
		)
	)
	(footprint ""
		(layer "F.Cu")
		(at 320.6496 -261.62 180)
		(property "Reference" "R255"
			(at 0 0 180)
			(layer "F.SilkS")
			(hide yes)
			(effects
				(font
					(size 1.27 1.27)
				)
			)
		)
		(property "Value" "10KR2F-2-GP"
			(at 0.064008 -3.993896 180)
			(unlocked yes)
			(layer "F.Fab")
			(hide yes)
			(effects
				(font
					(size 1.016 1.016)
					(thickness 0.1524)
				)
			)
		)
		(property "Device Type" "R402H16"
			(at 0.064008 -5.517896 180)
			(unlocked yes)
			(layer "F.Fab")
			(hide yes)
			(effects
				(font
					(size 1.016 1.016)
					(thickness 0.1524)
				)
			)
		)
		(duplicate_pad_numbers_are_jumpers no)
		(fp_line
			(start 0.508 -0.9398)
			(end -0.508 -0.9398)
			(stroke
				(width 0.1524)
				(type default)
			)
			(layer "F.SilkS")
		)
		(fp_line
			(start -0.508 -0.9398)
			(end -0.508 0.9398)
			(stroke
				(width 0.1524)
				(type default)
			)
			(layer "F.SilkS")
		)
		(fp_rect
			(start -0.508 0.9398)
			(end 0.508 -0.9398)
			(stroke
				(width 0)
				(type default)
			)
			(fill no)
			(layer "F.CrtYd")
		)
		(fp_rect
			(start -0.508 0.9398)
			(end 0.508 -0.9398)
			(stroke
				(width 0)
				(type default)
			)
			(fill no)
			(layer "F.Fab")
		)
		(pad "1" smd custom
			(at 0 -0.4445 180)
			(size 0.1397 0.1397)
			(layers "F.Cu" "F.Mask" "F.Paste")
			(net "P3V3_STBY_B")
			(options
				(clearance outline)
				(anchor circle)
			)
			(primitives
				(gr_poly
					(pts
						(arc
							(start -0.1778 -0.2794)
							(mid -0.249642 -0.249642)
							(end -0.2794 -0.1778)
						)
						(arc
							(start -0.2794 0.1778)
							(mid -0.249642 0.249642)
							(end -0.1778 0.2794)
						)
						(arc
							(start 0.1778 0.2794)
							(mid 0.249642 0.249642)
							(end 0.2794 0.1778)
						)
						(arc
							(start 0.2794 -0.1778)
							(mid 0.249642 -0.249642)
							(end 0.1778 -0.2794)
						)
					)
					(width 0)
					(fill yes)
				)
			)
		)
		(pad "2" smd custom
			(at 0 0.4445 180)
			(size 0.1397 0.1397)
			(layers "F.Cu" "F.Mask" "F.Paste")
			(net "HDD_PRSNT_6")
			(options
				(clearance outline)
				(anchor circle)
			)
			(primitives
				(gr_poly
					(pts
						(arc
							(start -0.1778 -0.2794)
							(mid -0.249642 -0.249642)
							(end -0.2794 -0.1778)
						)
						(arc
							(start -0.2794 0.1778)
							(mid -0.249642 0.249642)
							(end -0.1778 0.2794)
						)
						(arc
							(start 0.1778 0.2794)
							(mid 0.249642 0.249642)
							(end 0.2794 0.1778)
						)
						(arc
							(start 0.2794 -0.1778)
							(mid 0.249642 -0.249642)
							(end 0.1778 -0.2794)
						)
					)
					(width 0)
					(fill yes)
				)
			)
		)
	)
	(footprint ""
		(layer "F.Cu")
		(at 86.995 -42.291)
		(property "Reference" "C373"
			(at 0 0 0)
			(layer "F.SilkS")
			(hide yes)
			(effects
				(font
					(size 1.27 1.27)
				)
			)
		)
		(property "Value" "SC4D7U25V5KX-1-GP"
			(at -0.0762 -6.1214 0)
			(unlocked yes)
			(layer "F.Fab")
			(hide yes)
			(effects
				(font
					(size 1.016 1.016)
					(thickness 0.1524)
				)
			)
		)
		(property "Device Type" "C805H58"
			(at -0.0762 -8.1534 0)
			(unlocked yes)
			(layer "F.Fab")
			(hide yes)
			(effects
				(font
					(size 1.016 1.016)
					(thickness 0.1524)
				)
			)
		)
		(duplicate_pad_numbers_are_jumpers no)
		(fp_line
			(start 0.635 0)
			(end -0.635 0)
			(stroke
				(width 0.508)
				(type default)
			)
			(layer "F.SilkS")
		)
		(fp_rect
			(start -0.9652 1.778)
			(end 0.9652 -1.778)
			(stroke
				(width 0)
				(type default)
			)
			(fill no)
			(layer "F.CrtYd")
		)
		(fp_poly
			(pts
				(xy -0.9652 -1.778) (xy 0.9652 -1.778) (xy 0.9652 1.778) (xy -0.9652 1.778)
			)
			(stroke
				(width 0)
				(type default)
			)
			(fill no)
			(layer "F.Fab")
		)
		(pad "1" smd rect
			(at 0 -0.9652)
			(size 1.397 1.143)
			(layers "F.Cu" "F.Mask" "F.Paste")
			(net "P12V_HDD26")
		)
		(pad "2" smd rect
			(at 0 0.9652)
			(size 1.397 1.143)
			(layers "F.Cu" "F.Mask" "F.Paste")
			(net "GND")
		)
	)
	(footprint ""
		(layer "F.Cu")
		(at 472.899994 -65.39992)
		(property "Reference" "LED24"
			(at 0 0 0)
			(layer "F.SilkS")
			(hide yes)
			(effects
				(font
					(size 1.27 1.27)
				)
			)
		)
		(property "Value" "LED-BY-19-GP"
			(at -2.132076 1.414018 0)
			(unlocked yes)
			(layer "F.Fab")
			(hide yes)
			(effects
				(font
					(size 1.016 1.016)
					(thickness 0.1524)
				)
			)
		)
		(property "Device Type" "LED-1615-4PH26"
			(at -2.132076 -0.109982 0)
			(unlocked yes)
			(layer "F.Fab")
			(hide yes)
			(effects
				(font
					(size 1.016 1.016)
					(thickness 0.1524)
				)
			)
		)
		(duplicate_pad_numbers_are_jumpers no)
		(fp_line
			(start -1.2954 0.254)
			(end -1.2954 1.6002)
			(stroke
				(width 0.508)
				(type default)
			)
			(layer "F.SilkS")
		)
		(fp_line
			(start -1.2954 1.6002)
			(end 1.2954 1.6002)
			(stroke
				(width 0.508)
				(type default)
			)
			(layer "F.SilkS")
		)
		(fp_line
			(start -1.1176 -1.4224)
			(end 1.1176 -1.4224)
			(stroke
				(width 0.1524)
				(type default)
			)
			(layer "F.SilkS")
		)
		(fp_line
			(start -1.1176 1.4224)
			(end -1.1176 -1.4224)
			(stroke
				(width 0.1524)
				(type default)
			)
			(layer "F.SilkS")
		)
		(fp_line
			(start 1.1176 -1.4224)
			(end 1.1176 1.4224)
			(stroke
				(width 0.1524)
				(type default)
			)
			(layer "F.SilkS")
		)
		(fp_line
			(start 1.1176 1.4224)
			(end -1.1176 1.4224)
			(stroke
				(width 0.1524)
				(type default)
			)
			(layer "F.SilkS")
		)
		(fp_line
			(start 1.2954 1.6002)
			(end 1.2954 0.254)
			(stroke
				(width 0.508)
				(type default)
			)
			(layer "F.SilkS")
		)
		(fp_rect
			(start -0.7493 0.8001)
			(end 0.7493 -0.8001)
			(stroke
				(width 0)
				(type default)
			)
			(fill no)
			(layer "F.CrtYd")
		)
		(fp_poly
			(pts
				(xy -1.3716 1.6764) (xy -1.3716 -1.6764) (xy 1.3716 -1.6764) (xy 1.3716 0.0635) (xy 0.7493 0.0635)
				(xy 0.7493 -0.8001) (xy -0.7493 -0.8001) (xy -0.7493 0.8001) (xy 0.7493 0.8001) (xy 0.7493 0.0762)
				(xy 1.3716 0.0762) (xy 1.3716 1.6764)
			)
			(stroke
				(width 0)
				(type default)
			)
			(fill no)
			(layer "F.CrtYd")
		)
		(fp_rect
			(start -1.3716 1.6764)
			(end 1.3716 -1.6764)
			(stroke
				(width 0)
				(type default)
			)
			(fill no)
			(layer "F.Fab")
		)
		(pad "1" smd rect
			(at 0.50038 -0.73025)
			(size 0.7112 0.8636)
			(layers "F.Cu" "F.Mask" "F.Paste")
			(net "DRV_ACT_23")
		)
		(pad "2" smd rect
			(at -0.50038 -0.73025)
			(size 0.7112 0.8636)
			(layers "F.Cu" "F.Mask" "F.Paste")
			(net "FLT_HDD23")
		)
		(pad "3" smd rect
			(at 0.50038 0.73025)
			(size 0.7112 0.8636)
			(layers "F.Cu" "F.Mask" "F.Paste")
			(net "DRV_ACT_23_N")
		)
		(pad "4" smd rect
			(at -0.50038 0.73025)
			(size 0.7112 0.8636)
			(layers "F.Cu" "F.Mask" "F.Paste")
			(net "FLT_HDD23_N")
		)
	)
	(footprint ""
		(layer "F.Cu")
		(at 330.67498 -63.79972)
		(property "Reference" ""
			(at 0 0 0)
			(layer "F.SilkS")
			(hide yes)
			(effects
				(font
					(size 1.27 1.27)
				)
			)
		)
		(property "Value" "*"
			(at -8.398764 -8.057642 0)
			(unlocked yes)
			(layer "F.Fab")
			(hide yes)
			(effects
				(font
					(size 1.016 1.016)
					(thickness 0.1524)
				)
			)
		)
		(duplicate_pad_numbers_are_jumpers no)
		(fp_poly
			(pts
				(arc
					(start 7.3152 0)
					(mid 0 7.3152)
					(end -7.3152 0)
				)
				(arc
					(start -7.3152 -5.9944)
					(mid 0 -13.3096)
					(end 7.3152 -5.9944)
				)
			)
			(stroke
				(width 0)
				(type default)
			)
			(fill no)
			(layer "B.CrtYd")
		)
		(fp_poly
			(pts
				(arc
					(start 7.3152 0)
					(mid 0 7.3152)
					(end -7.3152 0)
				)
				(arc
					(start -7.3152 -5.9944)
					(mid 0 -13.3096)
					(end 7.3152 -5.9944)
				)
			)
			(stroke
				(width 0)
				(type default)
			)
			(fill no)
			(layer "F.CrtYd")
		)
		(fp_poly
			(pts
				(arc
					(start 7.3152 0)
					(mid 0 7.3152)
					(end -7.3152 0)
				)
				(arc
					(start -7.3152 -5.9944)
					(mid 0 -13.3096)
					(end 7.3152 -5.9944)
				)
			)
			(stroke
				(width 0)
				(type default)
			)
			(fill no)
			(layer "B.Fab")
		)
		(fp_poly
			(pts
				(arc
					(start 7.3152 0)
					(mid 0 7.3152)
					(end -7.3152 0)
				)
				(arc
					(start -7.3152 -5.9944)
					(mid 0 -13.3096)
					(end 7.3152 -5.9944)
				)
			)
			(stroke
				(width 0)
				(type default)
			)
			(fill no)
			(layer "F.Fab")
		)
		(pad "1" thru_hole oval
			(at 0 0)
			(size 14.0208 20.0152)
			(drill 0.0254
				(offset 0 -2.9972)
			)
			(layers "*.Cu" "*.Mask")
			(remove_unused_layers no)
			(net "Net_50")
			(clearance -1.002284)
			(thermal_gap 0.1524)
			(padstack
				(mode front_inner_back)
				(layer "Inner"
					(shape custom)
					(size 2.928012 2.928012)
					(options
						(anchor circle)
					)
					(primitives
						(gr_poly
							(pts
								(arc
									(start 4.571746 -2.084324)
									(mid 0.000333 7.430372)
									(end -4.571492 -2.084324)
								)
								(arc
									(start -4.571492 -2.084324)
									(mid -3.570296 -3.611977)
									(end -2.875026 -5.30098)
								)
								(arc
									(start -2.875026 -5.30098)
									(mid 0.000217 -7.43089)
									(end 2.87528 -5.30098)
								)
								(arc
									(start 2.87528 -5.30098)
									(mid 3.570511 -3.611956)
									(end 4.571746 -2.084324)
								)
							)
							(width 0)
							(fill yes)
						)
					)
					(clearance 0.1524)
				)
				(layer "B.Cu"
					(shape oval)
					(size 14.0208 20.0152)
					(offset 0 -2.9972)
					(clearance -1.002284)
				)
			)
		)
		(zone
			(layers "F.Cu" "B.Cu" "In1.Cu" "In2.Cu" "In3.Cu" "In4.Cu" "In5.Cu" "In6.Cu")
			(hatch none 0.5)
			(connect_pads
				(clearance 0)
			)
			(min_thickness 0.25)
			(keepout
				(tracks not_allowed)
				(vias allowed)
				(pads allowed)
				(copperpour not_allowed)
				(footprints allowed)
			)
			(placement
				(enabled no)
				(sheetname "")
			)
			(fill
				(thermal_gap 0.5)
				(thermal_bridge_width 0.5)
				(island_removal_mode 0)
			)
			(polygon
				(pts
					(arc
						(start 323.66458 -69.79412)
						(mid 330.67498 -76.80452)
						(end 337.68538 -69.79412)
					)
					(arc
						(start 337.68538 -63.79972)
						(mid 330.67498 -56.78932)
						(end 323.66458 -63.79972)
					)
				)
			)
		)
	)
	(footprint ""
		(layer "F.Cu")
		(at 129.921 -148.082 -90)
		(property "Reference" "R415"
			(at 0 0 270)
			(layer "F.SilkS")
			(hide yes)
			(effects
				(font
					(size 1.27 1.27)
				)
			)
		)
		(property "Value" "10KR2F-2-GP"
			(at 0.064008 -3.993896 270)
			(unlocked yes)
			(layer "F.Fab")
			(hide yes)
			(effects
				(font
					(size 1.016 1.016)
					(thickness 0.1524)
				)
			)
		)
		(property "Device Type" "R402H16"
			(at 0.064008 -5.517896 270)
			(unlocked yes)
			(layer "F.Fab")
			(hide yes)
			(effects
				(font
					(size 1.016 1.016)
					(thickness 0.1524)
				)
			)
		)
		(duplicate_pad_numbers_are_jumpers no)
		(fp_line
			(start -0.508 -0.9398)
			(end -0.508 0.9398)
			(stroke
				(width 0.1524)
				(type default)
			)
			(layer "F.SilkS")
		)
		(fp_line
			(start 0.508 -0.9398)
			(end -0.508 -0.9398)
			(stroke
				(width 0.1524)
				(type default)
			)
			(layer "F.SilkS")
		)
		(fp_rect
			(start -0.508 0.9398)
			(end 0.508 -0.9398)
			(stroke
				(width 0)
				(type default)
			)
			(fill no)
			(layer "F.CrtYd")
		)
		(fp_rect
			(start -0.508 0.9398)
			(end 0.508 -0.9398)
			(stroke
				(width 0)
				(type default)
			)
			(fill no)
			(layer "F.Fab")
		)
		(pad "1" smd custom
			(at 0 -0.4445 270)
			(size 0.1397 0.1397)
			(layers "F.Cu" "F.Mask" "F.Paste")
			(net "P3V3_STBY_B")
			(options
				(clearance outline)
				(anchor circle)
			)
			(primitives
				(gr_poly
					(pts
						(arc
							(start -0.1778 -0.2794)
							(mid -0.249642 -0.249642)
							(end -0.2794 -0.1778)
						)
						(arc
							(start -0.2794 0.1778)
							(mid -0.249642 0.249642)
							(end -0.1778 0.2794)
						)
						(arc
							(start 0.1778 0.2794)
							(mid 0.249642 0.249642)
							(end 0.2794 0.1778)
						)
						(arc
							(start 0.2794 -0.1778)
							(mid 0.249642 -0.249642)
							(end 0.1778 -0.2794)
						)
					)
					(width 0)
					(fill yes)
				)
			)
		)
		(pad "2" smd custom
			(at 0 0.4445 270)
			(size 0.1397 0.1397)
			(layers "F.Cu" "F.Mask" "F.Paste")
			(net "HDD_PRSNT_15")
			(options
				(clearance outline)
				(anchor circle)
			)
			(primitives
				(gr_poly
					(pts
						(arc
							(start -0.1778 -0.2794)
							(mid -0.249642 -0.249642)
							(end -0.2794 -0.1778)
						)
						(arc
							(start -0.2794 0.1778)
							(mid -0.249642 0.249642)
							(end -0.1778 0.2794)
						)
						(arc
							(start 0.1778 0.2794)
							(mid 0.249642 0.249642)
							(end 0.2794 0.1778)
						)
						(arc
							(start 0.2794 -0.1778)
							(mid 0.249642 -0.249642)
							(end 0.1778 -0.2794)
						)
					)
					(width 0)
					(fill yes)
				)
			)
		)
	)
	(footprint ""
		(layer "F.Cu")
		(at 362.966 -32.004 -90)
		(property "Reference" "R782"
			(at 0 0 270)
			(layer "F.SilkS")
			(hide yes)
			(effects
				(font
					(size 1.27 1.27)
				)
			)
		)
		(property "Value" "2R6F-GP"
			(at -0.0508 -4.8514 270)
			(unlocked yes)
			(layer "F.Fab")
			(hide yes)
			(effects
				(font
					(size 1.016 1.016)
					(thickness 0.1524)
				)
			)
		)
		(property "Device Type" "R1206H26"
			(at 0 -6.3754 270)
			(unlocked yes)
			(layer "F.Fab")
			(hide yes)
			(effects
				(font
					(size 1.016 1.016)
					(thickness 0.1524)
				)
			)
		)
		(duplicate_pad_numbers_are_jumpers no)
		(fp_line
			(start -1.016 2.2352)
			(end -1.016 -2.2352)
			(stroke
				(width 0.1524)
				(type default)
			)
			(layer "F.SilkS")
		)
		(fp_line
			(start 1.016 2.2352)
			(end -1.016 2.2352)
			(stroke
				(width 0.1524)
				(type default)
			)
			(layer "F.SilkS")
		)
		(fp_line
			(start -1.016 -2.2352)
			(end 1.016 -2.2352)
			(stroke
				(width 0.1524)
				(type default)
			)
			(layer "F.SilkS")
		)
		(fp_line
			(start 1.016 -2.2352)
			(end 1.016 2.2352)
			(stroke
				(width 0.1524)
				(type default)
			)
			(layer "F.SilkS")
		)
		(fp_rect
			(start -1.0922 2.3114)
			(end 1.0922 -2.3114)
			(stroke
				(width 0)
				(type default)
			)
			(fill no)
			(layer "F.CrtYd")
		)
		(fp_poly
			(pts
				(xy -1.0922 -2.3114) (xy 1.0922 -2.3114) (xy 1.0922 2.3114) (xy -1.0922 2.3114)
			)
			(stroke
				(width 0)
				(type default)
			)
			(fill no)
			(layer "F.Fab")
		)
		(pad "1" smd rect
			(at 0 -1.397 270)
			(size 1.651 1.27)
			(layers "F.Cu" "F.Mask" "F.Paste")
			(net "P5V_HDD31")
		)
		(pad "2" smd rect
			(at 0 1.397 270)
			(size 1.651 1.27)
			(layers "F.Cu" "F.Mask" "F.Paste")
			(net "5V_PRE_31")
		)
	)
	(footprint ""
		(layer "F.Cu")
		(at 249.921522 -359.257346)
		(property "Reference" "C562"
			(at 0 0 0)
			(layer "F.SilkS")
			(hide yes)
			(effects
				(font
					(size 1.27 1.27)
				)
			)
		)
		(property "Value" "SC1U16V3KX-5GP"
			(at 0 -2.8194 0)
			(unlocked yes)
			(layer "F.Fab")
			(hide yes)
			(effects
				(font
					(size 1.016 1.016)
					(thickness 0.1524)
				)
			)
		)
		(property "Device Type" "C603H36"
			(at 0 -4.3434 0)
			(unlocked yes)
			(layer "F.Fab")
			(hide yes)
			(effects
				(font
					(size 1.016 1.016)
					(thickness 0.1524)
				)
			)
		)
		(duplicate_pad_numbers_are_jumpers no)
		(fp_line
			(start 0.508 0)
			(end -0.508 0)
			(stroke
				(width 0.2032)
				(type default)
			)
			(layer "F.SilkS")
		)
		(fp_rect
			(start -0.5842 1.3335)
			(end 0.5842 -1.3335)
			(stroke
				(width 0)
				(type default)
			)
			(fill no)
			(layer "F.CrtYd")
		)
		(fp_rect
			(start -0.5842 1.3335)
			(end 0.5842 -1.3335)
			(stroke
				(width 0)
				(type default)
			)
			(fill no)
			(layer "F.Fab")
		)
		(pad "1" smd custom
			(at 0 -0.762)
			(size 0.2159 0.2159)
			(layers "F.Cu" "F.Mask" "F.Paste")
			(net "MB3_VCAP_R")
			(options
				(clearance outline)
				(anchor circle)
			)
			(primitives
				(gr_poly
					(pts
						(arc
							(start -0.3302 -0.4318)
							(mid -0.402042 -0.402042)
							(end -0.4318 -0.3302)
						)
						(arc
							(start -0.4318 0.3302)
							(mid -0.402042 0.402042)
							(end -0.3302 0.4318)
						)
						(arc
							(start 0.3302 0.4318)
							(mid 0.402042 0.402042)
							(end 0.4318 0.3302)
						)
						(arc
							(start 0.4318 -0.3302)
							(mid 0.402042 -0.402042)
							(end 0.3302 -0.4318)
						)
					)
					(width 0)
					(fill yes)
				)
			)
		)
		(pad "2" smd custom
			(at 0 0.762)
			(size 0.2159 0.2159)
			(layers "F.Cu" "F.Mask" "F.Paste")
			(net "AGND_CURRENT_DPB")
			(options
				(clearance outline)
				(anchor circle)
			)
			(primitives
				(gr_poly
					(pts
						(arc
							(start -0.3302 -0.4318)
							(mid -0.402042 -0.402042)
							(end -0.4318 -0.3302)
						)
						(arc
							(start -0.4318 0.3302)
							(mid -0.402042 0.402042)
							(end -0.3302 0.4318)
						)
						(arc
							(start 0.3302 0.4318)
							(mid 0.402042 0.402042)
							(end 0.4318 0.3302)
						)
						(arc
							(start 0.4318 -0.3302)
							(mid 0.402042 -0.402042)
							(end 0.3302 -0.4318)
						)
					)
					(width 0)
					(fill yes)
				)
			)
		)
	)
	(footprint ""
		(layer "F.Cu")
		(at 445.102996 -364.263686 90)
		(property "Reference" "C536"
			(at 0 0 90)
			(layer "F.SilkS")
			(hide yes)
			(effects
				(font
					(size 1.27 1.27)
				)
			)
		)
		(property "Value" "SCD1U25V2KX-2-GP"
			(at 1.1811 -2.7051 90)
			(unlocked yes)
			(layer "F.Fab")
			(hide yes)
			(effects
				(font
					(size 1.016 1.016)
					(thickness 0.1524)
				)
			)
		)
		(property "Device Type" "C402H22"
			(at 1.1811 -4.2291 90)
			(unlocked yes)
			(layer "F.Fab")
			(hide yes)
			(effects
				(font
					(size 1.016 1.016)
					(thickness 0.1524)
				)
			)
		)
		(duplicate_pad_numbers_are_jumpers no)
		(fp_rect
			(start -0.4318 0.9525)
			(end 0.4318 -0.9525)
			(stroke
				(width 0)
				(type default)
			)
			(fill no)
			(layer "F.CrtYd")
		)
		(fp_rect
			(start -0.4318 0.9525)
			(end 0.4318 -0.9525)
			(stroke
				(width 0)
				(type default)
			)
			(fill no)
			(layer "F.Fab")
		)
		(pad "1" smd custom
			(at 0 -0.4445 90)
			(size 0.1524 0.1524)
			(layers "F.Cu" "F.Mask" "F.Paste")
			(net "P12V_FAN3")
			(options
				(clearance outline)
				(anchor circle)
			)
			(primitives
				(gr_poly
					(pts
						(arc
							(start 0.3048 -0.2032)
							(mid 0.275042 -0.275042)
							(end 0.2032 -0.3048)
						)
						(arc
							(start -0.2032 -0.3048)
							(mid -0.275042 -0.275042)
							(end -0.3048 -0.2032)
						)
						(arc
							(start -0.3048 0.2032)
							(mid -0.275042 0.275042)
							(end -0.2032 0.3048)
						)
						(arc
							(start 0.2032 0.3048)
							(mid 0.275042 0.275042)
							(end 0.3048 0.2032)
						)
					)
					(width 0)
					(fill yes)
				)
			)
		)
		(pad "2" smd custom
			(at 0 0.4445 90)
			(size 0.1524 0.1524)
			(layers "F.Cu" "F.Mask" "F.Paste")
			(net "GND")
			(options
				(clearance outline)
				(anchor circle)
			)
			(primitives
				(gr_poly
					(pts
						(arc
							(start 0.3048 -0.2032)
							(mid 0.275042 -0.275042)
							(end 0.2032 -0.3048)
						)
						(arc
							(start -0.2032 -0.3048)
							(mid -0.275042 -0.275042)
							(end -0.3048 -0.2032)
						)
						(arc
							(start -0.3048 0.2032)
							(mid -0.275042 0.275042)
							(end -0.2032 0.3048)
						)
						(arc
							(start 0.2032 0.3048)
							(mid 0.275042 0.275042)
							(end 0.3048 0.2032)
						)
					)
					(width 0)
					(fill yes)
				)
			)
		)
	)
	(footprint ""
		(layer "F.Cu")
		(at 257.2893 -213.95944 -90)
		(property "Reference" "C24"
			(at 0 0 270)
			(layer "F.SilkS")
			(hide yes)
			(effects
				(font
					(size 1.27 1.27)
				)
			)
		)
		(property "Value" "SC1U16V3KX-5GP"
			(at 0 -2.8194 270)
			(unlocked yes)
			(layer "F.Fab")
			(hide yes)
			(effects
				(font
					(size 1.016 1.016)
					(thickness 0.1524)
				)
			)
		)
		(property "Device Type" "C603H36"
			(at 0 -4.3434 270)
			(unlocked yes)
			(layer "F.Fab")
			(hide yes)
			(effects
				(font
					(size 1.016 1.016)
					(thickness 0.1524)
				)
			)
		)
		(duplicate_pad_numbers_are_jumpers no)
		(fp_line
			(start 0.508 0)
			(end -0.508 0)
			(stroke
				(width 0.2032)
				(type default)
			)
			(layer "F.SilkS")
		)
		(fp_rect
			(start -0.5842 1.3335)
			(end 0.5842 -1.3335)
			(stroke
				(width 0)
				(type default)
			)
			(fill no)
			(layer "F.CrtYd")
		)
		(fp_rect
			(start -0.5842 1.3335)
			(end 0.5842 -1.3335)
			(stroke
				(width 0)
				(type default)
			)
			(fill no)
			(layer "F.Fab")
		)
		(pad "1" smd custom
			(at 0 -0.762 270)
			(size 0.2159 0.2159)
			(layers "F.Cu" "F.Mask" "F.Paste")
			(net "P3V3_STBY_B")
			(options
				(clearance outline)
				(anchor circle)
			)
			(primitives
				(gr_poly
					(pts
						(arc
							(start -0.3302 -0.4318)
							(mid -0.402042 -0.402042)
							(end -0.4318 -0.3302)
						)
						(arc
							(start -0.4318 0.3302)
							(mid -0.402042 0.402042)
							(end -0.3302 0.4318)
						)
						(arc
							(start 0.3302 0.4318)
							(mid 0.402042 0.402042)
							(end 0.4318 0.3302)
						)
						(arc
							(start 0.4318 -0.3302)
							(mid 0.402042 -0.402042)
							(end 0.3302 -0.4318)
						)
					)
					(width 0)
					(fill yes)
				)
			)
		)
		(pad "2" smd custom
			(at 0 0.762 270)
			(size 0.2159 0.2159)
			(layers "F.Cu" "F.Mask" "F.Paste")
			(net "GND")
			(options
				(clearance outline)
				(anchor circle)
			)
			(primitives
				(gr_poly
					(pts
						(arc
							(start -0.3302 -0.4318)
							(mid -0.402042 -0.402042)
							(end -0.4318 -0.3302)
						)
						(arc
							(start -0.4318 0.3302)
							(mid -0.402042 0.402042)
							(end -0.3302 0.4318)
						)
						(arc
							(start 0.3302 0.4318)
							(mid 0.402042 0.402042)
							(end 0.4318 0.3302)
						)
						(arc
							(start 0.4318 -0.3302)
							(mid 0.402042 -0.402042)
							(end 0.3302 -0.4318)
						)
					)
					(width 0)
					(fill yes)
				)
			)
		)
	)
	(footprint ""
		(layer "F.Cu")
		(at 33.949894 -8.330184 180)
		(property "Reference" "U15"
			(at 0 0 180)
			(layer "F.SilkS")
			(hide yes)
			(effects
				(font
					(size 1.27 1.27)
				)
			)
		)
		(property "Value" "TMP75AIDGKR-GP"
			(at -0.1143 -9.1948 180)
			(unlocked yes)
			(layer "F.Fab")
			(hide yes)
			(effects
				(font
					(size 1.016 1.016)
					(thickness 0.1524)
				)
			)
		)
		(property "Device Type" "MSOP8-1H44"
			(at -0.1143 -10.795 180)
			(unlocked yes)
			(layer "F.Fab")
			(hide yes)
			(effects
				(font
					(size 1.016 1.016)
					(thickness 0.1524)
				)
			)
		)
		(duplicate_pad_numbers_are_jumpers no)
		(fp_line
			(start 1.0795 1.016)
			(end 1.0795 -1.016)
			(stroke
				(width 0.1524)
				(type default)
			)
			(layer "F.SilkS")
		)
		(fp_line
			(start 1.0795 -1.016)
			(end -1.9558 -1.016)
			(stroke
				(width 0.1524)
				(type default)
			)
			(layer "F.SilkS")
		)
		(fp_line
			(start -1.4478 -0.0381)
			(end -1.9558 0.4699)
			(stroke
				(width 0.1524)
				(type default)
			)
			(layer "F.SilkS")
		)
		(fp_line
			(start -1.778 1.0922)
			(end -1.778 3.048)
			(stroke
				(width 0.508)
				(type default)
			)
			(layer "F.SilkS")
		)
		(fp_line
			(start -1.9558 1.016)
			(end 1.0795 1.016)
			(stroke
				(width 0.1524)
				(type default)
			)
			(layer "F.SilkS")
		)
		(fp_line
			(start -1.9558 -0.5461)
			(end -1.4478 -0.0381)
			(stroke
				(width 0.1524)
				(type default)
			)
			(layer "F.SilkS")
		)
		(fp_line
			(start -1.9558 -1.016)
			(end -1.9558 1.016)
			(stroke
				(width 0.1524)
				(type default)
			)
			(layer "F.SilkS")
		)
		(fp_poly
			(pts
				(xy -1.1557 -1.016) (xy -1.1557 1.016) (xy 1.1557 1.016) (xy 1.1557 -1.016)
			)
			(stroke
				(width 0)
				(type default)
			)
			(fill yes)
			(layer "F.SilkS")
		)
		(fp_rect
			(start -1.4986 2.4511)
			(end 1.4986 -2.4511)
			(stroke
				(width 0)
				(type default)
			)
			(fill no)
			(layer "F.CrtYd")
		)
		(fp_poly
			(pts
				(xy -2.032 3.302) (xy -2.032 -3.302) (xy 2.032 -3.302) (xy 2.032 -2.1209) (xy 1.4986 -2.1209) (xy 1.4986 -2.4511)
				(xy -1.4986 -2.4511) (xy -1.4986 2.4511) (xy 1.4986 2.4511) (xy 1.4986 -2.1082) (xy 2.032 -2.1082)
				(xy 2.032 3.302)
			)
			(stroke
				(width 0)
				(type default)
			)
			(fill no)
			(layer "F.CrtYd")
		)
		(fp_rect
			(start -2.032 3.302)
			(end 2.032 -3.302)
			(stroke
				(width 0)
				(type default)
			)
			(fill no)
			(layer "F.Fab")
		)
		(pad "1" smd rect
			(at -0.97536 2.05486 180)
			(size 0.3556 1.524)
			(layers "F.Cu" "F.Mask" "F.Paste")
			(net "TEMP1_SDA")
		)
		(pad "2" smd rect
			(at -0.32512 2.05486 180)
			(size 0.3556 1.524)
			(layers "F.Cu" "F.Mask" "F.Paste")
			(net "TEMP1_SCL")
		)
		(pad "3" smd rect
			(at 0.32512 2.05486 180)
			(size 0.3556 1.524)
			(layers "F.Cu" "F.Mask" "F.Paste")
			(net "TEMP1_ALERT")
		)
		(pad "4" smd rect
			(at 0.97536 2.05486 180)
			(size 0.3556 1.524)
			(layers "F.Cu" "F.Mask" "F.Paste")
			(net "GND")
		)
		(pad "5" smd rect
			(at 0.97536 -2.05486 180)
			(size 0.3556 1.524)
			(layers "F.Cu" "F.Mask" "F.Paste")
			(net "TEMP1_A2")
		)
		(pad "6" smd rect
			(at 0.32512 -2.05486 180)
			(size 0.3556 1.524)
			(layers "F.Cu" "F.Mask" "F.Paste")
			(net "TEMP1_A1")
		)
		(pad "7" smd rect
			(at -0.32512 -2.05486 180)
			(size 0.3556 1.524)
			(layers "F.Cu" "F.Mask" "F.Paste")
			(net "TEMP1_A0")
		)
		(pad "8" smd rect
			(at -0.97536 -2.05486 180)
			(size 0.3556 1.524)
			(layers "F.Cu" "F.Mask" "F.Paste")
			(net "P3V3_STBY_A")
		)
	)
	(footprint ""
		(layer "F.Cu")
		(at 447.421 -147.193 -90)
		(property "Reference" "C318"
			(at 0 0 270)
			(layer "F.SilkS")
			(hide yes)
			(effects
				(font
					(size 1.27 1.27)
				)
			)
		)
		(property "Value" "SCD01U50V2KX-1GP"
			(at 1.1811 -2.7051 270)
			(unlocked yes)
			(layer "F.Fab")
			(hide yes)
			(effects
				(font
					(size 1.016 1.016)
					(thickness 0.1524)
				)
			)
		)
		(property "Device Type" "C402H22"
			(at 1.1811 -4.2291 270)
			(unlocked yes)
			(layer "F.Fab")
			(hide yes)
			(effects
				(font
					(size 1.016 1.016)
					(thickness 0.1524)
				)
			)
		)
		(duplicate_pad_numbers_are_jumpers no)
		(fp_rect
			(start -0.4318 0.9525)
			(end 0.4318 -0.9525)
			(stroke
				(width 0)
				(type default)
			)
			(fill no)
			(layer "F.CrtYd")
		)
		(fp_rect
			(start -0.4318 0.9525)
			(end 0.4318 -0.9525)
			(stroke
				(width 0)
				(type default)
			)
			(fill no)
			(layer "F.Fab")
		)
		(pad "1" smd custom
			(at 0 -0.4445 270)
			(size 0.1524 0.1524)
			(layers "F.Cu" "F.Mask" "F.Paste")
			(net "HDD_PRSNT_22")
			(options
				(clearance outline)
				(anchor circle)
			)
			(primitives
				(gr_poly
					(pts
						(arc
							(start 0.3048 -0.2032)
							(mid 0.275042 -0.275042)
							(end 0.2032 -0.3048)
						)
						(arc
							(start -0.2032 -0.3048)
							(mid -0.275042 -0.275042)
							(end -0.3048 -0.2032)
						)
						(arc
							(start -0.3048 0.2032)
							(mid -0.275042 0.275042)
							(end -0.2032 0.3048)
						)
						(arc
							(start 0.2032 0.3048)
							(mid 0.275042 0.275042)
							(end 0.3048 0.2032)
						)
					)
					(width 0)
					(fill yes)
				)
			)
		)
		(pad "2" smd custom
			(at 0 0.4445 270)
			(size 0.1524 0.1524)
			(layers "F.Cu" "F.Mask" "F.Paste")
			(net "GND")
			(options
				(clearance outline)
				(anchor circle)
			)
			(primitives
				(gr_poly
					(pts
						(arc
							(start 0.3048 -0.2032)
							(mid 0.275042 -0.275042)
							(end 0.2032 -0.3048)
						)
						(arc
							(start -0.2032 -0.3048)
							(mid -0.275042 -0.275042)
							(end -0.3048 -0.2032)
						)
						(arc
							(start -0.3048 0.2032)
							(mid -0.275042 0.275042)
							(end -0.2032 0.3048)
						)
						(arc
							(start 0.2032 0.3048)
							(mid 0.275042 0.275042)
							(end 0.3048 0.2032)
						)
					)
					(width 0)
					(fill yes)
				)
			)
		)
	)
	(footprint ""
		(layer "F.Cu")
		(at 114.9096 -148.717 -90)
		(property "Reference" "C225"
			(at 0 0 270)
			(layer "F.SilkS")
			(hide yes)
			(effects
				(font
					(size 1.27 1.27)
				)
			)
		)
		(property "Value" "SC1U16V3KX-5GP"
			(at 0 -2.8194 270)
			(unlocked yes)
			(layer "F.Fab")
			(hide yes)
			(effects
				(font
					(size 1.016 1.016)
					(thickness 0.1524)
				)
			)
		)
		(property "Device Type" "C603H36"
			(at 0 -4.3434 270)
			(unlocked yes)
			(layer "F.Fab")
			(hide yes)
			(effects
				(font
					(size 1.016 1.016)
					(thickness 0.1524)
				)
			)
		)
		(duplicate_pad_numbers_are_jumpers no)
		(fp_line
			(start 0.508 0)
			(end -0.508 0)
			(stroke
				(width 0.2032)
				(type default)
			)
			(layer "F.SilkS")
		)
		(fp_rect
			(start -0.5842 1.3335)
			(end 0.5842 -1.3335)
			(stroke
				(width 0)
				(type default)
			)
			(fill no)
			(layer "F.CrtYd")
		)
		(fp_rect
			(start -0.5842 1.3335)
			(end 0.5842 -1.3335)
			(stroke
				(width 0)
				(type default)
			)
			(fill no)
			(layer "F.Fab")
		)
		(pad "1" smd custom
			(at 0 -0.762 270)
			(size 0.2159 0.2159)
			(layers "F.Cu" "F.Mask" "F.Paste")
			(net "P5V_HDD15")
			(options
				(clearance outline)
				(anchor circle)
			)
			(primitives
				(gr_poly
					(pts
						(arc
							(start -0.3302 -0.4318)
							(mid -0.402042 -0.402042)
							(end -0.4318 -0.3302)
						)
						(arc
							(start -0.4318 0.3302)
							(mid -0.402042 0.402042)
							(end -0.3302 0.4318)
						)
						(arc
							(start 0.3302 0.4318)
							(mid 0.402042 0.402042)
							(end 0.4318 0.3302)
						)
						(arc
							(start 0.4318 -0.3302)
							(mid 0.402042 -0.402042)
							(end 0.3302 -0.4318)
						)
					)
					(width 0)
					(fill yes)
				)
			)
		)
		(pad "2" smd custom
			(at 0 0.762 270)
			(size 0.2159 0.2159)
			(layers "F.Cu" "F.Mask" "F.Paste")
			(net "GND")
			(options
				(clearance outline)
				(anchor circle)
			)
			(primitives
				(gr_poly
					(pts
						(arc
							(start -0.3302 -0.4318)
							(mid -0.402042 -0.402042)
							(end -0.4318 -0.3302)
						)
						(arc
							(start -0.4318 0.3302)
							(mid -0.402042 0.402042)
							(end -0.3302 0.4318)
						)
						(arc
							(start 0.3302 0.4318)
							(mid 0.402042 0.402042)
							(end 0.4318 0.3302)
						)
						(arc
							(start 0.4318 -0.3302)
							(mid 0.402042 -0.402042)
							(end 0.3302 -0.4318)
						)
					)
					(width 0)
					(fill yes)
				)
			)
		)
	)
	(footprint ""
		(layer "F.Cu")
		(at 54.61 -249.555 90)
		(property "Reference" "R183"
			(at 0 0 90)
			(layer "F.SilkS")
			(hide yes)
			(effects
				(font
					(size 1.27 1.27)
				)
			)
		)
		(property "Value" "4K7R2F-GP"
			(at 0.064008 -3.993896 90)
			(unlocked yes)
			(layer "F.Fab")
			(hide yes)
			(effects
				(font
					(size 1.016 1.016)
					(thickness 0.1524)
				)
			)
		)
		(property "Device Type" "R402H16"
			(at 0.064008 -5.517896 90)
			(unlocked yes)
			(layer "F.Fab")
			(hide yes)
			(effects
				(font
					(size 1.016 1.016)
					(thickness 0.1524)
				)
			)
		)
		(duplicate_pad_numbers_are_jumpers no)
		(fp_line
			(start 0.508 -0.9398)
			(end -0.508 -0.9398)
			(stroke
				(width 0.1524)
				(type default)
			)
			(layer "F.SilkS")
		)
		(fp_line
			(start -0.508 -0.9398)
			(end -0.508 0.9398)
			(stroke
				(width 0.1524)
				(type default)
			)
			(layer "F.SilkS")
		)
		(fp_rect
			(start -0.508 0.9398)
			(end 0.508 -0.9398)
			(stroke
				(width 0)
				(type default)
			)
			(fill no)
			(layer "F.CrtYd")
		)
		(fp_rect
			(start -0.508 0.9398)
			(end 0.508 -0.9398)
			(stroke
				(width 0)
				(type default)
			)
			(fill no)
			(layer "F.Fab")
		)
		(pad "1" smd custom
			(at 0 -0.4445 90)
			(size 0.1397 0.1397)
			(layers "F.Cu" "F.Mask" "F.Paste")
			(net "SW_PWR_R_HDD1")
			(options
				(clearance outline)
				(anchor circle)
			)
			(primitives
				(gr_poly
					(pts
						(arc
							(start -0.1778 -0.2794)
							(mid -0.249642 -0.249642)
							(end -0.2794 -0.1778)
						)
						(arc
							(start -0.2794 0.1778)
							(mid -0.249642 0.249642)
							(end -0.1778 0.2794)
						)
						(arc
							(start 0.1778 0.2794)
							(mid 0.249642 0.249642)
							(end 0.2794 0.1778)
						)
						(arc
							(start 0.2794 -0.1778)
							(mid 0.249642 -0.249642)
							(end 0.1778 -0.2794)
						)
					)
					(width 0)
					(fill yes)
				)
			)
		)
		(pad "2" smd custom
			(at 0 0.4445 90)
			(size 0.1397 0.1397)
			(layers "F.Cu" "F.Mask" "F.Paste")
			(net "GND")
			(options
				(clearance outline)
				(anchor circle)
			)
			(primitives
				(gr_poly
					(pts
						(arc
							(start -0.1778 -0.2794)
							(mid -0.249642 -0.249642)
							(end -0.2794 -0.1778)
						)
						(arc
							(start -0.2794 0.1778)
							(mid -0.249642 0.249642)
							(end -0.1778 0.2794)
						)
						(arc
							(start 0.1778 0.2794)
							(mid 0.249642 0.249642)
							(end 0.2794 0.1778)
						)
						(arc
							(start 0.2794 -0.1778)
							(mid 0.249642 -0.249642)
							(end 0.1778 -0.2794)
						)
					)
					(width 0)
					(fill yes)
				)
			)
		)
	)
	(footprint ""
		(layer "F.Cu")
		(at 268.224 -210.4136 90)
		(property "Reference" "R10"
			(at 0 0 90)
			(layer "F.SilkS")
			(hide yes)
			(effects
				(font
					(size 1.27 1.27)
				)
			)
		)
		(property "Value" "1KR2J-1-GP"
			(at 0.064008 -3.993896 90)
			(unlocked yes)
			(layer "F.Fab")
			(hide yes)
			(effects
				(font
					(size 1.016 1.016)
					(thickness 0.1524)
				)
			)
		)
		(property "Device Type" "R402H16"
			(at 0.064008 -5.517896 90)
			(unlocked yes)
			(layer "F.Fab")
			(hide yes)
			(effects
				(font
					(size 1.016 1.016)
					(thickness 0.1524)
				)
			)
		)
		(duplicate_pad_numbers_are_jumpers no)
		(fp_line
			(start 0.508 -0.9398)
			(end -0.508 -0.9398)
			(stroke
				(width 0.1524)
				(type default)
			)
			(layer "F.SilkS")
		)
		(fp_line
			(start -0.508 -0.9398)
			(end -0.508 0.9398)
			(stroke
				(width 0.1524)
				(type default)
			)
			(layer "F.SilkS")
		)
		(fp_rect
			(start -0.508 0.9398)
			(end 0.508 -0.9398)
			(stroke
				(width 0)
				(type default)
			)
			(fill no)
			(layer "F.CrtYd")
		)
		(fp_rect
			(start -0.508 0.9398)
			(end 0.508 -0.9398)
			(stroke
				(width 0)
				(type default)
			)
			(fill no)
			(layer "F.Fab")
		)
		(pad "1" smd custom
			(at 0 -0.4445 90)
			(size 0.1397 0.1397)
			(layers "F.Cu" "F.Mask" "F.Paste")
			(net "P3V3_STBY_B")
			(options
				(clearance outline)
				(anchor circle)
			)
			(primitives
				(gr_poly
					(pts
						(arc
							(start -0.1778 -0.2794)
							(mid -0.249642 -0.249642)
							(end -0.2794 -0.1778)
						)
						(arc
							(start -0.2794 0.1778)
							(mid -0.249642 0.249642)
							(end -0.1778 0.2794)
						)
						(arc
							(start 0.1778 0.2794)
							(mid 0.249642 0.249642)
							(end 0.2794 0.1778)
						)
						(arc
							(start 0.2794 -0.1778)
							(mid 0.249642 -0.249642)
							(end 0.1778 -0.2794)
						)
					)
					(width 0)
					(fill yes)
				)
			)
		)
		(pad "2" smd custom
			(at 0 0.4445 90)
			(size 0.1397 0.1397)
			(layers "F.Cu" "F.Mask" "F.Paste")
			(net "I2C_DRIVE_B_INS_SCL")
			(options
				(clearance outline)
				(anchor circle)
			)
			(primitives
				(gr_poly
					(pts
						(arc
							(start -0.1778 -0.2794)
							(mid -0.249642 -0.249642)
							(end -0.2794 -0.1778)
						)
						(arc
							(start -0.2794 0.1778)
							(mid -0.249642 0.249642)
							(end -0.1778 0.2794)
						)
						(arc
							(start 0.1778 0.2794)
							(mid 0.249642 0.249642)
							(end 0.2794 0.1778)
						)
						(arc
							(start 0.2794 -0.1778)
							(mid 0.249642 -0.249642)
							(end 0.1778 -0.2794)
						)
					)
					(width 0)
					(fill yes)
				)
			)
		)
	)
	(footprint ""
		(layer "F.Cu")
		(at 135.9408 -369.4684 180)
		(property "Reference" "D40"
			(at 0 0 180)
			(layer "F.SilkS")
			(hide yes)
			(effects
				(font
					(size 1.27 1.27)
				)
			)
		)
		(property "Value" "BAS16H-GP"
			(at 0 -5.5372 180)
			(unlocked yes)
			(layer "F.Fab")
			(hide yes)
			(effects
				(font
					(size 1.016 1.016)
					(thickness 0.1524)
				)
			)
		)
		(property "Device Type" "SOD123AKH48"
			(at 0 -7.0612 180)
			(unlocked yes)
			(layer "F.Fab")
			(hide yes)
			(effects
				(font
					(size 1.016 1.016)
					(thickness 0.1524)
				)
			)
		)
		(duplicate_pad_numbers_are_jumpers no)
		(fp_line
			(start 1.016 2.667)
			(end 1.016 -2.667)
			(stroke
				(width 0.1524)
				(type default)
			)
			(layer "F.SilkS")
		)
		(fp_line
			(start 1.016 -2.667)
			(end -1.016 -2.667)
			(stroke
				(width 0.1524)
				(type default)
			)
			(layer "F.SilkS")
		)
		(fp_line
			(start 0.889 2.921)
			(end -0.889 2.921)
			(stroke
				(width 0.508)
				(type default)
			)
			(layer "F.SilkS")
		)
		(fp_line
			(start -1.016 2.667)
			(end 1.016 2.667)
			(stroke
				(width 0.1524)
				(type default)
			)
			(layer "F.SilkS")
		)
		(fp_line
			(start -1.016 -2.667)
			(end -1.016 2.667)
			(stroke
				(width 0.1524)
				(type default)
			)
			(layer "F.SilkS")
		)
		(fp_rect
			(start -1.143 3.175)
			(end 1.143 -2.794)
			(stroke
				(width 0)
				(type default)
			)
			(fill no)
			(layer "F.CrtYd")
		)
		(fp_poly
			(pts
				(xy -1.143 -2.794) (xy 1.143 -2.794) (xy 1.143 3.175) (xy -1.143 3.175)
			)
			(stroke
				(width 0)
				(type default)
			)
			(fill no)
			(layer "F.Fab")
		)
		(pad "A" smd rect
			(at 0 -1.6891 180)
			(size 0.889 1.397)
			(layers "F.Cu" "F.Mask" "F.Paste")
			(net "FAN_1_TACH1")
		)
		(pad "K" smd rect
			(at 0 1.6891 180)
			(size 0.889 1.397)
			(layers "F.Cu" "F.Mask" "F.Paste")
			(net "P12V_IN")
		)
	)
	(footprint ""
		(layer "F.Cu")
		(at 174.498 -138.049 90)
		(property "Reference" "R468"
			(at 0 0 90)
			(layer "F.SilkS")
			(hide yes)
			(effects
				(font
					(size 1.27 1.27)
				)
			)
		)
		(property "Value" "4K7R2J-2-GP"
			(at 0.064008 -3.993896 90)
			(unlocked yes)
			(layer "F.Fab")
			(hide yes)
			(effects
				(font
					(size 1.016 1.016)
					(thickness 0.1524)
				)
			)
		)
		(property "Device Type" "R402H16"
			(at 0.064008 -5.517896 90)
			(unlocked yes)
			(layer "F.Fab")
			(hide yes)
			(effects
				(font
					(size 1.016 1.016)
					(thickness 0.1524)
				)
			)
		)
		(duplicate_pad_numbers_are_jumpers no)
		(fp_line
			(start 0.508 -0.9398)
			(end -0.508 -0.9398)
			(stroke
				(width 0.1524)
				(type default)
			)
			(layer "F.SilkS")
		)
		(fp_line
			(start -0.508 -0.9398)
			(end -0.508 0.9398)
			(stroke
				(width 0.1524)
				(type default)
			)
			(layer "F.SilkS")
		)
		(fp_rect
			(start -0.508 0.9398)
			(end 0.508 -0.9398)
			(stroke
				(width 0)
				(type default)
			)
			(fill no)
			(layer "F.CrtYd")
		)
		(fp_rect
			(start -0.508 0.9398)
			(end 0.508 -0.9398)
			(stroke
				(width 0)
				(type default)
			)
			(fill no)
			(layer "F.Fab")
		)
		(pad "1" smd custom
			(at 0 -0.4445 90)
			(size 0.1397 0.1397)
			(layers "F.Cu" "F.Mask" "F.Paste")
			(net "P12V_B")
			(options
				(clearance outline)
				(anchor circle)
			)
			(primitives
				(gr_poly
					(pts
						(arc
							(start -0.1778 -0.2794)
							(mid -0.249642 -0.249642)
							(end -0.2794 -0.1778)
						)
						(arc
							(start -0.2794 0.1778)
							(mid -0.249642 0.249642)
							(end -0.1778 0.2794)
						)
						(arc
							(start 0.1778 0.2794)
							(mid 0.249642 0.249642)
							(end 0.2794 0.1778)
						)
						(arc
							(start 0.2794 -0.1778)
							(mid 0.249642 -0.249642)
							(end 0.1778 -0.2794)
						)
					)
					(width 0)
					(fill yes)
				)
			)
		)
		(pad "2" smd custom
			(at 0 0.4445 90)
			(size 0.1397 0.1397)
			(layers "F.Cu" "F.Mask" "F.Paste")
			(net "SW_HDD_P17")
			(options
				(clearance outline)
				(anchor circle)
			)
			(primitives
				(gr_poly
					(pts
						(arc
							(start -0.1778 -0.2794)
							(mid -0.249642 -0.249642)
							(end -0.2794 -0.1778)
						)
						(arc
							(start -0.2794 0.1778)
							(mid -0.249642 0.249642)
							(end -0.1778 0.2794)
						)
						(arc
							(start 0.1778 0.2794)
							(mid 0.249642 0.249642)
							(end 0.2794 0.1778)
						)
						(arc
							(start 0.2794 -0.1778)
							(mid 0.249642 -0.249642)
							(end 0.1778 -0.2794)
						)
					)
					(width 0)
					(fill yes)
				)
			)
		)
	)
	(footprint ""
		(layer "F.Cu")
		(at 50.038 -19.939 -90)
		(property "Reference" "R652"
			(at 0 0 270)
			(layer "F.SilkS")
			(hide yes)
			(effects
				(font
					(size 1.27 1.27)
				)
			)
		)
		(property "Value" "4K7R2J-2-GP"
			(at 0.064008 -3.993896 270)
			(unlocked yes)
			(layer "F.Fab")
			(hide yes)
			(effects
				(font
					(size 1.016 1.016)
					(thickness 0.1524)
				)
			)
		)
		(property "Device Type" "R402H16"
			(at 0.064008 -5.517896 270)
			(unlocked yes)
			(layer "F.Fab")
			(hide yes)
			(effects
				(font
					(size 1.016 1.016)
					(thickness 0.1524)
				)
			)
		)
		(duplicate_pad_numbers_are_jumpers no)
		(fp_line
			(start -0.508 -0.9398)
			(end -0.508 0.9398)
			(stroke
				(width 0.1524)
				(type default)
			)
			(layer "F.SilkS")
		)
		(fp_line
			(start 0.508 -0.9398)
			(end -0.508 -0.9398)
			(stroke
				(width 0.1524)
				(type default)
			)
			(layer "F.SilkS")
		)
		(fp_rect
			(start -0.508 0.9398)
			(end 0.508 -0.9398)
			(stroke
				(width 0)
				(type default)
			)
			(fill no)
			(layer "F.CrtYd")
		)
		(fp_rect
			(start -0.508 0.9398)
			(end 0.508 -0.9398)
			(stroke
				(width 0)
				(type default)
			)
			(fill no)
			(layer "F.Fab")
		)
		(pad "1" smd custom
			(at 0 -0.4445 270)
			(size 0.1397 0.1397)
			(layers "F.Cu" "F.Mask" "F.Paste")
			(net "P12V_B")
			(options
				(clearance outline)
				(anchor circle)
			)
			(primitives
				(gr_poly
					(pts
						(arc
							(start -0.1778 -0.2794)
							(mid -0.249642 -0.249642)
							(end -0.2794 -0.1778)
						)
						(arc
							(start -0.2794 0.1778)
							(mid -0.249642 0.249642)
							(end -0.1778 0.2794)
						)
						(arc
							(start 0.1778 0.2794)
							(mid 0.249642 0.249642)
							(end 0.2794 0.1778)
						)
						(arc
							(start 0.2794 -0.1778)
							(mid 0.249642 -0.249642)
							(end 0.1778 -0.2794)
						)
					)
					(width 0)
					(fill yes)
				)
			)
		)
		(pad "2" smd custom
			(at 0 0.4445 270)
			(size 0.1397 0.1397)
			(layers "F.Cu" "F.Mask" "F.Paste")
			(net "SW_HDD_P25")
			(options
				(clearance outline)
				(anchor circle)
			)
			(primitives
				(gr_poly
					(pts
						(arc
							(start -0.1778 -0.2794)
							(mid -0.249642 -0.249642)
							(end -0.2794 -0.1778)
						)
						(arc
							(start -0.2794 0.1778)
							(mid -0.249642 0.249642)
							(end -0.1778 0.2794)
						)
						(arc
							(start 0.1778 0.2794)
							(mid 0.249642 0.249642)
							(end 0.2794 0.1778)
						)
						(arc
							(start 0.2794 -0.1778)
							(mid 0.249642 -0.249642)
							(end 0.1778 -0.2794)
						)
					)
					(width 0)
					(fill yes)
				)
			)
		)
	)
	(footprint ""
		(layer "F.Cu")
		(at 242.951 -228.219 -90)
		(property "Reference" "R83"
			(at 0 0 270)
			(layer "F.SilkS")
			(hide yes)
			(effects
				(font
					(size 1.27 1.27)
				)
			)
		)
		(property "Value" "4K7R2F-GP"
			(at 0.064008 -3.993896 270)
			(unlocked yes)
			(layer "F.Fab")
			(hide yes)
			(effects
				(font
					(size 1.016 1.016)
					(thickness 0.1524)
				)
			)
		)
		(property "Device Type" "R402H16"
			(at 0.064008 -5.517896 270)
			(unlocked yes)
			(layer "F.Fab")
			(hide yes)
			(effects
				(font
					(size 1.016 1.016)
					(thickness 0.1524)
				)
			)
		)
		(duplicate_pad_numbers_are_jumpers no)
		(fp_line
			(start -0.508 -0.9398)
			(end -0.508 0.9398)
			(stroke
				(width 0.1524)
				(type default)
			)
			(layer "F.SilkS")
		)
		(fp_line
			(start 0.508 -0.9398)
			(end -0.508 -0.9398)
			(stroke
				(width 0.1524)
				(type default)
			)
			(layer "F.SilkS")
		)
		(fp_rect
			(start -0.508 0.9398)
			(end 0.508 -0.9398)
			(stroke
				(width 0)
				(type default)
			)
			(fill no)
			(layer "F.CrtYd")
		)
		(fp_rect
			(start -0.508 0.9398)
			(end 0.508 -0.9398)
			(stroke
				(width 0)
				(type default)
			)
			(fill no)
			(layer "F.Fab")
		)
		(pad "1" smd custom
			(at 0 -0.4445 270)
			(size 0.1397 0.1397)
			(layers "F.Cu" "F.Mask" "F.Paste")
			(net "P3V3_STBY_B")
			(options
				(clearance outline)
				(anchor circle)
			)
			(primitives
				(gr_poly
					(pts
						(arc
							(start -0.1778 -0.2794)
							(mid -0.249642 -0.249642)
							(end -0.2794 -0.1778)
						)
						(arc
							(start -0.2794 0.1778)
							(mid -0.249642 0.249642)
							(end -0.1778 0.2794)
						)
						(arc
							(start 0.1778 0.2794)
							(mid 0.249642 0.249642)
							(end 0.2794 0.1778)
						)
						(arc
							(start 0.2794 -0.1778)
							(mid 0.249642 -0.249642)
							(end 0.1778 -0.2794)
						)
					)
					(width 0)
					(fill yes)
				)
			)
		)
		(pad "2" smd custom
			(at 0 0.4445 270)
			(size 0.1397 0.1397)
			(layers "F.Cu" "F.Mask" "F.Paste")
			(net "IO_EXP3_RESET#")
			(options
				(clearance outline)
				(anchor circle)
			)
			(primitives
				(gr_poly
					(pts
						(arc
							(start -0.1778 -0.2794)
							(mid -0.249642 -0.249642)
							(end -0.2794 -0.1778)
						)
						(arc
							(start -0.2794 0.1778)
							(mid -0.249642 0.249642)
							(end -0.1778 0.2794)
						)
						(arc
							(start 0.1778 0.2794)
							(mid 0.249642 0.249642)
							(end 0.2794 0.1778)
						)
						(arc
							(start 0.2794 -0.1778)
							(mid 0.249642 -0.249642)
							(end 0.1778 -0.2794)
						)
					)
					(width 0)
					(fill yes)
				)
			)
		)
	)
	(footprint ""
		(layer "F.Cu")
		(at 254.112522 -358.622346)
		(property "Reference" "C561"
			(at 0 0 0)
			(layer "F.SilkS")
			(hide yes)
			(effects
				(font
					(size 1.27 1.27)
				)
			)
		)
		(property "Value" "SCD1U25V2KX-2-GP"
			(at 1.1811 -2.7051 0)
			(unlocked yes)
			(layer "F.Fab")
			(hide yes)
			(effects
				(font
					(size 1.016 1.016)
					(thickness 0.1524)
				)
			)
		)
		(property "Device Type" "C402H22"
			(at 1.1811 -4.2291 0)
			(unlocked yes)
			(layer "F.Fab")
			(hide yes)
			(effects
				(font
					(size 1.016 1.016)
					(thickness 0.1524)
				)
			)
		)
		(duplicate_pad_numbers_are_jumpers no)
		(fp_rect
			(start -0.4318 0.9525)
			(end 0.4318 -0.9525)
			(stroke
				(width 0)
				(type default)
			)
			(fill no)
			(layer "F.CrtYd")
		)
		(fp_rect
			(start -0.4318 0.9525)
			(end 0.4318 -0.9525)
			(stroke
				(width 0)
				(type default)
			)
			(fill no)
			(layer "F.Fab")
		)
		(pad "1" smd custom
			(at 0 -0.4445)
			(size 0.1524 0.1524)
			(layers "F.Cu" "F.Mask" "F.Paste")
			(net "MB3_ISTART_R")
			(options
				(clearance outline)
				(anchor circle)
			)
			(primitives
				(gr_poly
					(pts
						(arc
							(start 0.3048 -0.2032)
							(mid 0.275042 -0.275042)
							(end 0.2032 -0.3048)
						)
						(arc
							(start -0.2032 -0.3048)
							(mid -0.275042 -0.275042)
							(end -0.3048 -0.2032)
						)
						(arc
							(start -0.3048 0.2032)
							(mid -0.275042 0.275042)
							(end -0.2032 0.3048)
						)
						(arc
							(start 0.2032 0.3048)
							(mid 0.275042 0.275042)
							(end 0.3048 0.2032)
						)
					)
					(width 0)
					(fill yes)
				)
			)
		)
		(pad "2" smd custom
			(at 0 0.4445)
			(size 0.1524 0.1524)
			(layers "F.Cu" "F.Mask" "F.Paste")
			(net "AGND_CURRENT_DPB")
			(options
				(clearance outline)
				(anchor circle)
			)
			(primitives
				(gr_poly
					(pts
						(arc
							(start 0.3048 -0.2032)
							(mid 0.275042 -0.275042)
							(end 0.2032 -0.3048)
						)
						(arc
							(start -0.2032 -0.3048)
							(mid -0.275042 -0.275042)
							(end -0.3048 -0.2032)
						)
						(arc
							(start -0.3048 0.2032)
							(mid -0.275042 0.275042)
							(end -0.2032 0.3048)
						)
						(arc
							(start 0.2032 0.3048)
							(mid 0.275042 0.275042)
							(end 0.3048 0.2032)
						)
					)
					(width 0)
					(fill yes)
				)
			)
		)
	)
	(footprint ""
		(layer "F.Cu")
		(at 406.554178 -99.756976 180)
		(property "Reference" "Q240"
			(at 0 0 180)
			(layer "F.SilkS")
			(hide yes)
			(effects
				(font
					(size 1.27 1.27)
				)
			)
		)
		(property "Value" "2N7002K-2-GP"
			(at 0.127 -8.9662 180)
			(unlocked yes)
			(layer "F.Fab")
			(hide yes)
			(effects
				(font
					(size 1.016 1.016)
					(thickness 0.1524)
				)
			)
		)
		(property "Device Type" "SOT23DGS2D4H44"
			(at 0.127 -10.4902 180)
			(unlocked yes)
			(layer "F.Fab")
			(hide yes)
			(effects
				(font
					(size 1.016 1.016)
					(thickness 0.1524)
				)
			)
		)
		(duplicate_pad_numbers_are_jumpers no)
		(fp_line
			(start 1.651 1.778)
			(end 1.651 -1.778)
			(stroke
				(width 0.1524)
				(type default)
			)
			(layer "F.SilkS")
		)
		(fp_line
			(start 1.651 -1.778)
			(end -1.651 -1.778)
			(stroke
				(width 0.1524)
				(type default)
			)
			(layer "F.SilkS")
		)
		(fp_line
			(start -1.651 1.778)
			(end 1.651 1.778)
			(stroke
				(width 0.1524)
				(type default)
			)
			(layer "F.SilkS")
		)
		(fp_line
			(start -1.651 -1.778)
			(end -1.651 1.778)
			(stroke
				(width 0.1524)
				(type default)
			)
			(layer "F.SilkS")
		)
		(fp_poly
			(pts
				(xy -1.778 1.8796) (xy -1.778 -1.8796) (xy 1.778 -1.8796) (xy 1.778 1.8796)
			)
			(stroke
				(width 0)
				(type default)
			)
			(fill no)
			(layer "F.CrtYd")
		)
		(fp_poly
			(pts
				(xy -1.778 1.8796) (xy -1.778 -1.8796) (xy 1.778 -1.8796) (xy 1.778 1.8796)
			)
			(stroke
				(width 0)
				(type default)
			)
			(fill no)
			(layer "F.Fab")
		)
		(pad "D" smd custom
			(at 0 -0.9525 180)
			(size 0.1905 0.1905)
			(layers "F.Cu" "F.Mask" "F.Paste")
			(net "FLT_HDD21_N")
			(options
				(clearance outline)
				(anchor circle)
			)
			(primitives
				(gr_poly
					(pts
						(arc
							(start -0.1778 0.5715)
							(mid -0.321484 0.511984)
							(end -0.381 0.3683)
						)
						(arc
							(start -0.381 -0.3683)
							(mid -0.321484 -0.511984)
							(end -0.1778 -0.5715)
						)
						(arc
							(start 0.1778 -0.5715)
							(mid 0.321484 -0.511984)
							(end 0.381 -0.3683)
						)
						(arc
							(start 0.381 0.3683)
							(mid 0.321484 0.511984)
							(end 0.1778 0.5715)
						)
					)
					(width 0)
					(fill yes)
				)
			)
		)
		(pad "G" smd custom
			(at -0.98425 0.9525 180)
			(size 0.1905 0.1905)
			(layers "F.Cu" "F.Mask" "F.Paste")
			(net "DRIVE_B_21_FLT_LED")
			(options
				(clearance outline)
				(anchor circle)
			)
			(primitives
				(gr_poly
					(pts
						(arc
							(start -0.1778 0.5715)
							(mid -0.321484 0.511984)
							(end -0.381 0.3683)
						)
						(arc
							(start -0.381 -0.3683)
							(mid -0.321484 -0.511984)
							(end -0.1778 -0.5715)
						)
						(arc
							(start 0.1778 -0.5715)
							(mid 0.321484 -0.511984)
							(end 0.381 -0.3683)
						)
						(arc
							(start 0.381 0.3683)
							(mid 0.321484 0.511984)
							(end 0.1778 0.5715)
						)
					)
					(width 0)
					(fill yes)
				)
			)
		)
		(pad "S" smd custom
			(at 0.98425 0.9525 180)
			(size 0.1905 0.1905)
			(layers "F.Cu" "F.Mask" "F.Paste")
			(net "GND")
			(options
				(clearance outline)
				(anchor circle)
			)
			(primitives
				(gr_poly
					(pts
						(arc
							(start -0.1778 0.5715)
							(mid -0.321484 0.511984)
							(end -0.381 0.3683)
						)
						(arc
							(start -0.381 -0.3683)
							(mid -0.321484 -0.511984)
							(end -0.1778 -0.5715)
						)
						(arc
							(start 0.1778 -0.5715)
							(mid 0.321484 -0.511984)
							(end 0.381 -0.3683)
						)
						(arc
							(start 0.381 0.3683)
							(mid 0.321484 0.511984)
							(end 0.1778 0.5715)
						)
					)
					(width 0)
					(fill yes)
				)
			)
		)
	)
	(footprint ""
		(layer "F.Cu")
		(at 207.3402 -196.088 90)
		(property "Reference" "R27"
			(at 0 0 90)
			(layer "F.SilkS")
			(hide yes)
			(effects
				(font
					(size 1.27 1.27)
				)
			)
		)
		(property "Value" "4K7R2F-GP"
			(at 0.064008 -3.993896 90)
			(unlocked yes)
			(layer "F.Fab")
			(hide yes)
			(effects
				(font
					(size 1.016 1.016)
					(thickness 0.1524)
				)
			)
		)
		(property "Device Type" "R402H16"
			(at 0.064008 -5.517896 90)
			(unlocked yes)
			(layer "F.Fab")
			(hide yes)
			(effects
				(font
					(size 1.016 1.016)
					(thickness 0.1524)
				)
			)
		)
		(duplicate_pad_numbers_are_jumpers no)
		(fp_line
			(start 0.508 -0.9398)
			(end -0.508 -0.9398)
			(stroke
				(width 0.1524)
				(type default)
			)
			(layer "F.SilkS")
		)
		(fp_line
			(start -0.508 -0.9398)
			(end -0.508 0.9398)
			(stroke
				(width 0.1524)
				(type default)
			)
			(layer "F.SilkS")
		)
		(fp_rect
			(start -0.508 0.9398)
			(end 0.508 -0.9398)
			(stroke
				(width 0)
				(type default)
			)
			(fill no)
			(layer "F.CrtYd")
		)
		(fp_rect
			(start -0.508 0.9398)
			(end 0.508 -0.9398)
			(stroke
				(width 0)
				(type default)
			)
			(fill no)
			(layer "F.Fab")
		)
		(pad "1" smd custom
			(at 0 -0.4445 90)
			(size 0.1397 0.1397)
			(layers "F.Cu" "F.Mask" "F.Paste")
			(net "P3V3_STBY_B")
			(options
				(clearance outline)
				(anchor circle)
			)
			(primitives
				(gr_poly
					(pts
						(arc
							(start -0.1778 -0.2794)
							(mid -0.249642 -0.249642)
							(end -0.2794 -0.1778)
						)
						(arc
							(start -0.2794 0.1778)
							(mid -0.249642 0.249642)
							(end -0.1778 0.2794)
						)
						(arc
							(start 0.1778 0.2794)
							(mid 0.249642 0.249642)
							(end 0.2794 0.1778)
						)
						(arc
							(start 0.2794 -0.1778)
							(mid 0.249642 -0.249642)
							(end 0.1778 -0.2794)
						)
					)
					(width 0)
					(fill yes)
				)
			)
		)
		(pad "2" smd custom
			(at 0 0.4445 90)
			(size 0.1397 0.1397)
			(layers "F.Cu" "F.Mask" "F.Paste")
			(net "IO_EXP2_HDD_FAULT_A2")
			(options
				(clearance outline)
				(anchor circle)
			)
			(primitives
				(gr_poly
					(pts
						(arc
							(start -0.1778 -0.2794)
							(mid -0.249642 -0.249642)
							(end -0.2794 -0.1778)
						)
						(arc
							(start -0.2794 0.1778)
							(mid -0.249642 0.249642)
							(end -0.1778 0.2794)
						)
						(arc
							(start 0.1778 0.2794)
							(mid 0.249642 0.249642)
							(end 0.2794 0.1778)
						)
						(arc
							(start 0.2794 -0.1778)
							(mid 0.249642 -0.249642)
							(end 0.1778 -0.2794)
						)
					)
					(width 0)
					(fill yes)
				)
			)
		)
	)
	(footprint ""
		(layer "F.Cu")
		(at 33.4264 -31.5976 180)
		(property "Reference" "R622"
			(at 0 0 180)
			(layer "F.SilkS")
			(hide yes)
			(effects
				(font
					(size 1.27 1.27)
				)
			)
		)
		(property "Value" "10KR2F-2-GP"
			(at 0.064008 -3.993896 180)
			(unlocked yes)
			(layer "F.Fab")
			(hide yes)
			(effects
				(font
					(size 1.016 1.016)
					(thickness 0.1524)
				)
			)
		)
		(property "Device Type" "R402H16"
			(at 0.064008 -5.517896 180)
			(unlocked yes)
			(layer "F.Fab")
			(hide yes)
			(effects
				(font
					(size 1.016 1.016)
					(thickness 0.1524)
				)
			)
		)
		(duplicate_pad_numbers_are_jumpers no)
		(fp_line
			(start 0.508 -0.9398)
			(end -0.508 -0.9398)
			(stroke
				(width 0.1524)
				(type default)
			)
			(layer "F.SilkS")
		)
		(fp_line
			(start -0.508 -0.9398)
			(end -0.508 0.9398)
			(stroke
				(width 0.1524)
				(type default)
			)
			(layer "F.SilkS")
		)
		(fp_rect
			(start -0.508 0.9398)
			(end 0.508 -0.9398)
			(stroke
				(width 0)
				(type default)
			)
			(fill no)
			(layer "F.CrtYd")
		)
		(fp_rect
			(start -0.508 0.9398)
			(end 0.508 -0.9398)
			(stroke
				(width 0)
				(type default)
			)
			(fill no)
			(layer "F.Fab")
		)
		(pad "1" smd custom
			(at 0 -0.4445 180)
			(size 0.1397 0.1397)
			(layers "F.Cu" "F.Mask" "F.Paste")
			(net "P3V3_STBY_B")
			(options
				(clearance outline)
				(anchor circle)
			)
			(primitives
				(gr_poly
					(pts
						(arc
							(start -0.1778 -0.2794)
							(mid -0.249642 -0.249642)
							(end -0.2794 -0.1778)
						)
						(arc
							(start -0.2794 0.1778)
							(mid -0.249642 0.249642)
							(end -0.1778 0.2794)
						)
						(arc
							(start 0.1778 0.2794)
							(mid 0.249642 0.249642)
							(end 0.2794 0.1778)
						)
						(arc
							(start 0.2794 -0.1778)
							(mid 0.249642 -0.249642)
							(end 0.1778 -0.2794)
						)
					)
					(width 0)
					(fill yes)
				)
			)
		)
		(pad "2" smd custom
			(at 0 0.4445 180)
			(size 0.1397 0.1397)
			(layers "F.Cu" "F.Mask" "F.Paste")
			(net "HDD_PRSNT_24")
			(options
				(clearance outline)
				(anchor circle)
			)
			(primitives
				(gr_poly
					(pts
						(arc
							(start -0.1778 -0.2794)
							(mid -0.249642 -0.249642)
							(end -0.2794 -0.1778)
						)
						(arc
							(start -0.2794 0.1778)
							(mid -0.249642 0.249642)
							(end -0.1778 0.2794)
						)
						(arc
							(start 0.1778 0.2794)
							(mid 0.249642 0.249642)
							(end 0.2794 0.1778)
						)
						(arc
							(start 0.2794 -0.1778)
							(mid 0.249642 -0.249642)
							(end 0.1778 -0.2794)
						)
					)
					(width 0)
					(fill yes)
				)
			)
		)
	)
	(footprint ""
		(layer "F.Cu")
		(at 206.62138 -241.66322 180)
		(property "Reference" "U5"
			(at 0 0 180)
			(layer "F.SilkS")
			(hide yes)
			(effects
				(font
					(size 1.27 1.27)
				)
			)
		)
		(property "Value" "TCA9555PWR-GP"
			(at 0 -6.9342 180)
			(unlocked yes)
			(layer "F.Fab")
			(hide yes)
			(effects
				(font
					(size 1.016 1.016)
					(thickness 0.1524)
				)
			)
		)
		(property "Device Type" "TSOIC24H48"
			(at 0 -8.5852 180)
			(unlocked yes)
			(layer "F.Fab")
			(hide yes)
			(effects
				(font
					(size 1.016 1.016)
					(thickness 0.1524)
				)
			)
		)
		(duplicate_pad_numbers_are_jumpers no)
		(fp_line
			(start 3.81 1.397)
			(end -4.2291 1.397)
			(stroke
				(width 0.1524)
				(type default)
			)
			(layer "F.SilkS")
		)
		(fp_line
			(start 3.81 -1.397)
			(end 3.81 1.397)
			(stroke
				(width 0.1524)
				(type default)
			)
			(layer "F.SilkS")
		)
		(fp_line
			(start -3.429 0)
			(end -4.2291 0.8001)
			(stroke
				(width 0.1524)
				(type default)
			)
			(layer "F.SilkS")
		)
		(fp_line
			(start -4.22656 3.81)
			(end -4.2291 1.397)
			(stroke
				(width 0.508)
				(type default)
			)
			(layer "F.SilkS")
		)
		(fp_line
			(start -4.2291 3.937)
			(end -4.2291 -1.397)
			(stroke
				(width 0.1524)
				(type default)
			)
			(layer "F.SilkS")
		)
		(fp_line
			(start -4.2291 -0.8001)
			(end -3.429 0)
			(stroke
				(width 0.1524)
				(type default)
			)
			(layer "F.SilkS")
		)
		(fp_line
			(start -4.2291 -1.397)
			(end 3.81 -1.397)
			(stroke
				(width 0.1524)
				(type default)
			)
			(layer "F.SilkS")
		)
		(fp_poly
			(pts
				(xy -3.90652 -1.8542) (xy 3.90652 -1.8542) (xy 3.90652 1.8542) (xy -3.90652 1.8542)
			)
			(stroke
				(width 0)
				(type default)
			)
			(fill yes)
			(layer "F.SilkS")
		)
		(fp_poly
			(pts
				(xy -4.2164 3.81) (xy 4.2164 3.81) (xy 4.22656 -3.81) (xy -4.2164 -3.81)
			)
			(stroke
				(width 0)
				(type default)
			)
			(fill no)
			(layer "F.CrtYd")
		)
		(fp_poly
			(pts
				(xy -4.22656 -3.81) (xy 4.22656 -3.81) (xy 4.22656 3.81) (xy -4.22656 3.81)
			)
			(stroke
				(width 0)
				(type default)
			)
			(fill no)
			(layer "F.Fab")
		)
		(pad "1" smd rect
			(at -3.57632 2.8194 180)
			(size 0.3556 1.524)
			(layers "F.Cu" "F.Mask" "F.Paste")
			(net "IO_EXP4_INT_N")
		)
		(pad "2" smd rect
			(at -2.92608 2.8194 180)
			(size 0.3556 1.524)
			(layers "F.Cu" "F.Mask" "F.Paste")
			(net "IO_EXP4_A1")
		)
		(pad "3" smd rect
			(at -2.27584 2.8194 180)
			(size 0.3556 1.524)
			(layers "F.Cu" "F.Mask" "F.Paste")
			(net "IO_EXP4_A2")
		)
		(pad "4" smd rect
			(at -1.6256 2.8194 180)
			(size 0.3556 1.524)
			(layers "F.Cu" "F.Mask" "F.Paste")
			(net "DRIVE_B_0_INS")
		)
		(pad "5" smd rect
			(at -0.97536 2.8194 180)
			(size 0.3556 1.524)
			(layers "F.Cu" "F.Mask" "F.Paste")
			(net "DRIVE_B_1_INS")
		)
		(pad "6" smd rect
			(at -0.32512 2.8194 180)
			(size 0.3556 1.524)
			(layers "F.Cu" "F.Mask" "F.Paste")
			(net "DRIVE_B_2_INS")
		)
		(pad "7" smd rect
			(at 0.32512 2.8194 180)
			(size 0.3556 1.524)
			(layers "F.Cu" "F.Mask" "F.Paste")
			(net "DRIVE_B_3_INS")
		)
		(pad "8" smd rect
			(at 0.97536 2.8194 180)
			(size 0.3556 1.524)
			(layers "F.Cu" "F.Mask" "F.Paste")
			(net "DRIVE_B_4_INS")
		)
		(pad "9" smd rect
			(at 1.6256 2.8194 180)
			(size 0.3556 1.524)
			(layers "F.Cu" "F.Mask" "F.Paste")
			(net "DRIVE_B_5_INS")
		)
		(pad "10" smd rect
			(at 2.27584 2.8194 180)
			(size 0.3556 1.524)
			(layers "F.Cu" "F.Mask" "F.Paste")
			(net "DRIVE_B_6_INS")
		)
		(pad "11" smd rect
			(at 2.92608 2.8194 180)
			(size 0.3556 1.524)
			(layers "F.Cu" "F.Mask" "F.Paste")
			(net "DRIVE_B_7_INS")
		)
		(pad "12" smd rect
			(at 3.57632 2.8194 180)
			(size 0.3556 1.524)
			(layers "F.Cu" "F.Mask" "F.Paste")
			(net "GND")
		)
		(pad "13" smd rect
			(at 3.57632 -2.8194 180)
			(size 0.3556 1.524)
			(layers "F.Cu" "F.Mask" "F.Paste")
			(net "DRIVE_B_8_INS")
		)
		(pad "14" smd rect
			(at 2.92608 -2.8194 180)
			(size 0.3556 1.524)
			(layers "F.Cu" "F.Mask" "F.Paste")
			(net "DRIVE_B_9_INS")
		)
		(pad "15" smd rect
			(at 2.27584 -2.8194 180)
			(size 0.3556 1.524)
			(layers "F.Cu" "F.Mask" "F.Paste")
			(net "DRIVE_B_10_INS")
		)
		(pad "16" smd rect
			(at 1.6256 -2.8194 180)
			(size 0.3556 1.524)
			(layers "F.Cu" "F.Mask" "F.Paste")
			(net "DRIVE_B_11_INS")
		)
		(pad "17" smd rect
			(at 0.97536 -2.8194 180)
			(size 0.3556 1.524)
			(layers "F.Cu" "F.Mask" "F.Paste")
			(net "DRIVE_B_12_INS")
		)
		(pad "18" smd rect
			(at 0.32512 -2.8194 180)
			(size 0.3556 1.524)
			(layers "F.Cu" "F.Mask" "F.Paste")
			(net "DRIVE_B_13_INS")
		)
		(pad "19" smd rect
			(at -0.32512 -2.8194 180)
			(size 0.3556 1.524)
			(layers "F.Cu" "F.Mask" "F.Paste")
			(net "DRIVE_B_14_INS")
		)
		(pad "20" smd rect
			(at -0.97536 -2.8194 180)
			(size 0.3556 1.524)
			(layers "F.Cu" "F.Mask" "F.Paste")
			(net "DRIVE_B_15_INS")
		)
		(pad "21" smd rect
			(at -1.6256 -2.8194 180)
			(size 0.3556 1.524)
			(layers "F.Cu" "F.Mask" "F.Paste")
			(net "IO_EXP4_A0")
		)
		(pad "22" smd rect
			(at -2.27584 -2.8194 180)
			(size 0.3556 1.524)
			(layers "F.Cu" "F.Mask" "F.Paste")
			(net "IO_EXP4_SCL")
		)
		(pad "23" smd rect
			(at -2.92608 -2.8194 180)
			(size 0.3556 1.524)
			(layers "F.Cu" "F.Mask" "F.Paste")
			(net "IO_EXP4_SDA")
		)
		(pad "24" smd rect
			(at -3.57632 -2.8194 180)
			(size 0.3556 1.524)
			(layers "F.Cu" "F.Mask" "F.Paste")
			(net "P3V3_STBY_B")
		)
	)
	(footprint ""
		(layer "F.Cu")
		(at 41.679368 -213.590378 90)
		(property "Reference" "Q244"
			(at 0 0 90)
			(layer "F.SilkS")
			(hide yes)
			(effects
				(font
					(size 1.27 1.27)
				)
			)
		)
		(property "Value" "SSM3K324R-GP"
			(at 0.127 -8.9662 90)
			(unlocked yes)
			(layer "F.Fab")
			(hide yes)
			(effects
				(font
					(size 1.016 1.016)
					(thickness 0.1524)
				)
			)
		)
		(property "Device Type" "SOT23DGS2D4H35"
			(at 0.127 -10.4902 90)
			(unlocked yes)
			(layer "F.Fab")
			(hide yes)
			(effects
				(font
					(size 1.016 1.016)
					(thickness 0.1524)
				)
			)
		)
		(duplicate_pad_numbers_are_jumpers no)
		(fp_line
			(start 1.651 -1.778)
			(end -1.651 -1.778)
			(stroke
				(width 0.1524)
				(type default)
			)
			(layer "F.SilkS")
		)
		(fp_line
			(start -1.651 -1.778)
			(end -1.651 1.778)
			(stroke
				(width 0.1524)
				(type default)
			)
			(layer "F.SilkS")
		)
		(fp_line
			(start 1.651 1.778)
			(end 1.651 -1.778)
			(stroke
				(width 0.1524)
				(type default)
			)
			(layer "F.SilkS")
		)
		(fp_line
			(start -1.651 1.778)
			(end 1.651 1.778)
			(stroke
				(width 0.1524)
				(type default)
			)
			(layer "F.SilkS")
		)
		(fp_poly
			(pts
				(xy -1.778 1.8796) (xy -1.778 -1.8796) (xy 1.778 -1.8796) (xy 1.778 1.8796)
			)
			(stroke
				(width 0)
				(type default)
			)
			(fill no)
			(layer "F.CrtYd")
		)
		(fp_poly
			(pts
				(xy -1.778 1.8796) (xy -1.778 -1.8796) (xy 1.778 -1.8796) (xy 1.778 1.8796)
			)
			(stroke
				(width 0)
				(type default)
			)
			(fill no)
			(layer "F.Fab")
		)
		(pad "D" smd custom
			(at 0 -0.9525 90)
			(size 0.1905 0.1905)
			(layers "F.Cu" "F.Mask" "F.Paste")
			(net "DRV_ACT_1_N")
			(options
				(clearance outline)
				(anchor circle)
			)
			(primitives
				(gr_poly
					(pts
						(arc
							(start -0.1778 0.5715)
							(mid -0.321484 0.511984)
							(end -0.381 0.3683)
						)
						(arc
							(start -0.381 -0.3683)
							(mid -0.321484 -0.511984)
							(end -0.1778 -0.5715)
						)
						(arc
							(start 0.1778 -0.5715)
							(mid 0.321484 -0.511984)
							(end 0.381 -0.3683)
						)
						(arc
							(start 0.381 0.3683)
							(mid 0.321484 0.511984)
							(end 0.1778 0.5715)
						)
					)
					(width 0)
					(fill yes)
				)
			)
		)
		(pad "G" smd custom
			(at -0.98425 0.9525 90)
			(size 0.1905 0.1905)
			(layers "F.Cu" "F.Mask" "F.Paste")
			(net "DRIVE_B_1_ACT")
			(options
				(clearance outline)
				(anchor circle)
			)
			(primitives
				(gr_poly
					(pts
						(arc
							(start -0.1778 0.5715)
							(mid -0.321484 0.511984)
							(end -0.381 0.3683)
						)
						(arc
							(start -0.381 -0.3683)
							(mid -0.321484 -0.511984)
							(end -0.1778 -0.5715)
						)
						(arc
							(start 0.1778 -0.5715)
							(mid 0.321484 -0.511984)
							(end 0.381 -0.3683)
						)
						(arc
							(start 0.381 0.3683)
							(mid 0.321484 0.511984)
							(end 0.1778 0.5715)
						)
					)
					(width 0)
					(fill yes)
				)
			)
		)
		(pad "S" smd custom
			(at 0.98425 0.9525 90)
			(size 0.1905 0.1905)
			(layers "F.Cu" "F.Mask" "F.Paste")
			(net "GND")
			(options
				(clearance outline)
				(anchor circle)
			)
			(primitives
				(gr_poly
					(pts
						(arc
							(start -0.1778 0.5715)
							(mid -0.321484 0.511984)
							(end -0.381 0.3683)
						)
						(arc
							(start -0.381 -0.3683)
							(mid -0.321484 -0.511984)
							(end -0.1778 -0.5715)
						)
						(arc
							(start 0.1778 -0.5715)
							(mid 0.321484 -0.511984)
							(end 0.381 -0.3683)
						)
						(arc
							(start 0.381 0.3683)
							(mid 0.321484 0.511984)
							(end 0.1778 0.5715)
						)
					)
					(width 0)
					(fill yes)
				)
			)
		)
	)
	(footprint ""
		(layer "F.Cu")
		(at 54.483 -134.493 90)
		(property "Reference" "R381"
			(at 0 0 90)
			(layer "F.SilkS")
			(hide yes)
			(effects
				(font
					(size 1.27 1.27)
				)
			)
		)
		(property "Value" "4K7R2F-GP"
			(at 0.064008 -3.993896 90)
			(unlocked yes)
			(layer "F.Fab")
			(hide yes)
			(effects
				(font
					(size 1.016 1.016)
					(thickness 0.1524)
				)
			)
		)
		(property "Device Type" "R402H16"
			(at 0.064008 -5.517896 90)
			(unlocked yes)
			(layer "F.Fab")
			(hide yes)
			(effects
				(font
					(size 1.016 1.016)
					(thickness 0.1524)
				)
			)
		)
		(duplicate_pad_numbers_are_jumpers no)
		(fp_line
			(start 0.508 -0.9398)
			(end -0.508 -0.9398)
			(stroke
				(width 0.1524)
				(type default)
			)
			(layer "F.SilkS")
		)
		(fp_line
			(start -0.508 -0.9398)
			(end -0.508 0.9398)
			(stroke
				(width 0.1524)
				(type default)
			)
			(layer "F.SilkS")
		)
		(fp_rect
			(start -0.508 0.9398)
			(end 0.508 -0.9398)
			(stroke
				(width 0)
				(type default)
			)
			(fill no)
			(layer "F.CrtYd")
		)
		(fp_rect
			(start -0.508 0.9398)
			(end 0.508 -0.9398)
			(stroke
				(width 0)
				(type default)
			)
			(fill no)
			(layer "F.Fab")
		)
		(pad "1" smd custom
			(at 0 -0.4445 90)
			(size 0.1397 0.1397)
			(layers "F.Cu" "F.Mask" "F.Paste")
			(net "SW_PWR_R_HDD13")
			(options
				(clearance outline)
				(anchor circle)
			)
			(primitives
				(gr_poly
					(pts
						(arc
							(start -0.1778 -0.2794)
							(mid -0.249642 -0.249642)
							(end -0.2794 -0.1778)
						)
						(arc
							(start -0.2794 0.1778)
							(mid -0.249642 0.249642)
							(end -0.1778 0.2794)
						)
						(arc
							(start 0.1778 0.2794)
							(mid 0.249642 0.249642)
							(end 0.2794 0.1778)
						)
						(arc
							(start 0.2794 -0.1778)
							(mid 0.249642 -0.249642)
							(end 0.1778 -0.2794)
						)
					)
					(width 0)
					(fill yes)
				)
			)
		)
		(pad "2" smd custom
			(at 0 0.4445 90)
			(size 0.1397 0.1397)
			(layers "F.Cu" "F.Mask" "F.Paste")
			(net "GND")
			(options
				(clearance outline)
				(anchor circle)
			)
			(primitives
				(gr_poly
					(pts
						(arc
							(start -0.1778 -0.2794)
							(mid -0.249642 -0.249642)
							(end -0.2794 -0.1778)
						)
						(arc
							(start -0.2794 0.1778)
							(mid -0.249642 0.249642)
							(end -0.1778 0.2794)
						)
						(arc
							(start 0.1778 0.2794)
							(mid 0.249642 0.249642)
							(end 0.2794 0.1778)
						)
						(arc
							(start 0.2794 -0.1778)
							(mid 0.249642 -0.249642)
							(end 0.1778 -0.2794)
						)
					)
					(width 0)
					(fill yes)
				)
			)
		)
	)
	(footprint ""
		(layer "F.Cu")
		(at 457.003404 -370.8908 180)
		(property "Reference" "U52"
			(at 0 0 180)
			(layer "F.SilkS")
			(hide yes)
			(effects
				(font
					(size 1.27 1.27)
				)
			)
		)
		(property "Value" "SN74LVC1G08DCKR-GP"
			(at -2.3368 -8.6868 180)
			(unlocked yes)
			(layer "F.Fab")
			(hide yes)
			(effects
				(font
					(size 1.016 1.016)
					(thickness 0.1524)
				)
			)
		)
		(property "Device Type" "SC70-5H44"
			(at -2.3114 -10.414 180)
			(unlocked yes)
			(layer "F.Fab")
			(hide yes)
			(effects
				(font
					(size 1.016 1.016)
					(thickness 0.1524)
				)
			)
		)
		(duplicate_pad_numbers_are_jumpers no)
		(fp_line
			(start 1.3843 -1.8034)
			(end 1.3843 -1.1176)
			(stroke
				(width 0.3302)
				(type default)
			)
			(layer "F.SilkS")
		)
		(fp_line
			(start 1.27 1.7018)
			(end -1.27 1.7018)
			(stroke
				(width 0.1524)
				(type default)
			)
			(layer "F.SilkS")
		)
		(fp_line
			(start 1.27 -1.7018)
			(end 1.27 1.7018)
			(stroke
				(width 0.1524)
				(type default)
			)
			(layer "F.SilkS")
		)
		(fp_line
			(start 0.6604 -1.8034)
			(end 1.3843 -1.8034)
			(stroke
				(width 0.3302)
				(type default)
			)
			(layer "F.SilkS")
		)
		(fp_line
			(start -1.27 1.7018)
			(end -1.27 -1.7018)
			(stroke
				(width 0.1524)
				(type default)
			)
			(layer "F.SilkS")
		)
		(fp_line
			(start -1.27 -1.7018)
			(end 1.27 -1.7018)
			(stroke
				(width 0.1524)
				(type default)
			)
			(layer "F.SilkS")
		)
		(fp_rect
			(start -1.524 1.9558)
			(end 1.524 -1.9558)
			(stroke
				(width 0)
				(type default)
			)
			(fill no)
			(layer "F.CrtYd")
		)
		(fp_poly
			(pts
				(xy -1.524 -1.9558) (xy 1.524 -1.9558) (xy 1.524 1.9558) (xy -1.524 1.9558)
			)
			(stroke
				(width 0)
				(type default)
			)
			(fill no)
			(layer "F.Fab")
		)
		(pad "1" smd rect
			(at 0.65024 -0.8255 180)
			(size 0.4064 1.2192)
			(layers "F.Cu" "F.Mask" "F.Paste")
			(net "RDPB_FAN_LED3")
		)
		(pad "2" smd rect
			(at 0 -0.8255 180)
			(size 0.4064 1.2192)
			(layers "F.Cu" "F.Mask" "F.Paste")
			(net "FDPB_FAN_LED3")
		)
		(pad "3" smd rect
			(at -0.65024 -0.8255 180)
			(size 0.4064 1.2192)
			(layers "F.Cu" "F.Mask" "F.Paste")
			(net "GND")
		)
		(pad "4" smd rect
			(at -0.65024 0.8255 180)
			(size 0.4064 1.2192)
			(layers "F.Cu" "F.Mask" "F.Paste")
			(net "FAN_LED3")
		)
		(pad "5" smd rect
			(at 0.65024 0.8255 180)
			(size 0.4064 1.2192)
			(layers "F.Cu" "F.Mask" "F.Paste")
			(net "P3V3_IN")
		)
	)
	(footprint ""
		(layer "F.Cu")
		(at 406.554178 -214.757 180)
		(property "Reference" "Q228"
			(at 0 0 180)
			(layer "F.SilkS")
			(hide yes)
			(effects
				(font
					(size 1.27 1.27)
				)
			)
		)
		(property "Value" "2N7002K-2-GP"
			(at 0.127 -8.9662 180)
			(unlocked yes)
			(layer "F.Fab")
			(hide yes)
			(effects
				(font
					(size 1.016 1.016)
					(thickness 0.1524)
				)
			)
		)
		(property "Device Type" "SOT23DGS2D4H44"
			(at 0.127 -10.4902 180)
			(unlocked yes)
			(layer "F.Fab")
			(hide yes)
			(effects
				(font
					(size 1.016 1.016)
					(thickness 0.1524)
				)
			)
		)
		(duplicate_pad_numbers_are_jumpers no)
		(fp_line
			(start 1.651 1.778)
			(end 1.651 -1.778)
			(stroke
				(width 0.1524)
				(type default)
			)
			(layer "F.SilkS")
		)
		(fp_line
			(start 1.651 -1.778)
			(end -1.651 -1.778)
			(stroke
				(width 0.1524)
				(type default)
			)
			(layer "F.SilkS")
		)
		(fp_line
			(start -1.651 1.778)
			(end 1.651 1.778)
			(stroke
				(width 0.1524)
				(type default)
			)
			(layer "F.SilkS")
		)
		(fp_line
			(start -1.651 -1.778)
			(end -1.651 1.778)
			(stroke
				(width 0.1524)
				(type default)
			)
			(layer "F.SilkS")
		)
		(fp_poly
			(pts
				(xy -1.778 1.8796) (xy -1.778 -1.8796) (xy 1.778 -1.8796) (xy 1.778 1.8796)
			)
			(stroke
				(width 0)
				(type default)
			)
			(fill no)
			(layer "F.CrtYd")
		)
		(fp_poly
			(pts
				(xy -1.778 1.8796) (xy -1.778 -1.8796) (xy 1.778 -1.8796) (xy 1.778 1.8796)
			)
			(stroke
				(width 0)
				(type default)
			)
			(fill no)
			(layer "F.Fab")
		)
		(pad "D" smd custom
			(at 0 -0.9525 180)
			(size 0.1905 0.1905)
			(layers "F.Cu" "F.Mask" "F.Paste")
			(net "FLT_HDD9_N")
			(options
				(clearance outline)
				(anchor circle)
			)
			(primitives
				(gr_poly
					(pts
						(arc
							(start -0.1778 0.5715)
							(mid -0.321484 0.511984)
							(end -0.381 0.3683)
						)
						(arc
							(start -0.381 -0.3683)
							(mid -0.321484 -0.511984)
							(end -0.1778 -0.5715)
						)
						(arc
							(start 0.1778 -0.5715)
							(mid 0.321484 -0.511984)
							(end 0.381 -0.3683)
						)
						(arc
							(start 0.381 0.3683)
							(mid 0.321484 0.511984)
							(end 0.1778 0.5715)
						)
					)
					(width 0)
					(fill yes)
				)
			)
		)
		(pad "G" smd custom
			(at -0.98425 0.9525 180)
			(size 0.1905 0.1905)
			(layers "F.Cu" "F.Mask" "F.Paste")
			(net "DRIVE_B_9_FLT_LED")
			(options
				(clearance outline)
				(anchor circle)
			)
			(primitives
				(gr_poly
					(pts
						(arc
							(start -0.1778 0.5715)
							(mid -0.321484 0.511984)
							(end -0.381 0.3683)
						)
						(arc
							(start -0.381 -0.3683)
							(mid -0.321484 -0.511984)
							(end -0.1778 -0.5715)
						)
						(arc
							(start 0.1778 -0.5715)
							(mid 0.321484 -0.511984)
							(end 0.381 -0.3683)
						)
						(arc
							(start 0.381 0.3683)
							(mid 0.321484 0.511984)
							(end 0.1778 0.5715)
						)
					)
					(width 0)
					(fill yes)
				)
			)
		)
		(pad "S" smd custom
			(at 0.98425 0.9525 180)
			(size 0.1905 0.1905)
			(layers "F.Cu" "F.Mask" "F.Paste")
			(net "GND")
			(options
				(clearance outline)
				(anchor circle)
			)
			(primitives
				(gr_poly
					(pts
						(arc
							(start -0.1778 0.5715)
							(mid -0.321484 0.511984)
							(end -0.381 0.3683)
						)
						(arc
							(start -0.381 -0.3683)
							(mid -0.321484 -0.511984)
							(end -0.1778 -0.5715)
						)
						(arc
							(start 0.1778 -0.5715)
							(mid 0.321484 -0.511984)
							(end 0.381 -0.3683)
						)
						(arc
							(start 0.381 0.3683)
							(mid 0.321484 0.511984)
							(end 0.1778 0.5715)
						)
					)
					(width 0)
					(fill yes)
				)
			)
		)
	)
	(footprint ""
		(layer "F.Cu")
		(at 127.113284 -15.219426 90)
		(property "Reference" "C379"
			(at 0 0 90)
			(layer "F.SilkS")
			(hide yes)
			(effects
				(font
					(size 1.27 1.27)
				)
			)
		)
		(property "Value" "SCD01U16V1KX-GP"
			(at -2.8321 -1.7399 90)
			(unlocked yes)
			(layer "F.Fab")
			(hide yes)
			(effects
				(font
					(size 1.016 1.016)
					(thickness 0.1524)
				)
			)
		)
		(property "Device Type" "C0201H13"
			(at -2.8321 -3.2639 90)
			(unlocked yes)
			(layer "F.Fab")
			(hide yes)
			(effects
				(font
					(size 1.016 1.016)
					(thickness 0.1524)
				)
			)
		)
		(duplicate_pad_numbers_are_jumpers no)
		(fp_rect
			(start -0.2794 0.6477)
			(end 0.2794 -0.6477)
			(stroke
				(width 0)
				(type default)
			)
			(fill no)
			(layer "F.CrtYd")
		)
		(fp_rect
			(start -0.2794 0.6477)
			(end 0.2794 -0.6477)
			(stroke
				(width 0)
				(type default)
			)
			(fill no)
			(layer "F.Fab")
		)
		(pad "1" smd custom
			(at 0 -0.2794 90)
			(size 0.0762 0.0762)
			(layers "F.Cu" "F.Mask" "F.Paste")
			(net "SAS_HDD_RX_N27")
			(options
				(clearance outline)
				(anchor circle)
			)
			(primitives
				(gr_poly
					(pts
						(arc
							(start 0.1524 -0.127)
							(mid 0.137521 -0.162921)
							(end 0.1016 -0.1778)
						)
						(arc
							(start -0.1016 -0.1778)
							(mid -0.137521 -0.162921)
							(end -0.1524 -0.127)
						)
						(arc
							(start -0.1524 0.127)
							(mid -0.137521 0.162921)
							(end -0.1016 0.1778)
						)
						(arc
							(start 0.1016 0.1778)
							(mid 0.137521 0.162921)
							(end 0.1524 0.127)
						)
					)
					(width 0)
					(fill yes)
				)
			)
		)
		(pad "2" smd custom
			(at 0 0.2794 90)
			(size 0.0762 0.0762)
			(layers "F.Cu" "F.Mask" "F.Paste")
			(net "PHY_SCC_B_TO_DRV_B_27_DN")
			(options
				(clearance outline)
				(anchor circle)
			)
			(primitives
				(gr_poly
					(pts
						(arc
							(start 0.1524 -0.127)
							(mid 0.137521 -0.162921)
							(end 0.1016 -0.1778)
						)
						(arc
							(start -0.1016 -0.1778)
							(mid -0.137521 -0.162921)
							(end -0.1524 -0.127)
						)
						(arc
							(start -0.1524 0.127)
							(mid -0.137521 0.162921)
							(end -0.1016 0.1778)
						)
						(arc
							(start 0.1016 0.1778)
							(mid 0.137521 0.162921)
							(end 0.1524 0.127)
						)
					)
					(width 0)
					(fill yes)
				)
			)
		)
	)
	(footprint ""
		(layer "F.Cu")
		(at 478.409 -8.382 180)
		(property "Reference" "Q185"
			(at 0 0 180)
			(layer "F.SilkS")
			(hide yes)
			(effects
				(font
					(size 1.27 1.27)
				)
			)
		)
		(property "Value" "2N7002KDW-GP"
			(at -2.3622 -8.2042 180)
			(unlocked yes)
			(layer "F.Fab")
			(hide yes)
			(effects
				(font
					(size 1.016 1.016)
					(thickness 0.1524)
				)
			)
		)
		(property "Device Type" "SOT-363H44"
			(at -2.3622 -10.1092 180)
			(unlocked yes)
			(layer "F.Fab")
			(hide yes)
			(effects
				(font
					(size 1.016 1.016)
					(thickness 0.1524)
				)
			)
		)
		(duplicate_pad_numbers_are_jumpers no)
		(fp_line
			(start 1.4478 1.7018)
			(end 1.4478 -1.7018)
			(stroke
				(width 0.1524)
				(type default)
			)
			(layer "F.SilkS")
		)
		(fp_line
			(start 1.4478 -1.7018)
			(end -1.4478 -1.7018)
			(stroke
				(width 0.1524)
				(type default)
			)
			(layer "F.SilkS")
		)
		(fp_line
			(start -1.27 1.524)
			(end -1.27 0.6604)
			(stroke
				(width 0.4826)
				(type default)
			)
			(layer "F.SilkS")
		)
		(fp_line
			(start -1.4478 1.7018)
			(end 1.4478 1.7018)
			(stroke
				(width 0.1524)
				(type default)
			)
			(layer "F.SilkS")
		)
		(fp_line
			(start -1.4478 -1.7018)
			(end -1.4478 1.7018)
			(stroke
				(width 0.1524)
				(type default)
			)
			(layer "F.SilkS")
		)
		(fp_poly
			(pts
				(xy -1.524 -1.778) (xy 1.524 -1.778) (xy 1.524 1.778) (xy -1.524 1.778)
			)
			(stroke
				(width 0)
				(type default)
			)
			(fill no)
			(layer "F.CrtYd")
		)
		(fp_poly
			(pts
				(xy -1.524 -1.778) (xy 1.524 -1.778) (xy 1.524 1.778) (xy -1.524 1.778)
			)
			(stroke
				(width 0)
				(type default)
			)
			(fill no)
			(layer "F.Fab")
		)
		(pad "1" smd rect
			(at -0.65024 0.9398 180)
			(size 0.4064 1.016)
			(layers "F.Cu" "F.Mask" "F.Paste")
			(net "GND")
		)
		(pad "2" smd rect
			(at 0 0.9398 180)
			(size 0.4064 1.016)
			(layers "F.Cu" "F.Mask" "F.Paste")
			(net "SW_PWR_R_HDD35")
		)
		(pad "3" smd rect
			(at 0.65024 0.9398 180)
			(size 0.4064 1.016)
			(layers "F.Cu" "F.Mask" "F.Paste")
			(net "SW_HDD_P35")
		)
		(pad "4" smd rect
			(at 0.65024 -0.9398 180)
			(size 0.4064 1.016)
			(layers "F.Cu" "F.Mask" "F.Paste")
			(net "GND")
		)
		(pad "5" smd rect
			(at 0 -0.9398 180)
			(size 0.4064 1.016)
			(layers "F.Cu" "F.Mask" "F.Paste")
			(net "SW_HDD_G35")
		)
		(pad "6" smd rect
			(at -0.65024 -0.9398 180)
			(size 0.4064 1.016)
			(layers "F.Cu" "F.Mask" "F.Paste")
			(net "SW_HDD_R35")
		)
	)
	(footprint ""
		(layer "F.Cu")
		(at 87.376 -45.466 180)
		(property "Reference" "C374"
			(at 0 0 180)
			(layer "F.SilkS")
			(hide yes)
			(effects
				(font
					(size 1.27 1.27)
				)
			)
		)
		(property "Value" "SC1U25V3KX-GP"
			(at 0 -2.8194 180)
			(unlocked yes)
			(layer "F.Fab")
			(hide yes)
			(effects
				(font
					(size 1.016 1.016)
					(thickness 0.1524)
				)
			)
		)
		(property "Device Type" "C603H36"
			(at 0 -4.3434 180)
			(unlocked yes)
			(layer "F.Fab")
			(hide yes)
			(effects
				(font
					(size 1.016 1.016)
					(thickness 0.1524)
				)
			)
		)
		(duplicate_pad_numbers_are_jumpers no)
		(fp_line
			(start 0.508 0)
			(end -0.508 0)
			(stroke
				(width 0.2032)
				(type default)
			)
			(layer "F.SilkS")
		)
		(fp_rect
			(start -0.5842 1.3335)
			(end 0.5842 -1.3335)
			(stroke
				(width 0)
				(type default)
			)
			(fill no)
			(layer "F.CrtYd")
		)
		(fp_rect
			(start -0.5842 1.3335)
			(end 0.5842 -1.3335)
			(stroke
				(width 0)
				(type default)
			)
			(fill no)
			(layer "F.Fab")
		)
		(pad "1" smd custom
			(at 0 -0.762 180)
			(size 0.2159 0.2159)
			(layers "F.Cu" "F.Mask" "F.Paste")
			(net "P12V_HDD26")
			(options
				(clearance outline)
				(anchor circle)
			)
			(primitives
				(gr_poly
					(pts
						(arc
							(start -0.3302 -0.4318)
							(mid -0.402042 -0.402042)
							(end -0.4318 -0.3302)
						)
						(arc
							(start -0.4318 0.3302)
							(mid -0.402042 0.402042)
							(end -0.3302 0.4318)
						)
						(arc
							(start 0.3302 0.4318)
							(mid 0.402042 0.402042)
							(end 0.4318 0.3302)
						)
						(arc
							(start 0.4318 -0.3302)
							(mid 0.402042 -0.402042)
							(end 0.3302 -0.4318)
						)
					)
					(width 0)
					(fill yes)
				)
			)
		)
		(pad "2" smd custom
			(at 0 0.762 180)
			(size 0.2159 0.2159)
			(layers "F.Cu" "F.Mask" "F.Paste")
			(net "GND")
			(options
				(clearance outline)
				(anchor circle)
			)
			(primitives
				(gr_poly
					(pts
						(arc
							(start -0.3302 -0.4318)
							(mid -0.402042 -0.402042)
							(end -0.4318 -0.3302)
						)
						(arc
							(start -0.4318 0.3302)
							(mid -0.402042 0.402042)
							(end -0.3302 0.4318)
						)
						(arc
							(start 0.3302 0.4318)
							(mid 0.402042 0.402042)
							(end 0.4318 0.3302)
						)
						(arc
							(start 0.4318 -0.3302)
							(mid 0.402042 -0.402042)
							(end 0.3302 -0.4318)
						)
					)
					(width 0)
					(fill yes)
				)
			)
		)
	)
	(footprint ""
		(layer "F.Cu")
		(at 112.8776 -9.525)
		(property "Reference" "R706"
			(at 0 0 0)
			(layer "F.SilkS")
			(hide yes)
			(effects
				(font
					(size 1.27 1.27)
				)
			)
		)
		(property "Value" "300KR2F-GP"
			(at 0.064008 -3.993896 0)
			(unlocked yes)
			(layer "F.Fab")
			(hide yes)
			(effects
				(font
					(size 1.016 1.016)
					(thickness 0.1524)
				)
			)
		)
		(property "Device Type" "R402H16"
			(at 0.064008 -5.517896 0)
			(unlocked yes)
			(layer "F.Fab")
			(hide yes)
			(effects
				(font
					(size 1.016 1.016)
					(thickness 0.1524)
				)
			)
		)
		(duplicate_pad_numbers_are_jumpers no)
		(fp_line
			(start -0.508 -0.9398)
			(end -0.508 0.9398)
			(stroke
				(width 0.1524)
				(type default)
			)
			(layer "F.SilkS")
		)
		(fp_line
			(start 0.508 -0.9398)
			(end -0.508 -0.9398)
			(stroke
				(width 0.1524)
				(type default)
			)
			(layer "F.SilkS")
		)
		(fp_rect
			(start -0.508 0.9398)
			(end 0.508 -0.9398)
			(stroke
				(width 0)
				(type default)
			)
			(fill no)
			(layer "F.CrtYd")
		)
		(fp_rect
			(start -0.508 0.9398)
			(end 0.508 -0.9398)
			(stroke
				(width 0)
				(type default)
			)
			(fill no)
			(layer "F.Fab")
		)
		(pad "1" smd custom
			(at 0 -0.4445)
			(size 0.1397 0.1397)
			(layers "F.Cu" "F.Mask" "F.Paste")
			(net "SW_HDD_N27")
			(options
				(clearance outline)
				(anchor circle)
			)
			(primitives
				(gr_poly
					(pts
						(arc
							(start -0.1778 -0.2794)
							(mid -0.249642 -0.249642)
							(end -0.2794 -0.1778)
						)
						(arc
							(start -0.2794 0.1778)
							(mid -0.249642 0.249642)
							(end -0.1778 0.2794)
						)
						(arc
							(start 0.1778 0.2794)
							(mid 0.249642 0.249642)
							(end 0.2794 0.1778)
						)
						(arc
							(start 0.2794 -0.1778)
							(mid 0.249642 -0.249642)
							(end 0.1778 -0.2794)
						)
					)
					(width 0)
					(fill yes)
				)
			)
		)
		(pad "2" smd custom
			(at 0 0.4445)
			(size 0.1397 0.1397)
			(layers "F.Cu" "F.Mask" "F.Paste")
			(net "P12V_B")
			(options
				(clearance outline)
				(anchor circle)
			)
			(primitives
				(gr_poly
					(pts
						(arc
							(start -0.1778 -0.2794)
							(mid -0.249642 -0.249642)
							(end -0.2794 -0.1778)
						)
						(arc
							(start -0.2794 0.1778)
							(mid -0.249642 0.249642)
							(end -0.1778 0.2794)
						)
						(arc
							(start 0.1778 0.2794)
							(mid 0.249642 0.249642)
							(end 0.2794 0.1778)
						)
						(arc
							(start 0.2794 -0.1778)
							(mid 0.249642 -0.249642)
							(end 0.1778 -0.2794)
						)
					)
					(width 0)
					(fill yes)
				)
			)
		)
	)
	(footprint ""
		(layer "F.Cu")
		(at 472.313 -214.249)
		(property "Reference" "R375"
			(at 0 0 0)
			(layer "F.SilkS")
			(hide yes)
			(effects
				(font
					(size 1.27 1.27)
				)
			)
		)
		(property "Value" "130R3F-GP"
			(at -0.0254 -2.5146 0)
			(unlocked yes)
			(layer "F.Fab")
			(hide yes)
			(effects
				(font
					(size 1.016 1.016)
					(thickness 0.1524)
				)
			)
		)
		(property "Device Type" "R603H22"
			(at -0.0254 -4.0386 0)
			(unlocked yes)
			(layer "F.Fab")
			(hide yes)
			(effects
				(font
					(size 1.016 1.016)
					(thickness 0.1524)
				)
			)
		)
		(duplicate_pad_numbers_are_jumpers no)
		(fp_line
			(start -0.4826 0)
			(end -0.2032 0)
			(stroke
				(width 0.2032)
				(type default)
			)
			(layer "F.SilkS")
		)
		(fp_line
			(start 0.2032 0)
			(end 0.4826 0)
			(stroke
				(width 0.2032)
				(type default)
			)
			(layer "F.SilkS")
		)
		(fp_rect
			(start -0.5842 1.3335)
			(end 0.5842 -1.3335)
			(stroke
				(width 0)
				(type default)
			)
			(fill no)
			(layer "F.CrtYd")
		)
		(fp_rect
			(start -0.5842 1.3335)
			(end 0.5842 -1.3335)
			(stroke
				(width 0)
				(type default)
			)
			(fill no)
			(layer "F.Fab")
		)
		(pad "1" smd custom
			(at 0 -0.762)
			(size 0.2159 0.2159)
			(layers "F.Cu" "F.Mask" "F.Paste")
			(net "P5V_B_3")
			(options
				(clearance outline)
				(anchor circle)
			)
			(primitives
				(gr_poly
					(pts
						(arc
							(start -0.3302 -0.4318)
							(mid -0.402042 -0.402042)
							(end -0.4318 -0.3302)
						)
						(arc
							(start -0.4318 0.3302)
							(mid -0.402042 0.402042)
							(end -0.3302 0.4318)
						)
						(arc
							(start 0.3302 0.4318)
							(mid 0.402042 0.402042)
							(end 0.4318 0.3302)
						)
						(arc
							(start 0.4318 -0.3302)
							(mid 0.402042 -0.402042)
							(end 0.3302 -0.4318)
						)
					)
					(width 0)
					(fill yes)
				)
			)
		)
		(pad "2" smd custom
			(at 0 0.762)
			(size 0.2159 0.2159)
			(layers "F.Cu" "F.Mask" "F.Paste")
			(net "FLT_HDD11")
			(options
				(clearance outline)
				(anchor circle)
			)
			(primitives
				(gr_poly
					(pts
						(arc
							(start -0.3302 -0.4318)
							(mid -0.402042 -0.402042)
							(end -0.4318 -0.3302)
						)
						(arc
							(start -0.4318 0.3302)
							(mid -0.402042 0.402042)
							(end -0.3302 0.4318)
						)
						(arc
							(start 0.3302 0.4318)
							(mid 0.402042 0.402042)
							(end 0.4318 0.3302)
						)
						(arc
							(start 0.4318 -0.3302)
							(mid 0.402042 -0.402042)
							(end 0.3302 -0.4318)
						)
					)
					(width 0)
					(fill yes)
				)
			)
		)
	)
	(footprint ""
		(layer "F.Cu")
		(at 141.28115 -102.427786 -90)
		(property "Reference" "R389"
			(at 0 0 270)
			(layer "F.SilkS")
			(hide yes)
			(effects
				(font
					(size 1.27 1.27)
				)
			)
		)
		(property "Value" "4K7R2F-GP"
			(at 0.064008 -3.993896 270)
			(unlocked yes)
			(layer "F.Fab")
			(hide yes)
			(effects
				(font
					(size 1.016 1.016)
					(thickness 0.1524)
				)
			)
		)
		(property "Device Type" "R402H16"
			(at 0.064008 -5.517896 270)
			(unlocked yes)
			(layer "F.Fab")
			(hide yes)
			(effects
				(font
					(size 1.016 1.016)
					(thickness 0.1524)
				)
			)
		)
		(duplicate_pad_numbers_are_jumpers no)
		(fp_line
			(start -0.508 -0.9398)
			(end -0.508 0.9398)
			(stroke
				(width 0.1524)
				(type default)
			)
			(layer "F.SilkS")
		)
		(fp_line
			(start 0.508 -0.9398)
			(end -0.508 -0.9398)
			(stroke
				(width 0.1524)
				(type default)
			)
			(layer "F.SilkS")
		)
		(fp_rect
			(start -0.508 0.9398)
			(end 0.508 -0.9398)
			(stroke
				(width 0)
				(type default)
			)
			(fill no)
			(layer "F.CrtYd")
		)
		(fp_rect
			(start -0.508 0.9398)
			(end 0.508 -0.9398)
			(stroke
				(width 0)
				(type default)
			)
			(fill no)
			(layer "F.Fab")
		)
		(pad "1" smd custom
			(at 0 -0.4445 270)
			(size 0.1397 0.1397)
			(layers "F.Cu" "F.Mask" "F.Paste")
			(net "DRIVE_B_16_FLT_LED")
			(options
				(clearance outline)
				(anchor circle)
			)
			(primitives
				(gr_poly
					(pts
						(arc
							(start -0.1778 -0.2794)
							(mid -0.249642 -0.249642)
							(end -0.2794 -0.1778)
						)
						(arc
							(start -0.2794 0.1778)
							(mid -0.249642 0.249642)
							(end -0.1778 0.2794)
						)
						(arc
							(start 0.1778 0.2794)
							(mid 0.249642 0.249642)
							(end 0.2794 0.1778)
						)
						(arc
							(start 0.2794 -0.1778)
							(mid 0.249642 -0.249642)
							(end 0.1778 -0.2794)
						)
					)
					(width 0)
					(fill yes)
				)
			)
		)
		(pad "2" smd custom
			(at 0 0.4445 270)
			(size 0.1397 0.1397)
			(layers "F.Cu" "F.Mask" "F.Paste")
			(net "GND")
			(options
				(clearance outline)
				(anchor circle)
			)
			(primitives
				(gr_poly
					(pts
						(arc
							(start -0.1778 -0.2794)
							(mid -0.249642 -0.249642)
							(end -0.2794 -0.1778)
						)
						(arc
							(start -0.2794 0.1778)
							(mid -0.249642 0.249642)
							(end -0.1778 0.2794)
						)
						(arc
							(start 0.1778 0.2794)
							(mid 0.249642 0.249642)
							(end 0.2794 0.1778)
						)
						(arc
							(start 0.2794 -0.1778)
							(mid 0.249642 -0.249642)
							(end 0.1778 -0.2794)
						)
					)
					(width 0)
					(fill yes)
				)
			)
		)
	)
	(footprint ""
		(layer "F.Cu")
		(at 244.662452 -359.617772 180)
		(property "Reference" "R1050"
			(at 0 0 180)
			(layer "F.SilkS")
			(hide yes)
			(effects
				(font
					(size 1.27 1.27)
				)
			)
		)
		(property "Value" "3K92R2F-GP"
			(at 0.064008 -3.993896 180)
			(unlocked yes)
			(layer "F.Fab")
			(hide yes)
			(effects
				(font
					(size 1.016 1.016)
					(thickness 0.1524)
				)
			)
		)
		(property "Device Type" "R402H16"
			(at 0.064008 -5.517896 180)
			(unlocked yes)
			(layer "F.Fab")
			(hide yes)
			(effects
				(font
					(size 1.016 1.016)
					(thickness 0.1524)
				)
			)
		)
		(duplicate_pad_numbers_are_jumpers no)
		(fp_line
			(start 0.508 -0.9398)
			(end -0.508 -0.9398)
			(stroke
				(width 0.1524)
				(type default)
			)
			(layer "F.SilkS")
		)
		(fp_line
			(start -0.508 -0.9398)
			(end -0.508 0.9398)
			(stroke
				(width 0.1524)
				(type default)
			)
			(layer "F.SilkS")
		)
		(fp_rect
			(start -0.508 0.9398)
			(end 0.508 -0.9398)
			(stroke
				(width 0)
				(type default)
			)
			(fill no)
			(layer "F.CrtYd")
		)
		(fp_rect
			(start -0.508 0.9398)
			(end 0.508 -0.9398)
			(stroke
				(width 0)
				(type default)
			)
			(fill no)
			(layer "F.Fab")
		)
		(pad "1" smd custom
			(at 0 -0.4445 180)
			(size 0.1397 0.1397)
			(layers "F.Cu" "F.Mask" "F.Paste")
			(net "MB3_CM_OV_R")
			(options
				(clearance outline)
				(anchor circle)
			)
			(primitives
				(gr_poly
					(pts
						(arc
							(start -0.1778 -0.2794)
							(mid -0.249642 -0.249642)
							(end -0.2794 -0.1778)
						)
						(arc
							(start -0.2794 0.1778)
							(mid -0.249642 0.249642)
							(end -0.1778 0.2794)
						)
						(arc
							(start 0.1778 0.2794)
							(mid 0.249642 0.249642)
							(end 0.2794 0.1778)
						)
						(arc
							(start 0.2794 -0.1778)
							(mid 0.249642 -0.249642)
							(end 0.1778 -0.2794)
						)
					)
					(width 0)
					(fill yes)
				)
			)
		)
		(pad "2" smd custom
			(at 0 0.4445 180)
			(size 0.1397 0.1397)
			(layers "F.Cu" "F.Mask" "F.Paste")
			(net "AGND_CURRENT_DPB")
			(options
				(clearance outline)
				(anchor circle)
			)
			(primitives
				(gr_poly
					(pts
						(arc
							(start -0.1778 -0.2794)
							(mid -0.249642 -0.249642)
							(end -0.2794 -0.1778)
						)
						(arc
							(start -0.2794 0.1778)
							(mid -0.249642 0.249642)
							(end -0.1778 0.2794)
						)
						(arc
							(start 0.1778 0.2794)
							(mid 0.249642 0.249642)
							(end 0.2794 0.1778)
						)
						(arc
							(start 0.2794 -0.1778)
							(mid 0.249642 -0.249642)
							(end 0.1778 -0.2794)
						)
					)
					(width 0)
					(fill yes)
				)
			)
		)
	)
	(footprint ""
		(layer "F.Cu")
		(at 370.205 -143.891 90)
		(property "Reference" "C286"
			(at 0 0 90)
			(layer "F.SilkS")
			(hide yes)
			(effects
				(font
					(size 1.27 1.27)
				)
			)
		)
		(property "Value" "SCD033U25V2KX-GP"
			(at 1.1811 -2.7051 90)
			(unlocked yes)
			(layer "F.Fab")
			(hide yes)
			(effects
				(font
					(size 1.016 1.016)
					(thickness 0.1524)
				)
			)
		)
		(property "Device Type" "C402H22"
			(at 1.1811 -4.2291 90)
			(unlocked yes)
			(layer "F.Fab")
			(hide yes)
			(effects
				(font
					(size 1.016 1.016)
					(thickness 0.1524)
				)
			)
		)
		(duplicate_pad_numbers_are_jumpers no)
		(fp_rect
			(start -0.4318 0.9525)
			(end 0.4318 -0.9525)
			(stroke
				(width 0)
				(type default)
			)
			(fill no)
			(layer "F.CrtYd")
		)
		(fp_rect
			(start -0.4318 0.9525)
			(end 0.4318 -0.9525)
			(stroke
				(width 0)
				(type default)
			)
			(fill no)
			(layer "F.Fab")
		)
		(pad "1" smd custom
			(at 0 -0.4445 90)
			(size 0.1524 0.1524)
			(layers "F.Cu" "F.Mask" "F.Paste")
			(net "P12V_B")
			(options
				(clearance outline)
				(anchor circle)
			)
			(primitives
				(gr_poly
					(pts
						(arc
							(start 0.3048 -0.2032)
							(mid 0.275042 -0.275042)
							(end 0.2032 -0.3048)
						)
						(arc
							(start -0.2032 -0.3048)
							(mid -0.275042 -0.275042)
							(end -0.3048 -0.2032)
						)
						(arc
							(start -0.3048 0.2032)
							(mid -0.275042 0.275042)
							(end -0.2032 0.3048)
						)
						(arc
							(start 0.2032 0.3048)
							(mid 0.275042 0.275042)
							(end 0.3048 0.2032)
						)
					)
					(width 0)
					(fill yes)
				)
			)
		)
		(pad "2" smd custom
			(at 0 0.4445 90)
			(size 0.1524 0.1524)
			(layers "F.Cu" "F.Mask" "F.Paste")
			(net "SW_HDD_N19")
			(options
				(clearance outline)
				(anchor circle)
			)
			(primitives
				(gr_poly
					(pts
						(arc
							(start 0.3048 -0.2032)
							(mid 0.275042 -0.275042)
							(end 0.2032 -0.3048)
						)
						(arc
							(start -0.2032 -0.3048)
							(mid -0.275042 -0.275042)
							(end -0.3048 -0.2032)
						)
						(arc
							(start -0.3048 0.2032)
							(mid -0.275042 0.275042)
							(end -0.2032 0.3048)
						)
						(arc
							(start 0.2032 0.3048)
							(mid 0.275042 0.275042)
							(end 0.3048 0.2032)
						)
					)
					(width 0)
					(fill yes)
				)
			)
		)
	)
	(footprint ""
		(layer "F.Cu")
		(at 233.72318 -219.03436)
		(property "Reference" "R67"
			(at 0 0 0)
			(layer "F.SilkS")
			(hide yes)
			(effects
				(font
					(size 1.27 1.27)
				)
			)
		)
		(property "Value" "0R2J-2-GP"
			(at 0.064008 -3.993896 0)
			(unlocked yes)
			(layer "F.Fab")
			(hide yes)
			(effects
				(font
					(size 1.016 1.016)
					(thickness 0.1524)
				)
			)
		)
		(property "Device Type" "R402H16"
			(at 0.064008 -5.517896 0)
			(unlocked yes)
			(layer "F.Fab")
			(hide yes)
			(effects
				(font
					(size 1.016 1.016)
					(thickness 0.1524)
				)
			)
		)
		(duplicate_pad_numbers_are_jumpers no)
		(fp_line
			(start -0.508 -0.9398)
			(end -0.508 0.9398)
			(stroke
				(width 0.1524)
				(type default)
			)
			(layer "F.SilkS")
		)
		(fp_line
			(start 0.508 -0.9398)
			(end -0.508 -0.9398)
			(stroke
				(width 0.1524)
				(type default)
			)
			(layer "F.SilkS")
		)
		(fp_rect
			(start -0.508 0.9398)
			(end 0.508 -0.9398)
			(stroke
				(width 0)
				(type default)
			)
			(fill no)
			(layer "F.CrtYd")
		)
		(fp_rect
			(start -0.508 0.9398)
			(end 0.508 -0.9398)
			(stroke
				(width 0)
				(type default)
			)
			(fill no)
			(layer "F.Fab")
		)
		(pad "1" smd custom
			(at 0 -0.4445)
			(size 0.1397 0.1397)
			(layers "F.Cu" "F.Mask" "F.Paste")
			(net "IO_EXP1_SCL")
			(options
				(clearance outline)
				(anchor circle)
			)
			(primitives
				(gr_poly
					(pts
						(arc
							(start -0.1778 -0.2794)
							(mid -0.249642 -0.249642)
							(end -0.2794 -0.1778)
						)
						(arc
							(start -0.2794 0.1778)
							(mid -0.249642 0.249642)
							(end -0.1778 0.2794)
						)
						(arc
							(start 0.1778 0.2794)
							(mid 0.249642 0.249642)
							(end 0.2794 0.1778)
						)
						(arc
							(start 0.2794 -0.1778)
							(mid 0.249642 -0.249642)
							(end 0.1778 -0.2794)
						)
					)
					(width 0)
					(fill yes)
				)
			)
		)
		(pad "2" smd custom
			(at 0 0.4445)
			(size 0.1397 0.1397)
			(layers "F.Cu" "F.Mask" "F.Paste")
			(net "I2C_DRIVE_B_PWR_SCL")
			(options
				(clearance outline)
				(anchor circle)
			)
			(primitives
				(gr_poly
					(pts
						(arc
							(start -0.1778 -0.2794)
							(mid -0.249642 -0.249642)
							(end -0.2794 -0.1778)
						)
						(arc
							(start -0.2794 0.1778)
							(mid -0.249642 0.249642)
							(end -0.1778 0.2794)
						)
						(arc
							(start 0.1778 0.2794)
							(mid 0.249642 0.249642)
							(end 0.2794 0.1778)
						)
						(arc
							(start 0.2794 -0.1778)
							(mid 0.249642 -0.249642)
							(end 0.1778 -0.2794)
						)
					)
					(width 0)
					(fill yes)
				)
			)
		)
	)
	(footprint ""
		(layer "F.Cu")
		(at 444.506096 -111.434118 -90)
		(property "Reference" "C682"
			(at 0 0 270)
			(layer "F.SilkS")
			(hide yes)
			(effects
				(font
					(size 1.27 1.27)
				)
			)
		)
		(property "Value" "SC2200P50V2KX-2GP"
			(at 1.1811 -2.7051 270)
			(unlocked yes)
			(layer "F.Fab")
			(hide yes)
			(effects
				(font
					(size 1.016 1.016)
					(thickness 0.1524)
				)
			)
		)
		(property "Device Type" "C402H22"
			(at 1.1811 -4.2291 270)
			(unlocked yes)
			(layer "F.Fab")
			(hide yes)
			(effects
				(font
					(size 1.016 1.016)
					(thickness 0.1524)
				)
			)
		)
		(duplicate_pad_numbers_are_jumpers no)
		(fp_rect
			(start -0.4318 0.9525)
			(end 0.4318 -0.9525)
			(stroke
				(width 0)
				(type default)
			)
			(fill no)
			(layer "F.CrtYd")
		)
		(fp_rect
			(start -0.4318 0.9525)
			(end 0.4318 -0.9525)
			(stroke
				(width 0)
				(type default)
			)
			(fill no)
			(layer "F.Fab")
		)
		(pad "1" smd custom
			(at 0 -0.4445 270)
			(size 0.1524 0.1524)
			(layers "F.Cu" "F.Mask" "F.Paste")
			(net "P5V_B_4_LL")
			(options
				(clearance outline)
				(anchor circle)
			)
			(primitives
				(gr_poly
					(pts
						(arc
							(start 0.3048 -0.2032)
							(mid 0.275042 -0.275042)
							(end 0.2032 -0.3048)
						)
						(arc
							(start -0.2032 -0.3048)
							(mid -0.275042 -0.275042)
							(end -0.3048 -0.2032)
						)
						(arc
							(start -0.3048 0.2032)
							(mid -0.275042 0.275042)
							(end -0.2032 0.3048)
						)
						(arc
							(start 0.2032 0.3048)
							(mid 0.275042 0.275042)
							(end 0.3048 0.2032)
						)
					)
					(width 0)
					(fill yes)
				)
			)
		)
		(pad "2" smd custom
			(at 0 0.4445 270)
			(size 0.1524 0.1524)
			(layers "F.Cu" "F.Mask" "F.Paste")
			(net "P5V_B_4_SNB")
			(options
				(clearance outline)
				(anchor circle)
			)
			(primitives
				(gr_poly
					(pts
						(arc
							(start 0.3048 -0.2032)
							(mid 0.275042 -0.275042)
							(end 0.2032 -0.3048)
						)
						(arc
							(start -0.2032 -0.3048)
							(mid -0.275042 -0.275042)
							(end -0.3048 -0.2032)
						)
						(arc
							(start -0.3048 0.2032)
							(mid -0.275042 0.275042)
							(end -0.2032 0.3048)
						)
						(arc
							(start 0.2032 0.3048)
							(mid 0.275042 0.275042)
							(end 0.3048 0.2032)
						)
					)
					(width 0)
					(fill yes)
				)
			)
		)
	)
	(footprint ""
		(layer "F.Cu")
		(at 170.307 -214.7062 180)
		(property "Reference" "Q224"
			(at 0 0 180)
			(layer "F.SilkS")
			(hide yes)
			(effects
				(font
					(size 1.27 1.27)
				)
			)
		)
		(property "Value" "2N7002K-2-GP"
			(at 0.127 -8.9662 180)
			(unlocked yes)
			(layer "F.Fab")
			(hide yes)
			(effects
				(font
					(size 1.016 1.016)
					(thickness 0.1524)
				)
			)
		)
		(property "Device Type" "SOT23DGS2D4H44"
			(at 0.127 -10.4902 180)
			(unlocked yes)
			(layer "F.Fab")
			(hide yes)
			(effects
				(font
					(size 1.016 1.016)
					(thickness 0.1524)
				)
			)
		)
		(duplicate_pad_numbers_are_jumpers no)
		(fp_line
			(start 1.651 1.778)
			(end 1.651 -1.778)
			(stroke
				(width 0.1524)
				(type default)
			)
			(layer "F.SilkS")
		)
		(fp_line
			(start 1.651 -1.778)
			(end -1.651 -1.778)
			(stroke
				(width 0.1524)
				(type default)
			)
			(layer "F.SilkS")
		)
		(fp_line
			(start -1.651 1.778)
			(end 1.651 1.778)
			(stroke
				(width 0.1524)
				(type default)
			)
			(layer "F.SilkS")
		)
		(fp_line
			(start -1.651 -1.778)
			(end -1.651 1.778)
			(stroke
				(width 0.1524)
				(type default)
			)
			(layer "F.SilkS")
		)
		(fp_poly
			(pts
				(xy -1.778 1.8796) (xy -1.778 -1.8796) (xy 1.778 -1.8796) (xy 1.778 1.8796)
			)
			(stroke
				(width 0)
				(type default)
			)
			(fill no)
			(layer "F.CrtYd")
		)
		(fp_poly
			(pts
				(xy -1.778 1.8796) (xy -1.778 -1.8796) (xy 1.778 -1.8796) (xy 1.778 1.8796)
			)
			(stroke
				(width 0)
				(type default)
			)
			(fill no)
			(layer "F.Fab")
		)
		(pad "D" smd custom
			(at 0 -0.9525 180)
			(size 0.1905 0.1905)
			(layers "F.Cu" "F.Mask" "F.Paste")
			(net "FLT_HDD5_N")
			(options
				(clearance outline)
				(anchor circle)
			)
			(primitives
				(gr_poly
					(pts
						(arc
							(start -0.1778 0.5715)
							(mid -0.321484 0.511984)
							(end -0.381 0.3683)
						)
						(arc
							(start -0.381 -0.3683)
							(mid -0.321484 -0.511984)
							(end -0.1778 -0.5715)
						)
						(arc
							(start 0.1778 -0.5715)
							(mid 0.321484 -0.511984)
							(end 0.381 -0.3683)
						)
						(arc
							(start 0.381 0.3683)
							(mid 0.321484 0.511984)
							(end 0.1778 0.5715)
						)
					)
					(width 0)
					(fill yes)
				)
			)
		)
		(pad "G" smd custom
			(at -0.98425 0.9525 180)
			(size 0.1905 0.1905)
			(layers "F.Cu" "F.Mask" "F.Paste")
			(net "DRIVE_B_5_FLT_LED")
			(options
				(clearance outline)
				(anchor circle)
			)
			(primitives
				(gr_poly
					(pts
						(arc
							(start -0.1778 0.5715)
							(mid -0.321484 0.511984)
							(end -0.381 0.3683)
						)
						(arc
							(start -0.381 -0.3683)
							(mid -0.321484 -0.511984)
							(end -0.1778 -0.5715)
						)
						(arc
							(start 0.1778 -0.5715)
							(mid 0.321484 -0.511984)
							(end 0.381 -0.3683)
						)
						(arc
							(start 0.381 0.3683)
							(mid 0.321484 0.511984)
							(end 0.1778 0.5715)
						)
					)
					(width 0)
					(fill yes)
				)
			)
		)
		(pad "S" smd custom
			(at 0.98425 0.9525 180)
			(size 0.1905 0.1905)
			(layers "F.Cu" "F.Mask" "F.Paste")
			(net "GND")
			(options
				(clearance outline)
				(anchor circle)
			)
			(primitives
				(gr_poly
					(pts
						(arc
							(start -0.1778 0.5715)
							(mid -0.321484 0.511984)
							(end -0.381 0.3683)
						)
						(arc
							(start -0.381 -0.3683)
							(mid -0.321484 -0.511984)
							(end -0.1778 -0.5715)
						)
						(arc
							(start 0.1778 -0.5715)
							(mid 0.321484 -0.511984)
							(end 0.381 -0.3683)
						)
						(arc
							(start 0.381 0.3683)
							(mid 0.321484 0.511984)
							(end 0.1778 0.5715)
						)
					)
					(width 0)
					(fill yes)
				)
			)
		)
	)
	(footprint ""
		(layer "F.Cu")
		(at 109.474 -246.634 90)
		(property "Reference" "R216"
			(at 0 0 90)
			(layer "F.SilkS")
			(hide yes)
			(effects
				(font
					(size 1.27 1.27)
				)
			)
		)
		(property "Value" "4K7R2J-2-GP"
			(at 0.064008 -3.993896 90)
			(unlocked yes)
			(layer "F.Fab")
			(hide yes)
			(effects
				(font
					(size 1.016 1.016)
					(thickness 0.1524)
				)
			)
		)
		(property "Device Type" "R402H16"
			(at 0.064008 -5.517896 90)
			(unlocked yes)
			(layer "F.Fab")
			(hide yes)
			(effects
				(font
					(size 1.016 1.016)
					(thickness 0.1524)
				)
			)
		)
		(duplicate_pad_numbers_are_jumpers no)
		(fp_line
			(start 0.508 -0.9398)
			(end -0.508 -0.9398)
			(stroke
				(width 0.1524)
				(type default)
			)
			(layer "F.SilkS")
		)
		(fp_line
			(start -0.508 -0.9398)
			(end -0.508 0.9398)
			(stroke
				(width 0.1524)
				(type default)
			)
			(layer "F.SilkS")
		)
		(fp_rect
			(start -0.508 0.9398)
			(end 0.508 -0.9398)
			(stroke
				(width 0)
				(type default)
			)
			(fill no)
			(layer "F.CrtYd")
		)
		(fp_rect
			(start -0.508 0.9398)
			(end 0.508 -0.9398)
			(stroke
				(width 0)
				(type default)
			)
			(fill no)
			(layer "F.Fab")
		)
		(pad "1" smd custom
			(at 0 -0.4445 90)
			(size 0.1397 0.1397)
			(layers "F.Cu" "F.Mask" "F.Paste")
			(net "P12V_B")
			(options
				(clearance outline)
				(anchor circle)
			)
			(primitives
				(gr_poly
					(pts
						(arc
							(start -0.1778 -0.2794)
							(mid -0.249642 -0.249642)
							(end -0.2794 -0.1778)
						)
						(arc
							(start -0.2794 0.1778)
							(mid -0.249642 0.249642)
							(end -0.1778 0.2794)
						)
						(arc
							(start 0.1778 0.2794)
							(mid 0.249642 0.249642)
							(end 0.2794 0.1778)
						)
						(arc
							(start 0.2794 -0.1778)
							(mid 0.249642 -0.249642)
							(end 0.1778 -0.2794)
						)
					)
					(width 0)
					(fill yes)
				)
			)
		)
		(pad "2" smd custom
			(at 0 0.4445 90)
			(size 0.1397 0.1397)
			(layers "F.Cu" "F.Mask" "F.Paste")
			(net "SW_HDD_R3")
			(options
				(clearance outline)
				(anchor circle)
			)
			(primitives
				(gr_poly
					(pts
						(arc
							(start -0.1778 -0.2794)
							(mid -0.249642 -0.249642)
							(end -0.2794 -0.1778)
						)
						(arc
							(start -0.2794 0.1778)
							(mid -0.249642 0.249642)
							(end -0.1778 0.2794)
						)
						(arc
							(start 0.1778 0.2794)
							(mid 0.249642 0.249642)
							(end 0.2794 0.1778)
						)
						(arc
							(start 0.2794 -0.1778)
							(mid 0.249642 -0.249642)
							(end 0.1778 -0.2794)
						)
					)
					(width 0)
					(fill yes)
				)
			)
		)
	)
	(footprint ""
		(layer "F.Cu")
		(at 77.978 -145.796)
		(property "Reference" "Q60"
			(at 0 0 0)
			(layer "F.SilkS")
			(hide yes)
			(effects
				(font
					(size 1.27 1.27)
				)
			)
		)
		(property "Value" "AO4407AL-GP"
			(at -3.707384 -1.5367 0)
			(unlocked yes)
			(layer "F.Fab")
			(hide yes)
			(effects
				(font
					(size 1.016 1.016)
					(thickness 0.1524)
				)
			)
		)
		(property "Device Type" "SOIC8H69"
			(at -3.707384 -3.0607 0)
			(unlocked yes)
			(layer "F.Fab")
			(hide yes)
			(effects
				(font
					(size 1.016 1.016)
					(thickness 0.1524)
				)
			)
		)
		(duplicate_pad_numbers_are_jumpers no)
		(fp_line
			(start -2.7432 -1.4224)
			(end -2.7432 1.4224)
			(stroke
				(width 0.1524)
				(type default)
			)
			(layer "F.SilkS")
		)
		(fp_line
			(start -2.7432 1.4224)
			(end -2.6416 1.4224)
			(stroke
				(width 0.1524)
				(type default)
			)
			(layer "F.SilkS")
		)
		(fp_line
			(start -2.7432 1.4224)
			(end 2.1336 1.4224)
			(stroke
				(width 0.1524)
				(type default)
			)
			(layer "F.SilkS")
		)
		(fp_line
			(start -2.7178 -0.508)
			(end -2.1844 -0.0508)
			(stroke
				(width 0.1524)
				(type default)
			)
			(layer "F.SilkS")
		)
		(fp_line
			(start -2.6289 3.4417)
			(end -2.6289 1.4732)
			(stroke
				(width 0.381)
				(type default)
			)
			(layer "F.SilkS")
		)
		(fp_line
			(start -2.1844 -0.0508)
			(end -2.7178 0.508)
			(stroke
				(width 0.1524)
				(type default)
			)
			(layer "F.SilkS")
		)
		(fp_line
			(start 2.1336 -1.4224)
			(end -2.7432 -1.4224)
			(stroke
				(width 0.1524)
				(type default)
			)
			(layer "F.SilkS")
		)
		(fp_line
			(start 2.1336 1.4224)
			(end 2.1336 -1.4224)
			(stroke
				(width 0.1524)
				(type default)
			)
			(layer "F.SilkS")
		)
		(fp_poly
			(pts
				(xy -2.2098 -1.4224) (xy -2.2098 1.4224) (xy 2.2098 1.4224) (xy 2.2098 -1.4224)
			)
			(stroke
				(width 0)
				(type default)
			)
			(fill yes)
			(layer "F.SilkS")
		)
		(fp_rect
			(start -2.450084 2.999994)
			(end 2.450084 -2.999994)
			(stroke
				(width 0)
				(type default)
			)
			(fill no)
			(layer "F.CrtYd")
		)
		(fp_poly
			(pts
				(xy -2.8194 3.6322) (xy -2.8194 -3.6322) (xy 2.8194 -3.6322) (xy 2.8194 1.18364) (xy 2.450084 1.18364)
				(xy 2.450084 -2.999994) (xy -2.450084 -2.999994) (xy -2.450084 2.999994) (xy 2.450084 2.999994)
				(xy 2.450084 1.18618) (xy 2.8194 1.18618) (xy 2.8194 3.6322)
			)
			(stroke
				(width 0)
				(type default)
			)
			(fill no)
			(layer "F.CrtYd")
		)
		(fp_rect
			(start -2.8194 3.6322)
			(end 2.8194 -3.6322)
			(stroke
				(width 0)
				(type default)
			)
			(fill no)
			(layer "F.Fab")
		)
		(pad "1" smd rect
			(at -1.905 2.54)
			(size 0.635 1.651)
			(layers "F.Cu" "F.Mask" "F.Paste")
			(net "P12V_B")
		)
		(pad "2" smd rect
			(at -0.635 2.54)
			(size 0.635 1.651)
			(layers "F.Cu" "F.Mask" "F.Paste")
			(net "P12V_B")
		)
		(pad "3" smd rect
			(at 0.635 2.54)
			(size 0.635 1.651)
			(layers "F.Cu" "F.Mask" "F.Paste")
			(net "P12V_B")
		)
		(pad "4" smd rect
			(at 1.905 2.54)
			(size 0.635 1.651)
			(layers "F.Cu" "F.Mask" "F.Paste")
			(net "SW_HDD_N14")
		)
		(pad "5" smd rect
			(at 1.905 -2.54)
			(size 0.635 1.651)
			(layers "F.Cu" "F.Mask" "F.Paste")
			(net "P12V_HDD14")
		)
		(pad "6" smd rect
			(at 0.635 -2.54)
			(size 0.635 1.651)
			(layers "F.Cu" "F.Mask" "F.Paste")
			(net "P12V_HDD14")
		)
		(pad "7" smd rect
			(at -0.635 -2.54)
			(size 0.635 1.651)
			(layers "F.Cu" "F.Mask" "F.Paste")
			(net "P12V_HDD14")
		)
		(pad "8" smd rect
			(at -1.905 -2.54)
			(size 0.635 1.651)
			(layers "F.Cu" "F.Mask" "F.Paste")
			(net "P12V_HDD14")
		)
	)
	(footprint ""
		(layer "F.Cu")
		(at 232.55732 -219.04198)
		(property "Reference" "R63"
			(at 0 0 0)
			(layer "F.SilkS")
			(hide yes)
			(effects
				(font
					(size 1.27 1.27)
				)
			)
		)
		(property "Value" "4K7R2F-GP"
			(at 0.064008 -3.993896 0)
			(unlocked yes)
			(layer "F.Fab")
			(hide yes)
			(effects
				(font
					(size 1.016 1.016)
					(thickness 0.1524)
				)
			)
		)
		(property "Device Type" "R402H16"
			(at 0.064008 -5.517896 0)
			(unlocked yes)
			(layer "F.Fab")
			(hide yes)
			(effects
				(font
					(size 1.016 1.016)
					(thickness 0.1524)
				)
			)
		)
		(duplicate_pad_numbers_are_jumpers no)
		(fp_line
			(start -0.508 -0.9398)
			(end -0.508 0.9398)
			(stroke
				(width 0.1524)
				(type default)
			)
			(layer "F.SilkS")
		)
		(fp_line
			(start 0.508 -0.9398)
			(end -0.508 -0.9398)
			(stroke
				(width 0.1524)
				(type default)
			)
			(layer "F.SilkS")
		)
		(fp_rect
			(start -0.508 0.9398)
			(end 0.508 -0.9398)
			(stroke
				(width 0)
				(type default)
			)
			(fill no)
			(layer "F.CrtYd")
		)
		(fp_rect
			(start -0.508 0.9398)
			(end 0.508 -0.9398)
			(stroke
				(width 0)
				(type default)
			)
			(fill no)
			(layer "F.Fab")
		)
		(pad "1" smd custom
			(at 0 -0.4445)
			(size 0.1397 0.1397)
			(layers "F.Cu" "F.Mask" "F.Paste")
			(net "IO_EXP1_A0")
			(options
				(clearance outline)
				(anchor circle)
			)
			(primitives
				(gr_poly
					(pts
						(arc
							(start -0.1778 -0.2794)
							(mid -0.249642 -0.249642)
							(end -0.2794 -0.1778)
						)
						(arc
							(start -0.2794 0.1778)
							(mid -0.249642 0.249642)
							(end -0.1778 0.2794)
						)
						(arc
							(start 0.1778 0.2794)
							(mid 0.249642 0.249642)
							(end 0.2794 0.1778)
						)
						(arc
							(start 0.2794 -0.1778)
							(mid 0.249642 -0.249642)
							(end 0.1778 -0.2794)
						)
					)
					(width 0)
					(fill yes)
				)
			)
		)
		(pad "2" smd custom
			(at 0 0.4445)
			(size 0.1397 0.1397)
			(layers "F.Cu" "F.Mask" "F.Paste")
			(net "GND")
			(options
				(clearance outline)
				(anchor circle)
			)
			(primitives
				(gr_poly
					(pts
						(arc
							(start -0.1778 -0.2794)
							(mid -0.249642 -0.249642)
							(end -0.2794 -0.1778)
						)
						(arc
							(start -0.2794 0.1778)
							(mid -0.249642 0.249642)
							(end -0.1778 0.2794)
						)
						(arc
							(start 0.1778 0.2794)
							(mid 0.249642 0.249642)
							(end 0.2794 0.1778)
						)
						(arc
							(start 0.2794 -0.1778)
							(mid 0.249642 -0.249642)
							(end 0.1778 -0.2794)
						)
					)
					(width 0)
					(fill yes)
				)
			)
		)
	)
	(footprint ""
		(layer "F.Cu")
		(at 384.734562 -14.660626 -90)
		(property "Reference" "C445"
			(at 0 0 270)
			(layer "F.SilkS")
			(hide yes)
			(effects
				(font
					(size 1.27 1.27)
				)
			)
		)
		(property "Value" "SCD01U16V1KX-GP"
			(at -2.8321 -1.7399 270)
			(unlocked yes)
			(layer "F.Fab")
			(hide yes)
			(effects
				(font
					(size 1.016 1.016)
					(thickness 0.1524)
				)
			)
		)
		(property "Device Type" "C0201H13"
			(at -2.8321 -3.2639 270)
			(unlocked yes)
			(layer "F.Fab")
			(hide yes)
			(effects
				(font
					(size 1.016 1.016)
					(thickness 0.1524)
				)
			)
		)
		(duplicate_pad_numbers_are_jumpers no)
		(fp_rect
			(start -0.2794 0.6477)
			(end 0.2794 -0.6477)
			(stroke
				(width 0)
				(type default)
			)
			(fill no)
			(layer "F.CrtYd")
		)
		(fp_rect
			(start -0.2794 0.6477)
			(end 0.2794 -0.6477)
			(stroke
				(width 0)
				(type default)
			)
			(fill no)
			(layer "F.Fab")
		)
		(pad "1" smd custom
			(at 0 -0.2794 270)
			(size 0.0762 0.0762)
			(layers "F.Cu" "F.Mask" "F.Paste")
			(net "SAS_HDD_RX_P32")
			(options
				(clearance outline)
				(anchor circle)
			)
			(primitives
				(gr_poly
					(pts
						(arc
							(start 0.1524 -0.127)
							(mid 0.137521 -0.162921)
							(end 0.1016 -0.1778)
						)
						(arc
							(start -0.1016 -0.1778)
							(mid -0.137521 -0.162921)
							(end -0.1524 -0.127)
						)
						(arc
							(start -0.1524 0.127)
							(mid -0.137521 0.162921)
							(end -0.1016 0.1778)
						)
						(arc
							(start 0.1016 0.1778)
							(mid 0.137521 0.162921)
							(end 0.1524 0.127)
						)
					)
					(width 0)
					(fill yes)
				)
			)
		)
		(pad "2" smd custom
			(at 0 0.2794 270)
			(size 0.0762 0.0762)
			(layers "F.Cu" "F.Mask" "F.Paste")
			(net "PHY_SCC_B_TO_DRV_B_32_DP")
			(options
				(clearance outline)
				(anchor circle)
			)
			(primitives
				(gr_poly
					(pts
						(arc
							(start 0.1524 -0.127)
							(mid 0.137521 -0.162921)
							(end 0.1016 -0.1778)
						)
						(arc
							(start -0.1016 -0.1778)
							(mid -0.137521 -0.162921)
							(end -0.1524 -0.127)
						)
						(arc
							(start -0.1524 0.127)
							(mid -0.137521 0.162921)
							(end -0.1016 0.1778)
						)
						(arc
							(start 0.1016 0.1778)
							(mid 0.137521 0.162921)
							(end 0.1524 0.127)
						)
					)
					(width 0)
					(fill yes)
				)
			)
		)
	)
	(footprint ""
		(layer "F.Cu")
		(at 333.502 -44.958 180)
		(property "Reference" "C425"
			(at 0 0 180)
			(layer "F.SilkS")
			(hide yes)
			(effects
				(font
					(size 1.27 1.27)
				)
			)
		)
		(property "Value" "SC4D7U25V5KX-1-GP"
			(at -0.0762 -6.1214 180)
			(unlocked yes)
			(layer "F.Fab")
			(hide yes)
			(effects
				(font
					(size 1.016 1.016)
					(thickness 0.1524)
				)
			)
		)
		(property "Device Type" "C805H58"
			(at -0.0762 -8.1534 180)
			(unlocked yes)
			(layer "F.Fab")
			(hide yes)
			(effects
				(font
					(size 1.016 1.016)
					(thickness 0.1524)
				)
			)
		)
		(duplicate_pad_numbers_are_jumpers no)
		(fp_line
			(start 0.635 0)
			(end -0.635 0)
			(stroke
				(width 0.508)
				(type default)
			)
			(layer "F.SilkS")
		)
		(fp_rect
			(start -0.9652 1.778)
			(end 0.9652 -1.778)
			(stroke
				(width 0)
				(type default)
			)
			(fill no)
			(layer "F.CrtYd")
		)
		(fp_poly
			(pts
				(xy -0.9652 -1.778) (xy 0.9652 -1.778) (xy 0.9652 1.778) (xy -0.9652 1.778)
			)
			(stroke
				(width 0)
				(type default)
			)
			(fill no)
			(layer "F.Fab")
		)
		(pad "1" smd rect
			(at 0 -0.9652 180)
			(size 1.397 1.143)
			(layers "F.Cu" "F.Mask" "F.Paste")
			(net "P12V_HDD30")
		)
		(pad "2" smd rect
			(at 0 0.9652 180)
			(size 1.397 1.143)
			(layers "F.Cu" "F.Mask" "F.Paste")
			(net "GND")
		)
	)
	(footprint ""
		(layer "F.Cu")
		(at 475.2848 -263.779 -90)
		(property "Reference" "C173"
			(at 0 0 270)
			(layer "F.SilkS")
			(hide yes)
			(effects
				(font
					(size 1.27 1.27)
				)
			)
		)
		(property "Value" "SC1U16V3KX-5GP"
			(at 0 -2.8194 270)
			(unlocked yes)
			(layer "F.Fab")
			(hide yes)
			(effects
				(font
					(size 1.016 1.016)
					(thickness 0.1524)
				)
			)
		)
		(property "Device Type" "C603H36"
			(at 0 -4.3434 270)
			(unlocked yes)
			(layer "F.Fab")
			(hide yes)
			(effects
				(font
					(size 1.016 1.016)
					(thickness 0.1524)
				)
			)
		)
		(duplicate_pad_numbers_are_jumpers no)
		(fp_line
			(start 0.508 0)
			(end -0.508 0)
			(stroke
				(width 0.2032)
				(type default)
			)
			(layer "F.SilkS")
		)
		(fp_rect
			(start -0.5842 1.3335)
			(end 0.5842 -1.3335)
			(stroke
				(width 0)
				(type default)
			)
			(fill no)
			(layer "F.CrtYd")
		)
		(fp_rect
			(start -0.5842 1.3335)
			(end 0.5842 -1.3335)
			(stroke
				(width 0)
				(type default)
			)
			(fill no)
			(layer "F.Fab")
		)
		(pad "1" smd custom
			(at 0 -0.762 270)
			(size 0.2159 0.2159)
			(layers "F.Cu" "F.Mask" "F.Paste")
			(net "P5V_HDD11")
			(options
				(clearance outline)
				(anchor circle)
			)
			(primitives
				(gr_poly
					(pts
						(arc
							(start -0.3302 -0.4318)
							(mid -0.402042 -0.402042)
							(end -0.4318 -0.3302)
						)
						(arc
							(start -0.4318 0.3302)
							(mid -0.402042 0.402042)
							(end -0.3302 0.4318)
						)
						(arc
							(start 0.3302 0.4318)
							(mid 0.402042 0.402042)
							(end 0.4318 0.3302)
						)
						(arc
							(start 0.4318 -0.3302)
							(mid 0.402042 -0.402042)
							(end 0.3302 -0.4318)
						)
					)
					(width 0)
					(fill yes)
				)
			)
		)
		(pad "2" smd custom
			(at 0 0.762 270)
			(size 0.2159 0.2159)
			(layers "F.Cu" "F.Mask" "F.Paste")
			(net "GND")
			(options
				(clearance outline)
				(anchor circle)
			)
			(primitives
				(gr_poly
					(pts
						(arc
							(start -0.3302 -0.4318)
							(mid -0.402042 -0.402042)
							(end -0.4318 -0.3302)
						)
						(arc
							(start -0.4318 0.3302)
							(mid -0.402042 0.402042)
							(end -0.3302 0.4318)
						)
						(arc
							(start 0.3302 0.4318)
							(mid 0.402042 0.402042)
							(end 0.4318 0.3302)
						)
						(arc
							(start 0.4318 -0.3302)
							(mid 0.402042 -0.402042)
							(end 0.3302 -0.4318)
						)
					)
					(width 0)
					(fill yes)
				)
			)
		)
	)
	(footprint ""
		(layer "F.Cu")
		(at 250.4948 -138.684 180)
		(property "Reference" "R602"
			(at 0 0 180)
			(layer "F.SilkS")
			(hide yes)
			(effects
				(font
					(size 1.27 1.27)
				)
			)
		)
		(property "Value" "2K2R2F-GP"
			(at 0.064008 -3.993896 180)
			(unlocked yes)
			(layer "F.Fab")
			(hide yes)
			(effects
				(font
					(size 1.016 1.016)
					(thickness 0.1524)
				)
			)
		)
		(property "Device Type" "R402H16"
			(at 0.064008 -5.517896 180)
			(unlocked yes)
			(layer "F.Fab")
			(hide yes)
			(effects
				(font
					(size 1.016 1.016)
					(thickness 0.1524)
				)
			)
		)
		(duplicate_pad_numbers_are_jumpers no)
		(fp_line
			(start 0.508 -0.9398)
			(end -0.508 -0.9398)
			(stroke
				(width 0.1524)
				(type default)
			)
			(layer "F.SilkS")
		)
		(fp_line
			(start -0.508 -0.9398)
			(end -0.508 0.9398)
			(stroke
				(width 0.1524)
				(type default)
			)
			(layer "F.SilkS")
		)
		(fp_rect
			(start -0.508 0.9398)
			(end 0.508 -0.9398)
			(stroke
				(width 0)
				(type default)
			)
			(fill no)
			(layer "F.CrtYd")
		)
		(fp_rect
			(start -0.508 0.9398)
			(end 0.508 -0.9398)
			(stroke
				(width 0)
				(type default)
			)
			(fill no)
			(layer "F.Fab")
		)
		(pad "1" smd custom
			(at 0 -0.4445 180)
			(size 0.1397 0.1397)
			(layers "F.Cu" "F.Mask" "F.Paste")
			(net "P3V3_STBY_B")
			(options
				(clearance outline)
				(anchor circle)
			)
			(primitives
				(gr_poly
					(pts
						(arc
							(start -0.1778 -0.2794)
							(mid -0.249642 -0.249642)
							(end -0.2794 -0.1778)
						)
						(arc
							(start -0.2794 0.1778)
							(mid -0.249642 0.249642)
							(end -0.1778 0.2794)
						)
						(arc
							(start 0.1778 0.2794)
							(mid 0.249642 0.249642)
							(end 0.2794 0.1778)
						)
						(arc
							(start 0.2794 -0.1778)
							(mid 0.249642 -0.249642)
							(end 0.1778 -0.2794)
						)
					)
					(width 0)
					(fill yes)
				)
			)
		)
		(pad "2" smd custom
			(at 0 0.4445 180)
			(size 0.1397 0.1397)
			(layers "F.Cu" "F.Mask" "F.Paste")
			(net "I2C_SCC_B_SDA")
			(options
				(clearance outline)
				(anchor circle)
			)
			(primitives
				(gr_poly
					(pts
						(arc
							(start -0.1778 -0.2794)
							(mid -0.249642 -0.249642)
							(end -0.2794 -0.1778)
						)
						(arc
							(start -0.2794 0.1778)
							(mid -0.249642 0.249642)
							(end -0.1778 0.2794)
						)
						(arc
							(start 0.1778 0.2794)
							(mid 0.249642 0.249642)
							(end 0.2794 0.1778)
						)
						(arc
							(start 0.2794 -0.1778)
							(mid 0.249642 -0.249642)
							(end 0.1778 -0.2794)
						)
					)
					(width 0)
					(fill yes)
				)
			)
		)
	)
	(footprint ""
		(layer "F.Cu")
		(at 128.905 -372.237 90)
		(property "Reference" "R936"
			(at 0 0 90)
			(layer "F.SilkS")
			(hide yes)
			(effects
				(font
					(size 1.27 1.27)
				)
			)
		)
		(property "Value" "27KR3F-GP"
			(at -0.0254 -2.5146 90)
			(unlocked yes)
			(layer "F.Fab")
			(hide yes)
			(effects
				(font
					(size 1.016 1.016)
					(thickness 0.1524)
				)
			)
		)
		(property "Device Type" "R603H22"
			(at -0.0254 -4.0386 90)
			(unlocked yes)
			(layer "F.Fab")
			(hide yes)
			(effects
				(font
					(size 1.016 1.016)
					(thickness 0.1524)
				)
			)
		)
		(duplicate_pad_numbers_are_jumpers no)
		(fp_line
			(start 0.2032 0)
			(end 0.4826 0)
			(stroke
				(width 0.2032)
				(type default)
			)
			(layer "F.SilkS")
		)
		(fp_line
			(start -0.4826 0)
			(end -0.2032 0)
			(stroke
				(width 0.2032)
				(type default)
			)
			(layer "F.SilkS")
		)
		(fp_rect
			(start -0.5842 1.3335)
			(end 0.5842 -1.3335)
			(stroke
				(width 0)
				(type default)
			)
			(fill no)
			(layer "F.CrtYd")
		)
		(fp_rect
			(start -0.5842 1.3335)
			(end 0.5842 -1.3335)
			(stroke
				(width 0)
				(type default)
			)
			(fill no)
			(layer "F.Fab")
		)
		(pad "1" smd custom
			(at 0 -0.762 90)
			(size 0.2159 0.2159)
			(layers "F.Cu" "F.Mask" "F.Paste")
			(net "FANTACH_R1")
			(options
				(clearance outline)
				(anchor circle)
			)
			(primitives
				(gr_poly
					(pts
						(arc
							(start -0.3302 -0.4318)
							(mid -0.402042 -0.402042)
							(end -0.4318 -0.3302)
						)
						(arc
							(start -0.4318 0.3302)
							(mid -0.402042 0.402042)
							(end -0.3302 0.4318)
						)
						(arc
							(start 0.3302 0.4318)
							(mid 0.402042 0.402042)
							(end 0.4318 0.3302)
						)
						(arc
							(start 0.4318 -0.3302)
							(mid 0.402042 -0.402042)
							(end 0.3302 -0.4318)
						)
					)
					(width 0)
					(fill yes)
				)
			)
		)
		(pad "2" smd custom
			(at 0 0.762 90)
			(size 0.2159 0.2159)
			(layers "F.Cu" "F.Mask" "F.Paste")
			(net "FAN_1_TACH0")
			(options
				(clearance outline)
				(anchor circle)
			)
			(primitives
				(gr_poly
					(pts
						(arc
							(start -0.3302 -0.4318)
							(mid -0.402042 -0.402042)
							(end -0.4318 -0.3302)
						)
						(arc
							(start -0.4318 0.3302)
							(mid -0.402042 0.402042)
							(end -0.3302 0.4318)
						)
						(arc
							(start 0.3302 0.4318)
							(mid 0.402042 0.402042)
							(end 0.4318 0.3302)
						)
						(arc
							(start 0.4318 -0.3302)
							(mid 0.402042 -0.402042)
							(end 0.3302 -0.4318)
						)
					)
					(width 0)
					(fill yes)
				)
			)
		)
	)
	(footprint ""
		(layer "F.Cu")
		(at 176.657 -265.684 90)
		(property "Reference" "R240"
			(at 0 0 90)
			(layer "F.SilkS")
			(hide yes)
			(effects
				(font
					(size 1.27 1.27)
				)
			)
		)
		(property "Value" "2R6F-GP"
			(at -0.0508 -4.8514 90)
			(unlocked yes)
			(layer "F.Fab")
			(hide yes)
			(effects
				(font
					(size 1.016 1.016)
					(thickness 0.1524)
				)
			)
		)
		(property "Device Type" "R1206H26"
			(at 0 -6.3754 90)
			(unlocked yes)
			(layer "F.Fab")
			(hide yes)
			(effects
				(font
					(size 1.016 1.016)
					(thickness 0.1524)
				)
			)
		)
		(duplicate_pad_numbers_are_jumpers no)
		(fp_line
			(start 1.016 -2.2352)
			(end 1.016 2.2352)
			(stroke
				(width 0.1524)
				(type default)
			)
			(layer "F.SilkS")
		)
		(fp_line
			(start -1.016 -2.2352)
			(end 1.016 -2.2352)
			(stroke
				(width 0.1524)
				(type default)
			)
			(layer "F.SilkS")
		)
		(fp_line
			(start 1.016 2.2352)
			(end -1.016 2.2352)
			(stroke
				(width 0.1524)
				(type default)
			)
			(layer "F.SilkS")
		)
		(fp_line
			(start -1.016 2.2352)
			(end -1.016 -2.2352)
			(stroke
				(width 0.1524)
				(type default)
			)
			(layer "F.SilkS")
		)
		(fp_rect
			(start -1.0922 2.3114)
			(end 1.0922 -2.3114)
			(stroke
				(width 0)
				(type default)
			)
			(fill no)
			(layer "F.CrtYd")
		)
		(fp_poly
			(pts
				(xy -1.0922 -2.3114) (xy 1.0922 -2.3114) (xy 1.0922 2.3114) (xy -1.0922 2.3114)
			)
			(stroke
				(width 0)
				(type default)
			)
			(fill no)
			(layer "F.Fab")
		)
		(pad "1" smd rect
			(at 0 -1.397 90)
			(size 1.651 1.27)
			(layers "F.Cu" "F.Mask" "F.Paste")
			(net "P12V_HDD5")
		)
		(pad "2" smd rect
			(at 0 1.397 90)
			(size 1.651 1.27)
			(layers "F.Cu" "F.Mask" "F.Paste")
			(net "12V_PRE_5")
		)
	)
	(footprint ""
		(layer "F.Cu")
		(at 34.763964 -39.705026)
		(property "Reference" "TP141"
			(at 0 0 0)
			(layer "F.SilkS")
			(hide yes)
			(effects
				(font
					(size 1.27 1.27)
				)
			)
		)
		(property "Value" "*"
			(at -0.0508 -1.6764 0)
			(unlocked yes)
			(layer "F.Fab")
			(hide yes)
			(effects
				(font
					(size 1.016 1.016)
					(thickness 0.1524)
				)
			)
		)
		(property "Device Type" "TPAD32"
			(at -0.0508 -3.2004 0)
			(unlocked yes)
			(layer "F.Fab")
			(hide yes)
			(effects
				(font
					(size 1.016 1.016)
					(thickness 0.1524)
				)
			)
		)
		(duplicate_pad_numbers_are_jumpers no)
		(fp_poly
			(pts
				(arc
					(start 0.4064 0)
					(mid -0.4064 0)
					(end 0.4064 0)
				)
			)
			(stroke
				(width 0)
				(type default)
			)
			(fill no)
			(layer "F.CrtYd")
		)
		(fp_poly
			(pts
				(arc
					(start 0.7112 0)
					(mid -0.7112 0)
					(end 0.7112 0)
				)
			)
			(stroke
				(width 0)
				(type default)
			)
			(fill no)
			(layer "F.Fab")
		)
		(pad "1" smd circle
			(at 0 0)
			(size 0.8128 0.8128)
			(layers "F.Cu" "F.Mask" "F.Paste")
			(net "ACT_HDD_24")
		)
	)
	(footprint ""
		(layer "F.Cu")
		(at 412.877 -146.304)
		(property "Reference" "R557"
			(at 0 0 0)
			(layer "F.SilkS")
			(hide yes)
			(effects
				(font
					(size 1.27 1.27)
				)
			)
		)
		(property "Value" "220R3F-1-GP"
			(at -0.0254 -2.5146 0)
			(unlocked yes)
			(layer "F.Fab")
			(hide yes)
			(effects
				(font
					(size 1.016 1.016)
					(thickness 0.1524)
				)
			)
		)
		(property "Device Type" "R603H22"
			(at -0.0254 -4.0386 0)
			(unlocked yes)
			(layer "F.Fab")
			(hide yes)
			(effects
				(font
					(size 1.016 1.016)
					(thickness 0.1524)
				)
			)
		)
		(duplicate_pad_numbers_are_jumpers no)
		(fp_line
			(start -0.4826 0)
			(end -0.2032 0)
			(stroke
				(width 0.2032)
				(type default)
			)
			(layer "F.SilkS")
		)
		(fp_line
			(start 0.2032 0)
			(end 0.4826 0)
			(stroke
				(width 0.2032)
				(type default)
			)
			(layer "F.SilkS")
		)
		(fp_rect
			(start -0.5842 1.3335)
			(end 0.5842 -1.3335)
			(stroke
				(width 0)
				(type default)
			)
			(fill no)
			(layer "F.CrtYd")
		)
		(fp_rect
			(start -0.5842 1.3335)
			(end 0.5842 -1.3335)
			(stroke
				(width 0)
				(type default)
			)
			(fill no)
			(layer "F.Fab")
		)
		(pad "1" smd custom
			(at 0 -0.762)
			(size 0.2159 0.2159)
			(layers "F.Cu" "F.Mask" "F.Paste")
			(net "HDD_PRSNT_21")
			(options
				(clearance outline)
				(anchor circle)
			)
			(primitives
				(gr_poly
					(pts
						(arc
							(start -0.3302 -0.4318)
							(mid -0.402042 -0.402042)
							(end -0.4318 -0.3302)
						)
						(arc
							(start -0.4318 0.3302)
							(mid -0.402042 0.402042)
							(end -0.3302 0.4318)
						)
						(arc
							(start 0.3302 0.4318)
							(mid 0.402042 0.402042)
							(end 0.4318 0.3302)
						)
						(arc
							(start 0.4318 -0.3302)
							(mid 0.402042 -0.402042)
							(end 0.3302 -0.4318)
						)
					)
					(width 0)
					(fill yes)
				)
			)
		)
		(pad "2" smd custom
			(at 0 0.762)
			(size 0.2159 0.2159)
			(layers "F.Cu" "F.Mask" "F.Paste")
			(net "DRIVE_B_21_INS")
			(options
				(clearance outline)
				(anchor circle)
			)
			(primitives
				(gr_poly
					(pts
						(arc
							(start -0.3302 -0.4318)
							(mid -0.402042 -0.402042)
							(end -0.4318 -0.3302)
						)
						(arc
							(start -0.4318 0.3302)
							(mid -0.402042 0.402042)
							(end -0.3302 0.4318)
						)
						(arc
							(start 0.3302 0.4318)
							(mid 0.402042 0.402042)
							(end 0.4318 0.3302)
						)
						(arc
							(start 0.4318 -0.3302)
							(mid 0.402042 -0.402042)
							(end 0.3302 -0.4318)
						)
					)
					(width 0)
					(fill yes)
				)
			)
		)
	)
	(footprint ""
		(layer "F.Cu")
		(at 462.452212 -21.599906 -90)
		(property "Reference" "R867"
			(at 0 0 270)
			(layer "F.SilkS")
			(hide yes)
			(effects
				(font
					(size 1.27 1.27)
				)
			)
		)
		(property "Value" "4K7R2J-2-GP"
			(at 0.064008 -3.993896 270)
			(unlocked yes)
			(layer "F.Fab")
			(hide yes)
			(effects
				(font
					(size 1.016 1.016)
					(thickness 0.1524)
				)
			)
		)
		(property "Device Type" "R402H16"
			(at 0.064008 -5.517896 270)
			(unlocked yes)
			(layer "F.Fab")
			(hide yes)
			(effects
				(font
					(size 1.016 1.016)
					(thickness 0.1524)
				)
			)
		)
		(duplicate_pad_numbers_are_jumpers no)
		(fp_line
			(start -0.508 -0.9398)
			(end -0.508 0.9398)
			(stroke
				(width 0.1524)
				(type default)
			)
			(layer "F.SilkS")
		)
		(fp_line
			(start 0.508 -0.9398)
			(end -0.508 -0.9398)
			(stroke
				(width 0.1524)
				(type default)
			)
			(layer "F.SilkS")
		)
		(fp_rect
			(start -0.508 0.9398)
			(end 0.508 -0.9398)
			(stroke
				(width 0)
				(type default)
			)
			(fill no)
			(layer "F.CrtYd")
		)
		(fp_rect
			(start -0.508 0.9398)
			(end 0.508 -0.9398)
			(stroke
				(width 0)
				(type default)
			)
			(fill no)
			(layer "F.Fab")
		)
		(pad "1" smd custom
			(at 0 -0.4445 270)
			(size 0.1397 0.1397)
			(layers "F.Cu" "F.Mask" "F.Paste")
			(net "P12V_B")
			(options
				(clearance outline)
				(anchor circle)
			)
			(primitives
				(gr_poly
					(pts
						(arc
							(start -0.1778 -0.2794)
							(mid -0.249642 -0.249642)
							(end -0.2794 -0.1778)
						)
						(arc
							(start -0.2794 0.1778)
							(mid -0.249642 0.249642)
							(end -0.1778 0.2794)
						)
						(arc
							(start 0.1778 0.2794)
							(mid 0.249642 0.249642)
							(end 0.2794 0.1778)
						)
						(arc
							(start 0.2794 -0.1778)
							(mid 0.249642 -0.249642)
							(end 0.1778 -0.2794)
						)
					)
					(width 0)
					(fill yes)
				)
			)
		)
		(pad "2" smd custom
			(at 0 0.4445 270)
			(size 0.1397 0.1397)
			(layers "F.Cu" "F.Mask" "F.Paste")
			(net "SW_HDD_R34")
			(options
				(clearance outline)
				(anchor circle)
			)
			(primitives
				(gr_poly
					(pts
						(arc
							(start -0.1778 -0.2794)
							(mid -0.249642 -0.249642)
							(end -0.2794 -0.1778)
						)
						(arc
							(start -0.2794 0.1778)
							(mid -0.249642 0.249642)
							(end -0.1778 0.2794)
						)
						(arc
							(start 0.1778 0.2794)
							(mid 0.249642 0.249642)
							(end 0.2794 0.1778)
						)
						(arc
							(start 0.2794 -0.1778)
							(mid 0.249642 -0.249642)
							(end 0.1778 -0.2794)
						)
					)
					(width 0)
					(fill yes)
				)
			)
		)
	)
	(footprint ""
		(layer "F.Cu")
		(at 257.0226 -220.27642)
		(property "Reference" "U14"
			(at 0 0 0)
			(layer "F.SilkS")
			(hide yes)
			(effects
				(font
					(size 1.27 1.27)
				)
			)
		)
		(property "Value" "ADC128D818CIMTX-NOPB-1-GP"
			(at 0.127 -12.573 0)
			(unlocked yes)
			(layer "F.Fab")
			(hide yes)
			(effects
				(font
					(size 1.016 1.016)
					(thickness 0.1524)
				)
			)
		)
		(property "Device Type" "TSOIC16H48"
			(at 0.1016 -14.5796 0)
			(unlocked yes)
			(layer "F.Fab")
			(hide yes)
			(effects
				(font
					(size 1.016 1.016)
					(thickness 0.1524)
				)
			)
		)
		(duplicate_pad_numbers_are_jumpers no)
		(fp_line
			(start -3.0988 -1.778)
			(end -3.0988 1.778)
			(stroke
				(width 0.1524)
				(type default)
			)
			(layer "F.SilkS")
		)
		(fp_line
			(start -3.0988 -1.778)
			(end 2.3622 -1.778)
			(stroke
				(width 0.1524)
				(type default)
			)
			(layer "F.SilkS")
		)
		(fp_line
			(start -2.921 3.81)
			(end -2.921 1.778)
			(stroke
				(width 0.508)
				(type default)
			)
			(layer "F.SilkS")
		)
		(fp_line
			(start -2.54 0)
			(end -3.0988 -0.5588)
			(stroke
				(width 0.1524)
				(type default)
			)
			(layer "F.SilkS")
		)
		(fp_line
			(start -2.54 0)
			(end -3.0988 0.5588)
			(stroke
				(width 0.1524)
				(type default)
			)
			(layer "F.SilkS")
		)
		(fp_line
			(start 2.3622 -1.778)
			(end 2.3622 1.778)
			(stroke
				(width 0.1524)
				(type default)
			)
			(layer "F.SilkS")
		)
		(fp_line
			(start 2.3622 1.778)
			(end -2.921 1.778)
			(stroke
				(width 0.1524)
				(type default)
			)
			(layer "F.SilkS")
		)
		(fp_poly
			(pts
				(xy -2.4638 -1.778) (xy -2.4638 1.778) (xy 2.3622 1.778) (xy 2.3622 -1.778)
			)
			(stroke
				(width 0)
				(type default)
			)
			(fill yes)
			(layer "F.SilkS")
		)
		(fp_rect
			(start -3.175 4.064)
			(end 3.175 -4.064)
			(stroke
				(width 0)
				(type default)
			)
			(fill no)
			(layer "F.CrtYd")
		)
		(fp_poly
			(pts
				(xy -3.175 -4.064) (xy 3.175 -4.064) (xy 3.175 4.064) (xy -3.175 4.064)
			)
			(stroke
				(width 0)
				(type default)
			)
			(fill no)
			(layer "F.Fab")
		)
		(pad "1" smd rect
			(at -2.27584 2.8194)
			(size 0.3556 1.524)
			(layers "F.Cu" "F.Mask" "F.Paste")
			(net "Net_266")
		)
		(pad "2" smd rect
			(at -1.6256 2.8194)
			(size 0.3556 1.524)
			(layers "F.Cu" "F.Mask" "F.Paste")
			(net "VOL_SEN_SDA")
		)
		(pad "3" smd rect
			(at -0.97536 2.8194)
			(size 0.3556 1.524)
			(layers "F.Cu" "F.Mask" "F.Paste")
			(net "VOL_SEN_SCL")
		)
		(pad "4" smd rect
			(at -0.32512 2.8194)
			(size 0.3556 1.524)
			(layers "F.Cu" "F.Mask" "F.Paste")
			(net "GND")
		)
		(pad "5" smd rect
			(at 0.32512 2.8194)
			(size 0.3556 1.524)
			(layers "F.Cu" "F.Mask" "F.Paste")
			(net "P3V3_STBY_B")
		)
		(pad "6" smd rect
			(at 0.97536 2.8194)
			(size 0.3556 1.524)
			(layers "F.Cu" "F.Mask" "F.Paste")
			(net "VOL_SEN_INT_N")
		)
		(pad "7" smd rect
			(at 1.6256 2.8194)
			(size 0.3556 1.524)
			(layers "F.Cu" "F.Mask" "F.Paste")
			(net "VOL_SEN_ADDR0")
		)
		(pad "8" smd rect
			(at 2.27584 2.8194)
			(size 0.3556 1.524)
			(layers "F.Cu" "F.Mask" "F.Paste")
			(net "VOL_SEN_ADDR0")
		)
		(pad "9" smd rect
			(at 2.27584 -2.8194)
			(size 0.3556 1.524)
			(layers "F.Cu" "F.Mask" "F.Paste")
			(net "Net_267")
		)
		(pad "10" smd rect
			(at 1.6256 -2.8194)
			(size 0.3556 1.524)
			(layers "F.Cu" "F.Mask" "F.Paste")
			(net "Net_268")
		)
		(pad "11" smd rect
			(at 0.97536 -2.8194)
			(size 0.3556 1.524)
			(layers "F.Cu" "F.Mask" "F.Paste")
			(net "Net_269")
		)
		(pad "12" smd rect
			(at 0.32512 -2.8194)
			(size 0.3556 1.524)
			(layers "F.Cu" "F.Mask" "F.Paste")
			(net "P5V_B_4_SENSE")
		)
		(pad "13" smd rect
			(at -0.32512 -2.8194)
			(size 0.3556 1.524)
			(layers "F.Cu" "F.Mask" "F.Paste")
			(net "P5V_B_3_SENSE")
		)
		(pad "14" smd rect
			(at -0.97536 -2.8194)
			(size 0.3556 1.524)
			(layers "F.Cu" "F.Mask" "F.Paste")
			(net "P5V_B_2_SENSE")
		)
		(pad "15" smd rect
			(at -1.6256 -2.8194)
			(size 0.3556 1.524)
			(layers "F.Cu" "F.Mask" "F.Paste")
			(net "P5V_B_1_SENSE")
		)
		(pad "16" smd rect
			(at -2.27584 -2.8194)
			(size 0.3556 1.524)
			(layers "F.Cu" "F.Mask" "F.Paste")
			(net "P3V3_SENSE")
		)
	)
	(footprint ""
		(layer "F.Cu")
		(at 318.262 -32.8676 180)
		(property "Reference" "R764"
			(at 0 0 180)
			(layer "F.SilkS")
			(hide yes)
			(effects
				(font
					(size 1.27 1.27)
				)
			)
		)
		(property "Value" "220R3F-1-GP"
			(at -0.0254 -2.5146 180)
			(unlocked yes)
			(layer "F.Fab")
			(hide yes)
			(effects
				(font
					(size 1.016 1.016)
					(thickness 0.1524)
				)
			)
		)
		(property "Device Type" "R603H22"
			(at -0.0254 -4.0386 180)
			(unlocked yes)
			(layer "F.Fab")
			(hide yes)
			(effects
				(font
					(size 1.016 1.016)
					(thickness 0.1524)
				)
			)
		)
		(duplicate_pad_numbers_are_jumpers no)
		(fp_line
			(start 0.2032 0)
			(end 0.4826 0)
			(stroke
				(width 0.2032)
				(type default)
			)
			(layer "F.SilkS")
		)
		(fp_line
			(start -0.4826 0)
			(end -0.2032 0)
			(stroke
				(width 0.2032)
				(type default)
			)
			(layer "F.SilkS")
		)
		(fp_rect
			(start -0.5842 1.3335)
			(end 0.5842 -1.3335)
			(stroke
				(width 0)
				(type default)
			)
			(fill no)
			(layer "F.CrtYd")
		)
		(fp_rect
			(start -0.5842 1.3335)
			(end 0.5842 -1.3335)
			(stroke
				(width 0)
				(type default)
			)
			(fill no)
			(layer "F.Fab")
		)
		(pad "1" smd custom
			(at 0 -0.762 180)
			(size 0.2159 0.2159)
			(layers "F.Cu" "F.Mask" "F.Paste")
			(net "HDD_PRSNT_30")
			(options
				(clearance outline)
				(anchor circle)
			)
			(primitives
				(gr_poly
					(pts
						(arc
							(start -0.3302 -0.4318)
							(mid -0.402042 -0.402042)
							(end -0.4318 -0.3302)
						)
						(arc
							(start -0.4318 0.3302)
							(mid -0.402042 0.402042)
							(end -0.3302 0.4318)
						)
						(arc
							(start 0.3302 0.4318)
							(mid 0.402042 0.402042)
							(end 0.4318 0.3302)
						)
						(arc
							(start 0.4318 -0.3302)
							(mid 0.402042 -0.402042)
							(end 0.3302 -0.4318)
						)
					)
					(width 0)
					(fill yes)
				)
			)
		)
		(pad "2" smd custom
			(at 0 0.762 180)
			(size 0.2159 0.2159)
			(layers "F.Cu" "F.Mask" "F.Paste")
			(net "DRIVE_B_30_INS")
			(options
				(clearance outline)
				(anchor circle)
			)
			(primitives
				(gr_poly
					(pts
						(arc
							(start -0.3302 -0.4318)
							(mid -0.402042 -0.402042)
							(end -0.4318 -0.3302)
						)
						(arc
							(start -0.4318 0.3302)
							(mid -0.402042 0.402042)
							(end -0.3302 0.4318)
						)
						(arc
							(start 0.3302 0.4318)
							(mid 0.402042 0.402042)
							(end 0.4318 0.3302)
						)
						(arc
							(start 0.4318 -0.3302)
							(mid 0.402042 -0.402042)
							(end 0.3302 -0.4318)
						)
					)
					(width 0)
					(fill yes)
				)
			)
		)
	)
	(footprint ""
		(layer "F.Cu")
		(at 172.593 -140.462 90)
		(property "Reference" "C260"
			(at 0 0 90)
			(layer "F.SilkS")
			(hide yes)
			(effects
				(font
					(size 1.27 1.27)
				)
			)
		)
		(property "Value" "SCD033U25V2KX-GP"
			(at 1.1811 -2.7051 90)
			(unlocked yes)
			(layer "F.Fab")
			(hide yes)
			(effects
				(font
					(size 1.016 1.016)
					(thickness 0.1524)
				)
			)
		)
		(property "Device Type" "C402H22"
			(at 1.1811 -4.2291 90)
			(unlocked yes)
			(layer "F.Fab")
			(hide yes)
			(effects
				(font
					(size 1.016 1.016)
					(thickness 0.1524)
				)
			)
		)
		(duplicate_pad_numbers_are_jumpers no)
		(fp_rect
			(start -0.4318 0.9525)
			(end 0.4318 -0.9525)
			(stroke
				(width 0)
				(type default)
			)
			(fill no)
			(layer "F.CrtYd")
		)
		(fp_rect
			(start -0.4318 0.9525)
			(end 0.4318 -0.9525)
			(stroke
				(width 0)
				(type default)
			)
			(fill no)
			(layer "F.Fab")
		)
		(pad "1" smd custom
			(at 0 -0.4445 90)
			(size 0.1524 0.1524)
			(layers "F.Cu" "F.Mask" "F.Paste")
			(net "P12V_B")
			(options
				(clearance outline)
				(anchor circle)
			)
			(primitives
				(gr_poly
					(pts
						(arc
							(start 0.3048 -0.2032)
							(mid 0.275042 -0.275042)
							(end 0.2032 -0.3048)
						)
						(arc
							(start -0.2032 -0.3048)
							(mid -0.275042 -0.275042)
							(end -0.3048 -0.2032)
						)
						(arc
							(start -0.3048 0.2032)
							(mid -0.275042 0.275042)
							(end -0.2032 0.3048)
						)
						(arc
							(start 0.2032 0.3048)
							(mid 0.275042 0.275042)
							(end 0.3048 0.2032)
						)
					)
					(width 0)
					(fill yes)
				)
			)
		)
		(pad "2" smd custom
			(at 0 0.4445 90)
			(size 0.1524 0.1524)
			(layers "F.Cu" "F.Mask" "F.Paste")
			(net "SW_HDD_N17")
			(options
				(clearance outline)
				(anchor circle)
			)
			(primitives
				(gr_poly
					(pts
						(arc
							(start 0.3048 -0.2032)
							(mid 0.275042 -0.275042)
							(end 0.2032 -0.3048)
						)
						(arc
							(start -0.2032 -0.3048)
							(mid -0.275042 -0.275042)
							(end -0.3048 -0.2032)
						)
						(arc
							(start -0.3048 0.2032)
							(mid -0.275042 0.275042)
							(end -0.2032 0.3048)
						)
						(arc
							(start 0.2032 0.3048)
							(mid 0.275042 0.275042)
							(end 0.3048 0.2032)
						)
					)
					(width 0)
					(fill yes)
				)
			)
		)
	)
	(footprint ""
		(layer "F.Cu")
		(at 447.9544 -31.6484)
		(property "Reference" "C474"
			(at 0 0 0)
			(layer "F.SilkS")
			(hide yes)
			(effects
				(font
					(size 1.27 1.27)
				)
			)
		)
		(property "Value" "SCD01U50V2KX-1GP"
			(at 1.1811 -2.7051 0)
			(unlocked yes)
			(layer "F.Fab")
			(hide yes)
			(effects
				(font
					(size 1.016 1.016)
					(thickness 0.1524)
				)
			)
		)
		(property "Device Type" "C402H22"
			(at 1.1811 -4.2291 0)
			(unlocked yes)
			(layer "F.Fab")
			(hide yes)
			(effects
				(font
					(size 1.016 1.016)
					(thickness 0.1524)
				)
			)
		)
		(duplicate_pad_numbers_are_jumpers no)
		(fp_rect
			(start -0.4318 0.9525)
			(end 0.4318 -0.9525)
			(stroke
				(width 0)
				(type default)
			)
			(fill no)
			(layer "F.CrtYd")
		)
		(fp_rect
			(start -0.4318 0.9525)
			(end 0.4318 -0.9525)
			(stroke
				(width 0)
				(type default)
			)
			(fill no)
			(layer "F.Fab")
		)
		(pad "1" smd custom
			(at 0 -0.4445)
			(size 0.1524 0.1524)
			(layers "F.Cu" "F.Mask" "F.Paste")
			(net "HDD_PRSNT_34")
			(options
				(clearance outline)
				(anchor circle)
			)
			(primitives
				(gr_poly
					(pts
						(arc
							(start 0.3048 -0.2032)
							(mid 0.275042 -0.275042)
							(end 0.2032 -0.3048)
						)
						(arc
							(start -0.2032 -0.3048)
							(mid -0.275042 -0.275042)
							(end -0.3048 -0.2032)
						)
						(arc
							(start -0.3048 0.2032)
							(mid -0.275042 0.275042)
							(end -0.2032 0.3048)
						)
						(arc
							(start 0.2032 0.3048)
							(mid 0.275042 0.275042)
							(end 0.3048 0.2032)
						)
					)
					(width 0)
					(fill yes)
				)
			)
		)
		(pad "2" smd custom
			(at 0 0.4445)
			(size 0.1524 0.1524)
			(layers "F.Cu" "F.Mask" "F.Paste")
			(net "GND")
			(options
				(clearance outline)
				(anchor circle)
			)
			(primitives
				(gr_poly
					(pts
						(arc
							(start 0.3048 -0.2032)
							(mid 0.275042 -0.275042)
							(end 0.2032 -0.3048)
						)
						(arc
							(start -0.2032 -0.3048)
							(mid -0.275042 -0.275042)
							(end -0.3048 -0.2032)
						)
						(arc
							(start -0.3048 0.2032)
							(mid -0.275042 0.275042)
							(end -0.2032 0.3048)
						)
						(arc
							(start 0.2032 0.3048)
							(mid 0.275042 0.275042)
							(end 0.3048 0.2032)
						)
					)
					(width 0)
					(fill yes)
				)
			)
		)
	)
	(footprint ""
		(layer "F.Cu")
		(at 368.3 -33.02)
		(property "Reference" "Q162"
			(at 0 0 0)
			(layer "F.SilkS")
			(hide yes)
			(effects
				(font
					(size 1.27 1.27)
				)
			)
		)
		(property "Value" "AO4407AL-GP"
			(at -3.707384 -1.5367 0)
			(unlocked yes)
			(layer "F.Fab")
			(hide yes)
			(effects
				(font
					(size 1.016 1.016)
					(thickness 0.1524)
				)
			)
		)
		(property "Device Type" "SOIC8H69"
			(at -3.707384 -3.0607 0)
			(unlocked yes)
			(layer "F.Fab")
			(hide yes)
			(effects
				(font
					(size 1.016 1.016)
					(thickness 0.1524)
				)
			)
		)
		(duplicate_pad_numbers_are_jumpers no)
		(fp_line
			(start -2.7432 -1.4224)
			(end -2.7432 1.4224)
			(stroke
				(width 0.1524)
				(type default)
			)
			(layer "F.SilkS")
		)
		(fp_line
			(start -2.7432 1.4224)
			(end -2.6416 1.4224)
			(stroke
				(width 0.1524)
				(type default)
			)
			(layer "F.SilkS")
		)
		(fp_line
			(start -2.7432 1.4224)
			(end 2.1336 1.4224)
			(stroke
				(width 0.1524)
				(type default)
			)
			(layer "F.SilkS")
		)
		(fp_line
			(start -2.7178 -0.508)
			(end -2.1844 -0.0508)
			(stroke
				(width 0.1524)
				(type default)
			)
			(layer "F.SilkS")
		)
		(fp_line
			(start -2.6289 3.4417)
			(end -2.6289 1.4732)
			(stroke
				(width 0.381)
				(type default)
			)
			(layer "F.SilkS")
		)
		(fp_line
			(start -2.1844 -0.0508)
			(end -2.7178 0.508)
			(stroke
				(width 0.1524)
				(type default)
			)
			(layer "F.SilkS")
		)
		(fp_line
			(start 2.1336 -1.4224)
			(end -2.7432 -1.4224)
			(stroke
				(width 0.1524)
				(type default)
			)
			(layer "F.SilkS")
		)
		(fp_line
			(start 2.1336 1.4224)
			(end 2.1336 -1.4224)
			(stroke
				(width 0.1524)
				(type default)
			)
			(layer "F.SilkS")
		)
		(fp_poly
			(pts
				(xy -2.2098 -1.4224) (xy -2.2098 1.4224) (xy 2.2098 1.4224) (xy 2.2098 -1.4224)
			)
			(stroke
				(width 0)
				(type default)
			)
			(fill yes)
			(layer "F.SilkS")
		)
		(fp_rect
			(start -2.450084 2.999994)
			(end 2.450084 -2.999994)
			(stroke
				(width 0)
				(type default)
			)
			(fill no)
			(layer "F.CrtYd")
		)
		(fp_poly
			(pts
				(xy -2.8194 3.6322) (xy -2.8194 -3.6322) (xy 2.8194 -3.6322) (xy 2.8194 1.18364) (xy 2.450084 1.18364)
				(xy 2.450084 -2.999994) (xy -2.450084 -2.999994) (xy -2.450084 2.999994) (xy 2.450084 2.999994)
				(xy 2.450084 1.18618) (xy 2.8194 1.18618) (xy 2.8194 3.6322)
			)
			(stroke
				(width 0)
				(type default)
			)
			(fill no)
			(layer "F.CrtYd")
		)
		(fp_rect
			(start -2.8194 3.6322)
			(end 2.8194 -3.6322)
			(stroke
				(width 0)
				(type default)
			)
			(fill no)
			(layer "F.Fab")
		)
		(pad "1" smd rect
			(at -1.905 2.54)
			(size 0.635 1.651)
			(layers "F.Cu" "F.Mask" "F.Paste")
			(net "P12V_B")
		)
		(pad "2" smd rect
			(at -0.635 2.54)
			(size 0.635 1.651)
			(layers "F.Cu" "F.Mask" "F.Paste")
			(net "P12V_B")
		)
		(pad "3" smd rect
			(at 0.635 2.54)
			(size 0.635 1.651)
			(layers "F.Cu" "F.Mask" "F.Paste")
			(net "P12V_B")
		)
		(pad "4" smd rect
			(at 1.905 2.54)
			(size 0.635 1.651)
			(layers "F.Cu" "F.Mask" "F.Paste")
			(net "SW_HDD_N31")
		)
		(pad "5" smd rect
			(at 1.905 -2.54)
			(size 0.635 1.651)
			(layers "F.Cu" "F.Mask" "F.Paste")
			(net "P12V_HDD31")
		)
		(pad "6" smd rect
			(at 0.635 -2.54)
			(size 0.635 1.651)
			(layers "F.Cu" "F.Mask" "F.Paste")
			(net "P12V_HDD31")
		)
		(pad "7" smd rect
			(at -0.635 -2.54)
			(size 0.635 1.651)
			(layers "F.Cu" "F.Mask" "F.Paste")
			(net "P12V_HDD31")
		)
		(pad "8" smd rect
			(at -1.905 -2.54)
			(size 0.635 1.651)
			(layers "F.Cu" "F.Mask" "F.Paste")
			(net "P12V_HDD31")
		)
	)
	(footprint ""
		(layer "F.Cu")
		(at 268.224 -209.3595 90)
		(property "Reference" "R13"
			(at 0 0 90)
			(layer "F.SilkS")
			(hide yes)
			(effects
				(font
					(size 1.27 1.27)
				)
			)
		)
		(property "Value" "1KR2J-1-GP"
			(at 0.064008 -3.993896 90)
			(unlocked yes)
			(layer "F.Fab")
			(hide yes)
			(effects
				(font
					(size 1.016 1.016)
					(thickness 0.1524)
				)
			)
		)
		(property "Device Type" "R402H16"
			(at 0.064008 -5.517896 90)
			(unlocked yes)
			(layer "F.Fab")
			(hide yes)
			(effects
				(font
					(size 1.016 1.016)
					(thickness 0.1524)
				)
			)
		)
		(duplicate_pad_numbers_are_jumpers no)
		(fp_line
			(start 0.508 -0.9398)
			(end -0.508 -0.9398)
			(stroke
				(width 0.1524)
				(type default)
			)
			(layer "F.SilkS")
		)
		(fp_line
			(start -0.508 -0.9398)
			(end -0.508 0.9398)
			(stroke
				(width 0.1524)
				(type default)
			)
			(layer "F.SilkS")
		)
		(fp_rect
			(start -0.508 0.9398)
			(end 0.508 -0.9398)
			(stroke
				(width 0)
				(type default)
			)
			(fill no)
			(layer "F.CrtYd")
		)
		(fp_rect
			(start -0.508 0.9398)
			(end 0.508 -0.9398)
			(stroke
				(width 0)
				(type default)
			)
			(fill no)
			(layer "F.Fab")
		)
		(pad "1" smd custom
			(at 0 -0.4445 90)
			(size 0.1397 0.1397)
			(layers "F.Cu" "F.Mask" "F.Paste")
			(net "P3V3_STBY_B")
			(options
				(clearance outline)
				(anchor circle)
			)
			(primitives
				(gr_poly
					(pts
						(arc
							(start -0.1778 -0.2794)
							(mid -0.249642 -0.249642)
							(end -0.2794 -0.1778)
						)
						(arc
							(start -0.2794 0.1778)
							(mid -0.249642 0.249642)
							(end -0.1778 0.2794)
						)
						(arc
							(start 0.1778 0.2794)
							(mid 0.249642 0.249642)
							(end 0.2794 0.1778)
						)
						(arc
							(start 0.2794 -0.1778)
							(mid 0.249642 -0.249642)
							(end 0.1778 -0.2794)
						)
					)
					(width 0)
					(fill yes)
				)
			)
		)
		(pad "2" smd custom
			(at 0 0.4445 90)
			(size 0.1397 0.1397)
			(layers "F.Cu" "F.Mask" "F.Paste")
			(net "I2C_DRIVE_B_FLT_LED_SDA")
			(options
				(clearance outline)
				(anchor circle)
			)
			(primitives
				(gr_poly
					(pts
						(arc
							(start -0.1778 -0.2794)
							(mid -0.249642 -0.249642)
							(end -0.2794 -0.1778)
						)
						(arc
							(start -0.2794 0.1778)
							(mid -0.249642 0.249642)
							(end -0.1778 0.2794)
						)
						(arc
							(start 0.1778 0.2794)
							(mid 0.249642 0.249642)
							(end 0.2794 0.1778)
						)
						(arc
							(start 0.2794 -0.1778)
							(mid 0.249642 -0.249642)
							(end 0.1778 -0.2794)
						)
					)
					(width 0)
					(fill yes)
				)
			)
		)
	)
	(footprint ""
		(layer "F.Cu")
		(at 369.57 -250.444 90)
		(property "Reference" "R282"
			(at 0 0 90)
			(layer "F.SilkS")
			(hide yes)
			(effects
				(font
					(size 1.27 1.27)
				)
			)
		)
		(property "Value" "200KR2F-L-GP"
			(at 0.064008 -3.993896 90)
			(unlocked yes)
			(layer "F.Fab")
			(hide yes)
			(effects
				(font
					(size 1.016 1.016)
					(thickness 0.1524)
				)
			)
		)
		(property "Device Type" "R402H16"
			(at 0.064008 -5.517896 90)
			(unlocked yes)
			(layer "F.Fab")
			(hide yes)
			(effects
				(font
					(size 1.016 1.016)
					(thickness 0.1524)
				)
			)
		)
		(duplicate_pad_numbers_are_jumpers no)
		(fp_line
			(start 0.508 -0.9398)
			(end -0.508 -0.9398)
			(stroke
				(width 0.1524)
				(type default)
			)
			(layer "F.SilkS")
		)
		(fp_line
			(start -0.508 -0.9398)
			(end -0.508 0.9398)
			(stroke
				(width 0.1524)
				(type default)
			)
			(layer "F.SilkS")
		)
		(fp_rect
			(start -0.508 0.9398)
			(end 0.508 -0.9398)
			(stroke
				(width 0)
				(type default)
			)
			(fill no)
			(layer "F.CrtYd")
		)
		(fp_rect
			(start -0.508 0.9398)
			(end 0.508 -0.9398)
			(stroke
				(width 0)
				(type default)
			)
			(fill no)
			(layer "F.Fab")
		)
		(pad "1" smd custom
			(at 0 -0.4445 90)
			(size 0.1397 0.1397)
			(layers "F.Cu" "F.Mask" "F.Paste")
			(net "SW_HDD_R7")
			(options
				(clearance outline)
				(anchor circle)
			)
			(primitives
				(gr_poly
					(pts
						(arc
							(start -0.1778 -0.2794)
							(mid -0.249642 -0.249642)
							(end -0.2794 -0.1778)
						)
						(arc
							(start -0.2794 0.1778)
							(mid -0.249642 0.249642)
							(end -0.1778 0.2794)
						)
						(arc
							(start 0.1778 0.2794)
							(mid 0.249642 0.249642)
							(end 0.2794 0.1778)
						)
						(arc
							(start 0.2794 -0.1778)
							(mid 0.249642 -0.249642)
							(end 0.1778 -0.2794)
						)
					)
					(width 0)
					(fill yes)
				)
			)
		)
		(pad "2" smd custom
			(at 0 0.4445 90)
			(size 0.1397 0.1397)
			(layers "F.Cu" "F.Mask" "F.Paste")
			(net "SW_HDD_N7")
			(options
				(clearance outline)
				(anchor circle)
			)
			(primitives
				(gr_poly
					(pts
						(arc
							(start -0.1778 -0.2794)
							(mid -0.249642 -0.249642)
							(end -0.2794 -0.1778)
						)
						(arc
							(start -0.2794 0.1778)
							(mid -0.249642 0.249642)
							(end -0.1778 0.2794)
						)
						(arc
							(start 0.1778 0.2794)
							(mid 0.249642 0.249642)
							(end 0.2794 0.1778)
						)
						(arc
							(start 0.2794 -0.1778)
							(mid 0.249642 -0.249642)
							(end 0.1778 -0.2794)
						)
					)
					(width 0)
					(fill yes)
				)
			)
		)
	)
	(footprint ""
		(layer "F.Cu")
		(at 44.54906 -118.310406 180)
		(property "Reference" "R1134"
			(at 0 0 180)
			(layer "F.SilkS")
			(hide yes)
			(effects
				(font
					(size 1.27 1.27)
				)
			)
		)
		(property "Value" "619KR2F-GP"
			(at 0.064008 -3.993896 180)
			(unlocked yes)
			(layer "F.Fab")
			(hide yes)
			(effects
				(font
					(size 1.016 1.016)
					(thickness 0.1524)
				)
			)
		)
		(property "Device Type" "R402H16"
			(at 0.064008 -5.517896 180)
			(unlocked yes)
			(layer "F.Fab")
			(hide yes)
			(effects
				(font
					(size 1.016 1.016)
					(thickness 0.1524)
				)
			)
		)
		(duplicate_pad_numbers_are_jumpers no)
		(fp_line
			(start 0.508 -0.9398)
			(end -0.508 -0.9398)
			(stroke
				(width 0.1524)
				(type default)
			)
			(layer "F.SilkS")
		)
		(fp_line
			(start -0.508 -0.9398)
			(end -0.508 0.9398)
			(stroke
				(width 0.1524)
				(type default)
			)
			(layer "F.SilkS")
		)
		(fp_rect
			(start -0.508 0.9398)
			(end 0.508 -0.9398)
			(stroke
				(width 0)
				(type default)
			)
			(fill no)
			(layer "F.CrtYd")
		)
		(fp_rect
			(start -0.508 0.9398)
			(end 0.508 -0.9398)
			(stroke
				(width 0)
				(type default)
			)
			(fill no)
			(layer "F.Fab")
		)
		(pad "1" smd custom
			(at 0 -0.4445 180)
			(size 0.1397 0.1397)
			(layers "F.Cu" "F.Mask" "F.Paste")
			(net "P5V_B_2_RF")
			(options
				(clearance outline)
				(anchor circle)
			)
			(primitives
				(gr_poly
					(pts
						(arc
							(start -0.1778 -0.2794)
							(mid -0.249642 -0.249642)
							(end -0.2794 -0.1778)
						)
						(arc
							(start -0.2794 0.1778)
							(mid -0.249642 0.249642)
							(end -0.1778 0.2794)
						)
						(arc
							(start 0.1778 0.2794)
							(mid 0.249642 0.249642)
							(end 0.2794 0.1778)
						)
						(arc
							(start 0.2794 -0.1778)
							(mid 0.249642 -0.249642)
							(end 0.1778 -0.2794)
						)
					)
					(width 0)
					(fill yes)
				)
			)
		)
		(pad "2" smd custom
			(at 0 0.4445 180)
			(size 0.1397 0.1397)
			(layers "F.Cu" "F.Mask" "F.Paste")
			(net "AGND_P5V_B_2")
			(options
				(clearance outline)
				(anchor circle)
			)
			(primitives
				(gr_poly
					(pts
						(arc
							(start -0.1778 -0.2794)
							(mid -0.249642 -0.249642)
							(end -0.2794 -0.1778)
						)
						(arc
							(start -0.2794 0.1778)
							(mid -0.249642 0.249642)
							(end -0.1778 0.2794)
						)
						(arc
							(start 0.1778 0.2794)
							(mid 0.249642 0.249642)
							(end 0.2794 0.1778)
						)
						(arc
							(start 0.2794 -0.1778)
							(mid 0.249642 -0.249642)
							(end 0.1778 -0.2794)
						)
					)
					(width 0)
					(fill yes)
				)
			)
		)
	)
	(footprint ""
		(layer "F.Cu")
		(at 457.93533 -229.963218 90)
		(property "Reference" "R1146"
			(at 0 0 90)
			(layer "F.SilkS")
			(hide yes)
			(effects
				(font
					(size 1.27 1.27)
				)
			)
		)
		(property "Value" "100KR2F-L1-GP"
			(at 0.064008 -3.993896 90)
			(unlocked yes)
			(layer "F.Fab")
			(hide yes)
			(effects
				(font
					(size 1.016 1.016)
					(thickness 0.1524)
				)
			)
		)
		(property "Device Type" "R402H16"
			(at 0.064008 -5.517896 90)
			(unlocked yes)
			(layer "F.Fab")
			(hide yes)
			(effects
				(font
					(size 1.016 1.016)
					(thickness 0.1524)
				)
			)
		)
		(duplicate_pad_numbers_are_jumpers no)
		(fp_line
			(start 0.508 -0.9398)
			(end -0.508 -0.9398)
			(stroke
				(width 0.1524)
				(type default)
			)
			(layer "F.SilkS")
		)
		(fp_line
			(start -0.508 -0.9398)
			(end -0.508 0.9398)
			(stroke
				(width 0.1524)
				(type default)
			)
			(layer "F.SilkS")
		)
		(fp_rect
			(start -0.508 0.9398)
			(end 0.508 -0.9398)
			(stroke
				(width 0)
				(type default)
			)
			(fill no)
			(layer "F.CrtYd")
		)
		(fp_rect
			(start -0.508 0.9398)
			(end 0.508 -0.9398)
			(stroke
				(width 0)
				(type default)
			)
			(fill no)
			(layer "F.Fab")
		)
		(pad "1" smd custom
			(at 0 -0.4445 90)
			(size 0.1397 0.1397)
			(layers "F.Cu" "F.Mask" "F.Paste")
			(net "AGND_P5V_B_3")
			(options
				(clearance outline)
				(anchor circle)
			)
			(primitives
				(gr_poly
					(pts
						(arc
							(start -0.1778 -0.2794)
							(mid -0.249642 -0.249642)
							(end -0.2794 -0.1778)
						)
						(arc
							(start -0.2794 0.1778)
							(mid -0.249642 0.249642)
							(end -0.1778 0.2794)
						)
						(arc
							(start 0.1778 0.2794)
							(mid 0.249642 0.249642)
							(end 0.2794 0.1778)
						)
						(arc
							(start 0.2794 -0.1778)
							(mid 0.249642 -0.249642)
							(end 0.1778 -0.2794)
						)
					)
					(width 0)
					(fill yes)
				)
			)
		)
		(pad "2" smd custom
			(at 0 0.4445 90)
			(size 0.1397 0.1397)
			(layers "F.Cu" "F.Mask" "F.Paste")
			(net "P5V_B_3_MODE")
			(options
				(clearance outline)
				(anchor circle)
			)
			(primitives
				(gr_poly
					(pts
						(arc
							(start -0.1778 -0.2794)
							(mid -0.249642 -0.249642)
							(end -0.2794 -0.1778)
						)
						(arc
							(start -0.2794 0.1778)
							(mid -0.249642 0.249642)
							(end -0.1778 0.2794)
						)
						(arc
							(start 0.1778 0.2794)
							(mid 0.249642 0.249642)
							(end 0.2794 0.1778)
						)
						(arc
							(start 0.2794 -0.1778)
							(mid 0.249642 -0.249642)
							(end 0.1778 -0.2794)
						)
					)
					(width 0)
					(fill yes)
				)
			)
		)
	)
	(footprint ""
		(layer "F.Cu")
		(at 54.37886 -120.342406)
		(property "Reference" "TP203"
			(at 0 0 0)
			(layer "F.SilkS")
			(hide yes)
			(effects
				(font
					(size 1.27 1.27)
				)
			)
		)
		(property "Value" "*"
			(at -0.0508 -1.6764 0)
			(unlocked yes)
			(layer "F.Fab")
			(hide yes)
			(effects
				(font
					(size 1.016 1.016)
					(thickness 0.1524)
				)
			)
		)
		(property "Device Type" "TPAD32"
			(at -0.0508 -3.2004 0)
			(unlocked yes)
			(layer "F.Fab")
			(hide yes)
			(effects
				(font
					(size 1.016 1.016)
					(thickness 0.1524)
				)
			)
		)
		(duplicate_pad_numbers_are_jumpers no)
		(fp_poly
			(pts
				(arc
					(start 0.4064 0)
					(mid -0.4064 0)
					(end 0.4064 0)
				)
			)
			(stroke
				(width 0)
				(type default)
			)
			(fill no)
			(layer "F.CrtYd")
		)
		(fp_poly
			(pts
				(arc
					(start 0.7112 0)
					(mid -0.7112 0)
					(end 0.7112 0)
				)
			)
			(stroke
				(width 0)
				(type default)
			)
			(fill no)
			(layer "F.Fab")
		)
		(pad "1" smd circle
			(at 0 0)
			(size 0.8128 0.8128)
			(layers "F.Cu" "F.Mask" "F.Paste")
			(net "P5V_B_2_PGOOD")
		)
	)
	(footprint ""
		(layer "F.Cu")
		(at 134.1628 -370.7384 180)
		(property "Reference" "R940"
			(at 0 0 180)
			(layer "F.SilkS")
			(hide yes)
			(effects
				(font
					(size 1.27 1.27)
				)
			)
		)
		(property "Value" "27KR3F-GP"
			(at -0.0254 -2.5146 180)
			(unlocked yes)
			(layer "F.Fab")
			(hide yes)
			(effects
				(font
					(size 1.016 1.016)
					(thickness 0.1524)
				)
			)
		)
		(property "Device Type" "R603H22"
			(at -0.0254 -4.0386 180)
			(unlocked yes)
			(layer "F.Fab")
			(hide yes)
			(effects
				(font
					(size 1.016 1.016)
					(thickness 0.1524)
				)
			)
		)
		(duplicate_pad_numbers_are_jumpers no)
		(fp_line
			(start 0.2032 0)
			(end 0.4826 0)
			(stroke
				(width 0.2032)
				(type default)
			)
			(layer "F.SilkS")
		)
		(fp_line
			(start -0.4826 0)
			(end -0.2032 0)
			(stroke
				(width 0.2032)
				(type default)
			)
			(layer "F.SilkS")
		)
		(fp_rect
			(start -0.5842 1.3335)
			(end 0.5842 -1.3335)
			(stroke
				(width 0)
				(type default)
			)
			(fill no)
			(layer "F.CrtYd")
		)
		(fp_rect
			(start -0.5842 1.3335)
			(end 0.5842 -1.3335)
			(stroke
				(width 0)
				(type default)
			)
			(fill no)
			(layer "F.Fab")
		)
		(pad "1" smd custom
			(at 0 -0.762 180)
			(size 0.2159 0.2159)
			(layers "F.Cu" "F.Mask" "F.Paste")
			(net "FAN_1_TACH1")
			(options
				(clearance outline)
				(anchor circle)
			)
			(primitives
				(gr_poly
					(pts
						(arc
							(start -0.3302 -0.4318)
							(mid -0.402042 -0.402042)
							(end -0.4318 -0.3302)
						)
						(arc
							(start -0.4318 0.3302)
							(mid -0.402042 0.402042)
							(end -0.3302 0.4318)
						)
						(arc
							(start 0.3302 0.4318)
							(mid 0.402042 0.402042)
							(end 0.4318 0.3302)
						)
						(arc
							(start 0.4318 -0.3302)
							(mid 0.402042 -0.402042)
							(end 0.3302 -0.4318)
						)
					)
					(width 0)
					(fill yes)
				)
			)
		)
		(pad "2" smd custom
			(at 0 0.762 180)
			(size 0.2159 0.2159)
			(layers "F.Cu" "F.Mask" "F.Paste")
			(net "FANTACH_F1")
			(options
				(clearance outline)
				(anchor circle)
			)
			(primitives
				(gr_poly
					(pts
						(arc
							(start -0.3302 -0.4318)
							(mid -0.402042 -0.402042)
							(end -0.4318 -0.3302)
						)
						(arc
							(start -0.4318 0.3302)
							(mid -0.402042 0.402042)
							(end -0.3302 0.4318)
						)
						(arc
							(start 0.3302 0.4318)
							(mid 0.402042 0.402042)
							(end 0.4318 0.3302)
						)
						(arc
							(start 0.4318 -0.3302)
							(mid 0.402042 -0.402042)
							(end 0.3302 -0.4318)
						)
					)
					(width 0)
					(fill yes)
				)
			)
		)
	)
	(footprint ""
		(layer "F.Cu")
		(at 459.613 -274.955 180)
		(property "Reference" "C165"
			(at 0 0 180)
			(layer "F.SilkS")
			(hide yes)
			(effects
				(font
					(size 1.27 1.27)
				)
			)
		)
		(property "Value" "SC4D7U25V5KX-1-GP"
			(at -0.0762 -6.1214 180)
			(unlocked yes)
			(layer "F.Fab")
			(hide yes)
			(effects
				(font
					(size 1.016 1.016)
					(thickness 0.1524)
				)
			)
		)
		(property "Device Type" "C805H58"
			(at -0.0762 -8.1534 180)
			(unlocked yes)
			(layer "F.Fab")
			(hide yes)
			(effects
				(font
					(size 1.016 1.016)
					(thickness 0.1524)
				)
			)
		)
		(duplicate_pad_numbers_are_jumpers no)
		(fp_line
			(start 0.635 0)
			(end -0.635 0)
			(stroke
				(width 0.508)
				(type default)
			)
			(layer "F.SilkS")
		)
		(fp_rect
			(start -0.9652 1.778)
			(end 0.9652 -1.778)
			(stroke
				(width 0)
				(type default)
			)
			(fill no)
			(layer "F.CrtYd")
		)
		(fp_poly
			(pts
				(xy -0.9652 -1.778) (xy 0.9652 -1.778) (xy 0.9652 1.778) (xy -0.9652 1.778)
			)
			(stroke
				(width 0)
				(type default)
			)
			(fill no)
			(layer "F.Fab")
		)
		(pad "1" smd rect
			(at 0 -0.9652 180)
			(size 1.397 1.143)
			(layers "F.Cu" "F.Mask" "F.Paste")
			(net "P12V_HDD10")
		)
		(pad "2" smd rect
			(at 0 0.9652 180)
			(size 1.397 1.143)
			(layers "F.Cu" "F.Mask" "F.Paste")
			(net "GND")
		)
	)
	(footprint ""
		(layer "F.Cu")
		(at 283.41955 -157.541722)
		(property "Reference" "R490"
			(at 0 0 0)
			(layer "F.SilkS")
			(hide yes)
			(effects
				(font
					(size 1.27 1.27)
				)
			)
		)
		(property "Value" "0R2J-2-GP"
			(at 0.064008 -3.993896 0)
			(unlocked yes)
			(layer "F.Fab")
			(hide yes)
			(effects
				(font
					(size 1.016 1.016)
					(thickness 0.1524)
				)
			)
		)
		(property "Device Type" "R402H16"
			(at 0.064008 -5.517896 0)
			(unlocked yes)
			(layer "F.Fab")
			(hide yes)
			(effects
				(font
					(size 1.016 1.016)
					(thickness 0.1524)
				)
			)
		)
		(duplicate_pad_numbers_are_jumpers no)
		(fp_line
			(start -0.508 -0.9398)
			(end -0.508 0.9398)
			(stroke
				(width 0.1524)
				(type default)
			)
			(layer "F.SilkS")
		)
		(fp_line
			(start 0.508 -0.9398)
			(end -0.508 -0.9398)
			(stroke
				(width 0.1524)
				(type default)
			)
			(layer "F.SilkS")
		)
		(fp_rect
			(start -0.508 0.9398)
			(end 0.508 -0.9398)
			(stroke
				(width 0)
				(type default)
			)
			(fill no)
			(layer "F.CrtYd")
		)
		(fp_rect
			(start -0.508 0.9398)
			(end 0.508 -0.9398)
			(stroke
				(width 0)
				(type default)
			)
			(fill no)
			(layer "F.Fab")
		)
		(pad "1" smd custom
			(at 0 -0.4445)
			(size 0.1397 0.1397)
			(layers "F.Cu" "F.Mask" "F.Paste")
			(net "SCC_B_HS_EN")
			(options
				(clearance outline)
				(anchor circle)
			)
			(primitives
				(gr_poly
					(pts
						(arc
							(start -0.1778 -0.2794)
							(mid -0.249642 -0.249642)
							(end -0.2794 -0.1778)
						)
						(arc
							(start -0.2794 0.1778)
							(mid -0.249642 0.249642)
							(end -0.1778 0.2794)
						)
						(arc
							(start 0.1778 0.2794)
							(mid 0.249642 0.249642)
							(end 0.2794 0.1778)
						)
						(arc
							(start 0.2794 -0.1778)
							(mid 0.249642 -0.249642)
							(end 0.1778 -0.2794)
						)
					)
					(width 0)
					(fill yes)
				)
			)
		)
		(pad "2" smd custom
			(at 0 0.4445)
			(size 0.1397 0.1397)
			(layers "F.Cu" "F.Mask" "F.Paste")
			(net "GND")
			(options
				(clearance outline)
				(anchor circle)
			)
			(primitives
				(gr_poly
					(pts
						(arc
							(start -0.1778 -0.2794)
							(mid -0.249642 -0.249642)
							(end -0.2794 -0.1778)
						)
						(arc
							(start -0.2794 0.1778)
							(mid -0.249642 0.249642)
							(end -0.1778 0.2794)
						)
						(arc
							(start 0.1778 0.2794)
							(mid 0.249642 0.249642)
							(end 0.2794 0.1778)
						)
						(arc
							(start 0.2794 -0.1778)
							(mid 0.249642 -0.249642)
							(end 0.1778 -0.2794)
						)
					)
					(width 0)
					(fill yes)
				)
			)
		)
	)
	(footprint ""
		(layer "F.Cu")
		(at 319.216024 -39.705026)
		(property "Reference" "TP171"
			(at 0 0 0)
			(layer "F.SilkS")
			(hide yes)
			(effects
				(font
					(size 1.27 1.27)
				)
			)
		)
		(property "Value" "*"
			(at -0.0508 -1.6764 0)
			(unlocked yes)
			(layer "F.Fab")
			(hide yes)
			(effects
				(font
					(size 1.016 1.016)
					(thickness 0.1524)
				)
			)
		)
		(property "Device Type" "TPAD32"
			(at -0.0508 -3.2004 0)
			(unlocked yes)
			(layer "F.Fab")
			(hide yes)
			(effects
				(font
					(size 1.016 1.016)
					(thickness 0.1524)
				)
			)
		)
		(duplicate_pad_numbers_are_jumpers no)
		(fp_poly
			(pts
				(arc
					(start 0.4064 0)
					(mid -0.4064 0)
					(end 0.4064 0)
				)
			)
			(stroke
				(width 0)
				(type default)
			)
			(fill no)
			(layer "F.CrtYd")
		)
		(fp_poly
			(pts
				(arc
					(start 0.7112 0)
					(mid -0.7112 0)
					(end 0.7112 0)
				)
			)
			(stroke
				(width 0)
				(type default)
			)
			(fill no)
			(layer "F.Fab")
		)
		(pad "1" smd circle
			(at 0 0)
			(size 0.8128 0.8128)
			(layers "F.Cu" "F.Mask" "F.Paste")
			(net "ACT_HDD_30")
		)
	)
	(footprint ""
		(layer "F.Cu")
		(at 315.149992 -180.399944)
		(property "Reference" "LED7"
			(at 0 0 0)
			(layer "F.SilkS")
			(hide yes)
			(effects
				(font
					(size 1.27 1.27)
				)
			)
		)
		(property "Value" "LED-BY-19-GP"
			(at -2.132076 1.414018 0)
			(unlocked yes)
			(layer "F.Fab")
			(hide yes)
			(effects
				(font
					(size 1.016 1.016)
					(thickness 0.1524)
				)
			)
		)
		(property "Device Type" "LED-1615-4PH26"
			(at -2.132076 -0.109982 0)
			(unlocked yes)
			(layer "F.Fab")
			(hide yes)
			(effects
				(font
					(size 1.016 1.016)
					(thickness 0.1524)
				)
			)
		)
		(duplicate_pad_numbers_are_jumpers no)
		(fp_line
			(start -1.2954 0.254)
			(end -1.2954 1.6002)
			(stroke
				(width 0.508)
				(type default)
			)
			(layer "F.SilkS")
		)
		(fp_line
			(start -1.2954 1.6002)
			(end 1.2954 1.6002)
			(stroke
				(width 0.508)
				(type default)
			)
			(layer "F.SilkS")
		)
		(fp_line
			(start -1.1176 -1.4224)
			(end 1.1176 -1.4224)
			(stroke
				(width 0.1524)
				(type default)
			)
			(layer "F.SilkS")
		)
		(fp_line
			(start -1.1176 1.4224)
			(end -1.1176 -1.4224)
			(stroke
				(width 0.1524)
				(type default)
			)
			(layer "F.SilkS")
		)
		(fp_line
			(start 1.1176 -1.4224)
			(end 1.1176 1.4224)
			(stroke
				(width 0.1524)
				(type default)
			)
			(layer "F.SilkS")
		)
		(fp_line
			(start 1.1176 1.4224)
			(end -1.1176 1.4224)
			(stroke
				(width 0.1524)
				(type default)
			)
			(layer "F.SilkS")
		)
		(fp_line
			(start 1.2954 1.6002)
			(end 1.2954 0.254)
			(stroke
				(width 0.508)
				(type default)
			)
			(layer "F.SilkS")
		)
		(fp_rect
			(start -0.7493 0.8001)
			(end 0.7493 -0.8001)
			(stroke
				(width 0)
				(type default)
			)
			(fill no)
			(layer "F.CrtYd")
		)
		(fp_poly
			(pts
				(xy -1.3716 1.6764) (xy -1.3716 -1.6764) (xy 1.3716 -1.6764) (xy 1.3716 0.0635) (xy 0.7493 0.0635)
				(xy 0.7493 -0.8001) (xy -0.7493 -0.8001) (xy -0.7493 0.8001) (xy 0.7493 0.8001) (xy 0.7493 0.0762)
				(xy 1.3716 0.0762) (xy 1.3716 1.6764)
			)
			(stroke
				(width 0)
				(type default)
			)
			(fill no)
			(layer "F.CrtYd")
		)
		(fp_rect
			(start -1.3716 1.6764)
			(end 1.3716 -1.6764)
			(stroke
				(width 0)
				(type default)
			)
			(fill no)
			(layer "F.Fab")
		)
		(pad "1" smd rect
			(at 0.50038 -0.73025)
			(size 0.7112 0.8636)
			(layers "F.Cu" "F.Mask" "F.Paste")
			(net "DRV_ACT_6")
		)
		(pad "2" smd rect
			(at -0.50038 -0.73025)
			(size 0.7112 0.8636)
			(layers "F.Cu" "F.Mask" "F.Paste")
			(net "FLT_HDD6")
		)
		(pad "3" smd rect
			(at 0.50038 0.73025)
			(size 0.7112 0.8636)
			(layers "F.Cu" "F.Mask" "F.Paste")
			(net "DRV_ACT_6_N")
		)
		(pad "4" smd rect
			(at -0.50038 0.73025)
			(size 0.7112 0.8636)
			(layers "F.Cu" "F.Mask" "F.Paste")
			(net "FLT_HDD6_N")
		)
	)
	(footprint ""
		(layer "F.Cu")
		(at 395.224 -128.651)
		(property "Reference" "R542"
			(at 0 0 0)
			(layer "F.SilkS")
			(hide yes)
			(effects
				(font
					(size 1.27 1.27)
				)
			)
		)
		(property "Value" "4K7R2F-GP"
			(at 0.064008 -3.993896 0)
			(unlocked yes)
			(layer "F.Fab")
			(hide yes)
			(effects
				(font
					(size 1.016 1.016)
					(thickness 0.1524)
				)
			)
		)
		(property "Device Type" "R402H16"
			(at 0.064008 -5.517896 0)
			(unlocked yes)
			(layer "F.Fab")
			(hide yes)
			(effects
				(font
					(size 1.016 1.016)
					(thickness 0.1524)
				)
			)
		)
		(duplicate_pad_numbers_are_jumpers no)
		(fp_line
			(start -0.508 -0.9398)
			(end -0.508 0.9398)
			(stroke
				(width 0.1524)
				(type default)
			)
			(layer "F.SilkS")
		)
		(fp_line
			(start 0.508 -0.9398)
			(end -0.508 -0.9398)
			(stroke
				(width 0.1524)
				(type default)
			)
			(layer "F.SilkS")
		)
		(fp_rect
			(start -0.508 0.9398)
			(end 0.508 -0.9398)
			(stroke
				(width 0)
				(type default)
			)
			(fill no)
			(layer "F.CrtYd")
		)
		(fp_rect
			(start -0.508 0.9398)
			(end 0.508 -0.9398)
			(stroke
				(width 0)
				(type default)
			)
			(fill no)
			(layer "F.Fab")
		)
		(pad "1" smd custom
			(at 0 -0.4445)
			(size 0.1397 0.1397)
			(layers "F.Cu" "F.Mask" "F.Paste")
			(net "SW_PWR_R_HDD20")
			(options
				(clearance outline)
				(anchor circle)
			)
			(primitives
				(gr_poly
					(pts
						(arc
							(start -0.1778 -0.2794)
							(mid -0.249642 -0.249642)
							(end -0.2794 -0.1778)
						)
						(arc
							(start -0.2794 0.1778)
							(mid -0.249642 0.249642)
							(end -0.1778 0.2794)
						)
						(arc
							(start 0.1778 0.2794)
							(mid 0.249642 0.249642)
							(end 0.2794 0.1778)
						)
						(arc
							(start 0.2794 -0.1778)
							(mid 0.249642 -0.249642)
							(end 0.1778 -0.2794)
						)
					)
					(width 0)
					(fill yes)
				)
			)
		)
		(pad "2" smd custom
			(at 0 0.4445)
			(size 0.1397 0.1397)
			(layers "F.Cu" "F.Mask" "F.Paste")
			(net "GND")
			(options
				(clearance outline)
				(anchor circle)
			)
			(primitives
				(gr_poly
					(pts
						(arc
							(start -0.1778 -0.2794)
							(mid -0.249642 -0.249642)
							(end -0.2794 -0.1778)
						)
						(arc
							(start -0.2794 0.1778)
							(mid -0.249642 0.249642)
							(end -0.1778 0.2794)
						)
						(arc
							(start 0.1778 0.2794)
							(mid 0.249642 0.249642)
							(end 0.2794 0.1778)
						)
						(arc
							(start 0.2794 -0.1778)
							(mid 0.249642 -0.249642)
							(end 0.1778 -0.2794)
						)
					)
					(width 0)
					(fill yes)
				)
			)
		)
	)
	(footprint ""
		(layer "F.Cu")
		(at 45.814996 -360.299)
		(property "Reference" "R963"
			(at 0 0 0)
			(layer "F.SilkS")
			(hide yes)
			(effects
				(font
					(size 1.27 1.27)
				)
			)
		)
		(property "Value" "4K7R2J-2-GP"
			(at 0.064008 -3.993896 0)
			(unlocked yes)
			(layer "F.Fab")
			(hide yes)
			(effects
				(font
					(size 1.016 1.016)
					(thickness 0.1524)
				)
			)
		)
		(property "Device Type" "R402H16"
			(at 0.064008 -5.517896 0)
			(unlocked yes)
			(layer "F.Fab")
			(hide yes)
			(effects
				(font
					(size 1.016 1.016)
					(thickness 0.1524)
				)
			)
		)
		(duplicate_pad_numbers_are_jumpers no)
		(fp_line
			(start -0.508 -0.9398)
			(end -0.508 0.9398)
			(stroke
				(width 0.1524)
				(type default)
			)
			(layer "F.SilkS")
		)
		(fp_line
			(start 0.508 -0.9398)
			(end -0.508 -0.9398)
			(stroke
				(width 0.1524)
				(type default)
			)
			(layer "F.SilkS")
		)
		(fp_rect
			(start -0.508 0.9398)
			(end 0.508 -0.9398)
			(stroke
				(width 0)
				(type default)
			)
			(fill no)
			(layer "F.CrtYd")
		)
		(fp_rect
			(start -0.508 0.9398)
			(end 0.508 -0.9398)
			(stroke
				(width 0)
				(type default)
			)
			(fill no)
			(layer "F.Fab")
		)
		(pad "1" smd custom
			(at 0 -0.4445)
			(size 0.1397 0.1397)
			(layers "F.Cu" "F.Mask" "F.Paste")
			(net "P12V_IN")
			(options
				(clearance outline)
				(anchor circle)
			)
			(primitives
				(gr_poly
					(pts
						(arc
							(start -0.1778 -0.2794)
							(mid -0.249642 -0.249642)
							(end -0.2794 -0.1778)
						)
						(arc
							(start -0.2794 0.1778)
							(mid -0.249642 0.249642)
							(end -0.1778 0.2794)
						)
						(arc
							(start 0.1778 0.2794)
							(mid 0.249642 0.249642)
							(end 0.2794 0.1778)
						)
						(arc
							(start 0.2794 -0.1778)
							(mid 0.249642 -0.249642)
							(end 0.1778 -0.2794)
						)
					)
					(width 0)
					(fill yes)
				)
			)
		)
		(pad "2" smd custom
			(at 0 0.4445)
			(size 0.1397 0.1397)
			(layers "F.Cu" "F.Mask" "F.Paste")
			(net "GATE_FAN0")
			(options
				(clearance outline)
				(anchor circle)
			)
			(primitives
				(gr_poly
					(pts
						(arc
							(start -0.1778 -0.2794)
							(mid -0.249642 -0.249642)
							(end -0.2794 -0.1778)
						)
						(arc
							(start -0.2794 0.1778)
							(mid -0.249642 0.249642)
							(end -0.1778 0.2794)
						)
						(arc
							(start 0.1778 0.2794)
							(mid 0.249642 0.249642)
							(end 0.2794 0.1778)
						)
						(arc
							(start 0.2794 -0.1778)
							(mid 0.249642 -0.249642)
							(end 0.1778 -0.2794)
						)
					)
					(width 0)
					(fill yes)
				)
			)
		)
	)
	(footprint ""
		(layer "F.Cu")
		(at 333.6798 -13.2842 180)
		(property "Reference" "R777"
			(at 0 0 180)
			(layer "F.SilkS")
			(hide yes)
			(effects
				(font
					(size 1.27 1.27)
				)
			)
		)
		(property "Value" "0R2J-2-GP"
			(at 0.064008 -3.993896 180)
			(unlocked yes)
			(layer "F.Fab")
			(hide yes)
			(effects
				(font
					(size 1.016 1.016)
					(thickness 0.1524)
				)
			)
		)
		(property "Device Type" "R402H16"
			(at 0.064008 -5.517896 180)
			(unlocked yes)
			(layer "F.Fab")
			(hide yes)
			(effects
				(font
					(size 1.016 1.016)
					(thickness 0.1524)
				)
			)
		)
		(duplicate_pad_numbers_are_jumpers no)
		(fp_line
			(start 0.508 -0.9398)
			(end -0.508 -0.9398)
			(stroke
				(width 0.1524)
				(type default)
			)
			(layer "F.SilkS")
		)
		(fp_line
			(start -0.508 -0.9398)
			(end -0.508 0.9398)
			(stroke
				(width 0.1524)
				(type default)
			)
			(layer "F.SilkS")
		)
		(fp_rect
			(start -0.508 0.9398)
			(end 0.508 -0.9398)
			(stroke
				(width 0)
				(type default)
			)
			(fill no)
			(layer "F.CrtYd")
		)
		(fp_rect
			(start -0.508 0.9398)
			(end 0.508 -0.9398)
			(stroke
				(width 0)
				(type default)
			)
			(fill no)
			(layer "F.Fab")
		)
		(pad "1" smd custom
			(at 0 -0.4445 180)
			(size 0.1397 0.1397)
			(layers "F.Cu" "F.Mask" "F.Paste")
			(net "SW_HDD_G30")
			(options
				(clearance outline)
				(anchor circle)
			)
			(primitives
				(gr_poly
					(pts
						(arc
							(start -0.1778 -0.2794)
							(mid -0.249642 -0.249642)
							(end -0.2794 -0.1778)
						)
						(arc
							(start -0.2794 0.1778)
							(mid -0.249642 0.249642)
							(end -0.1778 0.2794)
						)
						(arc
							(start 0.1778 0.2794)
							(mid 0.249642 0.249642)
							(end 0.2794 0.1778)
						)
						(arc
							(start 0.2794 -0.1778)
							(mid 0.249642 -0.249642)
							(end 0.1778 -0.2794)
						)
					)
					(width 0)
					(fill yes)
				)
			)
		)
		(pad "2" smd custom
			(at 0 0.4445 180)
			(size 0.1397 0.1397)
			(layers "F.Cu" "F.Mask" "F.Paste")
			(net "SW_HDD_R30")
			(options
				(clearance outline)
				(anchor circle)
			)
			(primitives
				(gr_poly
					(pts
						(arc
							(start -0.1778 -0.2794)
							(mid -0.249642 -0.249642)
							(end -0.2794 -0.1778)
						)
						(arc
							(start -0.2794 0.1778)
							(mid -0.249642 0.249642)
							(end -0.1778 0.2794)
						)
						(arc
							(start 0.1778 0.2794)
							(mid 0.249642 0.249642)
							(end 0.2794 0.1778)
						)
						(arc
							(start 0.2794 -0.1778)
							(mid 0.249642 -0.249642)
							(end 0.1778 -0.2794)
						)
					)
					(width 0)
					(fill yes)
				)
			)
		)
	)
	(footprint ""
		(layer "F.Cu")
		(at 342.399874 -379.899926 180)
		(property "Reference" "FAN3"
			(at 0 0 180)
			(layer "F.SilkS")
			(hide yes)
			(effects
				(font
					(size 1.27 1.27)
				)
			)
		)
		(property "Value" "MLX-CONN10D-7-GP"
			(at -15.641574 4.697984 180)
			(unlocked yes)
			(layer "F.Fab")
			(hide yes)
			(effects
				(font
					(size 1.016 1.016)
					(thickness 0.1524)
				)
			)
		)
		(property "Device Type" "15-24-6103"
			(at -15.641574 3.173984 180)
			(unlocked yes)
			(layer "F.Fab")
			(hide yes)
			(effects
				(font
					(size 1.016 1.016)
					(thickness 0.1524)
				)
			)
		)
		(duplicate_pad_numbers_are_jumpers no)
		(fp_line
			(start 14.0462 8.1534)
			(end -14.0462 8.1534)
			(stroke
				(width 0.1524)
				(type default)
			)
			(layer "F.SilkS")
		)
		(fp_line
			(start 14.0462 -6.4516)
			(end 14.0462 8.1534)
			(stroke
				(width 0.1524)
				(type default)
			)
			(layer "F.SilkS")
		)
		(fp_line
			(start 9.9314 -6.4516)
			(end 14.0462 -6.4516)
			(stroke
				(width 0.1524)
				(type default)
			)
			(layer "F.SilkS")
		)
		(fp_line
			(start 9.9314 -14.3256)
			(end 9.9314 -6.4516)
			(stroke
				(width 0.1524)
				(type default)
			)
			(layer "F.SilkS")
		)
		(fp_line
			(start -9.9314 -6.4516)
			(end -9.9314 -14.3256)
			(stroke
				(width 0.1524)
				(type default)
			)
			(layer "F.SilkS")
		)
		(fp_line
			(start -9.9314 -14.3256)
			(end 9.9314 -14.3256)
			(stroke
				(width 0.1524)
				(type default)
			)
			(layer "F.SilkS")
		)
		(fp_line
			(start -14.0462 8.1534)
			(end -14.0462 -6.4516)
			(stroke
				(width 0.1524)
				(type default)
			)
			(layer "F.SilkS")
		)
		(fp_line
			(start -14.0462 -6.4516)
			(end -9.9314 -6.4516)
			(stroke
				(width 0.1524)
				(type default)
			)
			(layer "F.SilkS")
		)
		(fp_circle
			(center 8.400034 -7.29996)
			(end 6.761734 -7.29996)
			(stroke
				(width 0.3048)
				(type default)
			)
			(fill no)
			(layer "F.SilkS")
		)
		(fp_circle
			(center 8.400034 -12.800076)
			(end 6.761734 -12.800076)
			(stroke
				(width 0.3048)
				(type default)
			)
			(fill no)
			(layer "F.SilkS")
		)
		(fp_circle
			(center 4.19989 -7.29996)
			(end 2.56159 -7.29996)
			(stroke
				(width 0.3048)
				(type default)
			)
			(fill no)
			(layer "F.SilkS")
		)
		(fp_circle
			(center 4.19989 -12.800076)
			(end 2.56159 -12.800076)
			(stroke
				(width 0.3048)
				(type default)
			)
			(fill no)
			(layer "F.SilkS")
		)
		(fp_circle
			(center 0 -7.29996)
			(end -1.6383 -7.29996)
			(stroke
				(width 0.3048)
				(type default)
			)
			(fill no)
			(layer "F.SilkS")
		)
		(fp_circle
			(center 0 -12.800076)
			(end -1.6383 -12.800076)
			(stroke
				(width 0.3048)
				(type default)
			)
			(fill no)
			(layer "F.SilkS")
		)
		(fp_circle
			(center -4.19989 -7.29996)
			(end -5.83819 -7.29996)
			(stroke
				(width 0.3048)
				(type default)
			)
			(fill no)
			(layer "F.SilkS")
		)
		(fp_circle
			(center -4.19989 -12.800076)
			(end -5.83819 -12.800076)
			(stroke
				(width 0.3048)
				(type default)
			)
			(fill no)
			(layer "F.SilkS")
		)
		(fp_circle
			(center -8.400034 -7.29996)
			(end -10.038334 -7.29996)
			(stroke
				(width 0.3048)
				(type default)
			)
			(fill no)
			(layer "F.SilkS")
		)
		(fp_circle
			(center -8.400034 -12.800076)
			(end -10.038334 -12.800076)
			(stroke
				(width 0.3048)
				(type default)
			)
			(fill no)
			(layer "F.SilkS")
		)
		(fp_poly
			(pts
				(xy -13.7922 7.8994) (xy -13.7922 -6.1976) (xy -9.2964 -6.1976) (xy -9.2964 -13.6906) (xy 9.2964 -13.6906)
				(xy 9.2964 -6.1976) (xy 13.7922 -6.1976) (xy 13.7922 7.8994)
			)
			(stroke
				(width 0)
				(type default)
			)
			(fill no)
			(layer "F.CrtYd")
		)
		(fp_poly
			(pts
				(xy -14.3002 8.4074) (xy -14.3002 -6.7056) (xy -10.1854 -6.7056) (xy -10.1854 -14.5796) (xy 10.1854 -14.5796)
				(xy 10.1854 -6.7056) (xy 14.3002 -6.7056) (xy 14.3002 -0.00635) (xy 13.7922 -0.00635) (xy 13.7922 -6.1976)
				(xy 9.2964 -6.1976) (xy 9.2964 -13.6906) (xy -9.2964 -13.6906) (xy -9.2964 -6.1976) (xy -13.7922 -6.1976)
				(xy -13.7922 7.8994) (xy 13.7922 7.8994) (xy 13.7922 0.00635) (xy 14.3002 0.00635) (xy 14.3002 8.4074)
			)
			(stroke
				(width 0)
				(type default)
			)
			(fill no)
			(layer "F.CrtYd")
		)
		(fp_poly
			(pts
				(xy -14.3002 8.4074) (xy -14.3002 -6.7056) (xy -10.1854 -6.7056) (xy -10.1854 -14.5796) (xy 10.1854 -14.5796)
				(xy 10.1854 -6.7056) (xy 14.3002 -6.7056) (xy 14.3002 8.4074)
			)
			(stroke
				(width 0)
				(type default)
			)
			(fill no)
			(layer "F.Fab")
		)
		(pad "" np_thru_hole circle
			(at -8.400034 0 180)
			(size 0.254 0.254)
			(drill 3.0226)
			(layers "*.Cu" "*.Mask")
			(clearance 1.7399)
			(thermal_gap 1.7399)
		)
		(pad "" np_thru_hole circle
			(at 8.400034 0 180)
			(size 0.254 0.254)
			(drill 3.0226)
			(layers "*.Cu" "*.Mask")
			(clearance 1.7399)
			(thermal_gap 1.7399)
		)
		(pad "1" thru_hole circle
			(at 8.400034 -7.29996 180)
			(size 2.5654 2.5654)
			(drill 1.8034)
			(layers "*.Cu" "*.Mask")
			(remove_unused_layers no)
			(net "FAN_2_TACH0")
			(clearance 0.127)
			(thermal_gap 0.127)
		)
		(pad "2" thru_hole circle
			(at 8.400034 -12.800076 180)
			(size 2.5654 2.5654)
			(drill 1.8034)
			(layers "*.Cu" "*.Mask")
			(remove_unused_layers no)
			(net "FAN_2_TACH1")
			(clearance 0.127)
			(thermal_gap 0.127)
		)
		(pad "3" thru_hole circle
			(at 4.19989 -7.29996 180)
			(size 2.5654 2.5654)
			(drill 1.8034)
			(layers "*.Cu" "*.Mask")
			(remove_unused_layers no)
			(net "FAN_2_PWM")
			(clearance 0.127)
			(thermal_gap 0.127)
		)
		(pad "4" thru_hole circle
			(at 4.19989 -12.800076 180)
			(size 2.5654 2.5654)
			(drill 1.8034)
			(layers "*.Cu" "*.Mask")
			(remove_unused_layers no)
			(net "FAN_2_PWM")
			(clearance 0.127)
			(thermal_gap 0.127)
		)
		(pad "5" thru_hole circle
			(at 0 -7.29996 180)
			(size 2.5654 2.5654)
			(drill 1.8034)
			(layers "*.Cu" "*.Mask")
			(remove_unused_layers no)
			(net "FAN_2_INS_N")
			(clearance 0.127)
			(thermal_gap 0.127)
		)
		(pad "6" thru_hole circle
			(at 0 -12.800076 180)
			(size 2.5654 2.5654)
			(drill 1.8034)
			(layers "*.Cu" "*.Mask")
			(remove_unused_layers no)
			(net "Net_1772")
			(clearance 0.127)
			(thermal_gap 0.127)
		)
		(pad "7" thru_hole circle
			(at -4.19989 -7.29996 180)
			(size 2.5654 2.5654)
			(drill 1.8034)
			(layers "*.Cu" "*.Mask")
			(remove_unused_layers no)
			(net "P12V_FAN2")
			(clearance 0.127)
			(thermal_gap 0.127)
		)
		(pad "8" thru_hole circle
			(at -4.19989 -12.800076 180)
			(size 2.5654 2.5654)
			(drill 1.8034)
			(layers "*.Cu" "*.Mask")
			(remove_unused_layers no)
			(net "P12V_FAN2")
			(clearance 0.127)
			(thermal_gap 0.127)
		)
		(pad "9" thru_hole circle
			(at -8.400034 -7.29996 180)
			(size 2.5654 2.5654)
			(drill 1.8034)
			(layers "*.Cu" "*.Mask")
			(remove_unused_layers no)
			(net "GND")
			(clearance 0.127)
			(thermal_gap 0.127)
		)
		(pad "10" thru_hole circle
			(at -8.400034 -12.800076 180)
			(size 2.5654 2.5654)
			(drill 1.8034)
			(layers "*.Cu" "*.Mask")
			(remove_unused_layers no)
			(net "GND")
			(clearance 0.127)
			(thermal_gap 0.127)
		)
		(zone
			(layers "F.Cu" "B.Cu" "In1.Cu" "In2.Cu" "In3.Cu" "In4.Cu" "In5.Cu" "In6.Cu")
			(hatch none 0.5)
			(connect_pads
				(clearance 0)
			)
			(min_thickness 0.25)
			(keepout
				(tracks not_allowed)
				(vias allowed)
				(pads allowed)
				(copperpour not_allowed)
				(footprints allowed)
			)
			(placement
				(enabled no)
				(sheetname "")
			)
			(fill
				(thermal_gap 0.5)
				(thermal_bridge_width 0.5)
				(island_removal_mode 0)
			)
			(polygon
				(pts
					(arc
						(start 335.81594 -379.899926)
						(mid 332.18374 -379.899926)
						(end 335.81594 -379.899926)
					)
				)
			)
		)
		(zone
			(layers "F.Cu" "B.Cu" "In1.Cu" "In2.Cu" "In3.Cu" "In4.Cu" "In5.Cu" "In6.Cu")
			(hatch none 0.5)
			(connect_pads
				(clearance 0)
			)
			(min_thickness 0.25)
			(keepout
				(tracks not_allowed)
				(vias allowed)
				(pads allowed)
				(copperpour not_allowed)
				(footprints allowed)
			)
			(placement
				(enabled no)
				(sheetname "")
			)
			(fill
				(thermal_gap 0.5)
				(thermal_bridge_width 0.5)
				(island_removal_mode 0)
			)
			(polygon
				(pts
					(arc
						(start 352.616008 -379.899926)
						(mid 348.983808 -379.899926)
						(end 352.616008 -379.899926)
					)
				)
			)
		)
	)
	(footprint ""
		(layer "F.Cu")
		(at 115.316 -16.637 -90)
		(property "Reference" "Q137"
			(at 0 0 270)
			(layer "F.SilkS")
			(hide yes)
			(effects
				(font
					(size 1.27 1.27)
				)
			)
		)
		(property "Value" "2N7002KDW-GP"
			(at -2.3622 -8.2042 270)
			(unlocked yes)
			(layer "F.Fab")
			(hide yes)
			(effects
				(font
					(size 1.016 1.016)
					(thickness 0.1524)
				)
			)
		)
		(property "Device Type" "SOT-363H44"
			(at -2.3622 -10.1092 270)
			(unlocked yes)
			(layer "F.Fab")
			(hide yes)
			(effects
				(font
					(size 1.016 1.016)
					(thickness 0.1524)
				)
			)
		)
		(duplicate_pad_numbers_are_jumpers no)
		(fp_line
			(start -1.4478 1.7018)
			(end 1.4478 1.7018)
			(stroke
				(width 0.1524)
				(type default)
			)
			(layer "F.SilkS")
		)
		(fp_line
			(start 1.4478 1.7018)
			(end 1.4478 -1.7018)
			(stroke
				(width 0.1524)
				(type default)
			)
			(layer "F.SilkS")
		)
		(fp_line
			(start -1.27 1.524)
			(end -1.27 0.6604)
			(stroke
				(width 0.4826)
				(type default)
			)
			(layer "F.SilkS")
		)
		(fp_line
			(start -1.4478 -1.7018)
			(end -1.4478 1.7018)
			(stroke
				(width 0.1524)
				(type default)
			)
			(layer "F.SilkS")
		)
		(fp_line
			(start 1.4478 -1.7018)
			(end -1.4478 -1.7018)
			(stroke
				(width 0.1524)
				(type default)
			)
			(layer "F.SilkS")
		)
		(fp_poly
			(pts
				(xy -1.524 -1.778) (xy 1.524 -1.778) (xy 1.524 1.778) (xy -1.524 1.778)
			)
			(stroke
				(width 0)
				(type default)
			)
			(fill no)
			(layer "F.CrtYd")
		)
		(fp_poly
			(pts
				(xy -1.524 -1.778) (xy 1.524 -1.778) (xy 1.524 1.778) (xy -1.524 1.778)
			)
			(stroke
				(width 0)
				(type default)
			)
			(fill no)
			(layer "F.Fab")
		)
		(pad "1" smd rect
			(at -0.65024 0.9398 270)
			(size 0.4064 1.016)
			(layers "F.Cu" "F.Mask" "F.Paste")
			(net "GND")
		)
		(pad "2" smd rect
			(at 0 0.9398 270)
			(size 0.4064 1.016)
			(layers "F.Cu" "F.Mask" "F.Paste")
			(net "SW_PWR_R_HDD27")
		)
		(pad "3" smd rect
			(at 0.65024 0.9398 270)
			(size 0.4064 1.016)
			(layers "F.Cu" "F.Mask" "F.Paste")
			(net "SW_HDD_P27")
		)
		(pad "4" smd rect
			(at 0.65024 -0.9398 270)
			(size 0.4064 1.016)
			(layers "F.Cu" "F.Mask" "F.Paste")
			(net "GND")
		)
		(pad "5" smd rect
			(at 0 -0.9398 270)
			(size 0.4064 1.016)
			(layers "F.Cu" "F.Mask" "F.Paste")
			(net "SW_HDD_G27")
		)
		(pad "6" smd rect
			(at -0.65024 -0.9398 270)
			(size 0.4064 1.016)
			(layers "F.Cu" "F.Mask" "F.Paste")
			(net "SW_HDD_R27")
		)
	)
	(footprint ""
		(layer "F.Cu")
		(at 466.934804 -372.2624 -90)
		(property "Reference" "R980"
			(at 0 0 270)
			(layer "F.SilkS")
			(hide yes)
			(effects
				(font
					(size 1.27 1.27)
				)
			)
		)
		(property "Value" "270R5J-2-GP"
			(at 0 -8.9535 270)
			(unlocked yes)
			(layer "F.Fab")
			(hide yes)
			(effects
				(font
					(size 1.27 1.016)
					(thickness 0.1524)
				)
			)
		)
		(property "Device Type" "R805H24"
			(at 0 -10.6299 270)
			(unlocked yes)
			(layer "F.Fab")
			(hide yes)
			(effects
				(font
					(size 1.27 1.016)
					(thickness 0.1524)
				)
			)
		)
		(duplicate_pad_numbers_are_jumpers no)
		(fp_line
			(start -0.889 1.7018)
			(end 0.889 1.7018)
			(stroke
				(width 0.1524)
				(type default)
			)
			(layer "F.SilkS")
		)
		(fp_line
			(start 0.889 1.7018)
			(end 0.889 -0.508)
			(stroke
				(width 0.1524)
				(type default)
			)
			(layer "F.SilkS")
		)
		(fp_line
			(start -0.889 0.0762)
			(end -0.889 1.7018)
			(stroke
				(width 0.1524)
				(type default)
			)
			(layer "F.SilkS")
		)
		(fp_line
			(start -0.889 -1.7018)
			(end -0.889 0.2794)
			(stroke
				(width 0.1524)
				(type default)
			)
			(layer "F.SilkS")
		)
		(fp_line
			(start 0.889 -1.7018)
			(end 0.889 -0.381)
			(stroke
				(width 0.1524)
				(type default)
			)
			(layer "F.SilkS")
		)
		(fp_line
			(start 0.889 -1.7018)
			(end -0.889 -1.7018)
			(stroke
				(width 0.1524)
				(type default)
			)
			(layer "F.SilkS")
		)
		(fp_poly
			(pts
				(xy 0.9652 -1.778) (xy 0.9652 1.778) (xy -0.9652 1.778) (xy -0.9652 -1.778)
			)
			(stroke
				(width 0)
				(type default)
			)
			(fill no)
			(layer "F.CrtYd")
		)
		(fp_rect
			(start -0.9652 1.778)
			(end 0.9652 -1.778)
			(stroke
				(width 0)
				(type default)
			)
			(fill no)
			(layer "F.Fab")
		)
		(pad "1" smd rect
			(at 0 -0.9652 270)
			(size 1.397 1.143)
			(layers "F.Cu" "F.Mask" "F.Paste")
			(net "FAN_LED_BLUE3")
		)
		(pad "2" smd rect
			(at 0 0.9652 270)
			(size 1.397 1.143)
			(layers "F.Cu" "F.Mask" "F.Paste")
			(net "FAN_BLUE3")
		)
	)
	(footprint ""
		(layer "F.Cu")
		(at 46.355 -131.572 90)
		(property "Reference" "R383"
			(at 0 0 90)
			(layer "F.SilkS")
			(hide yes)
			(effects
				(font
					(size 1.27 1.27)
				)
			)
		)
		(property "Value" "4K7R2J-2-GP"
			(at 0.064008 -3.993896 90)
			(unlocked yes)
			(layer "F.Fab")
			(hide yes)
			(effects
				(font
					(size 1.016 1.016)
					(thickness 0.1524)
				)
			)
		)
		(property "Device Type" "R402H16"
			(at 0.064008 -5.517896 90)
			(unlocked yes)
			(layer "F.Fab")
			(hide yes)
			(effects
				(font
					(size 1.016 1.016)
					(thickness 0.1524)
				)
			)
		)
		(duplicate_pad_numbers_are_jumpers no)
		(fp_line
			(start 0.508 -0.9398)
			(end -0.508 -0.9398)
			(stroke
				(width 0.1524)
				(type default)
			)
			(layer "F.SilkS")
		)
		(fp_line
			(start -0.508 -0.9398)
			(end -0.508 0.9398)
			(stroke
				(width 0.1524)
				(type default)
			)
			(layer "F.SilkS")
		)
		(fp_rect
			(start -0.508 0.9398)
			(end 0.508 -0.9398)
			(stroke
				(width 0)
				(type default)
			)
			(fill no)
			(layer "F.CrtYd")
		)
		(fp_rect
			(start -0.508 0.9398)
			(end 0.508 -0.9398)
			(stroke
				(width 0)
				(type default)
			)
			(fill no)
			(layer "F.Fab")
		)
		(pad "1" smd custom
			(at 0 -0.4445 90)
			(size 0.1397 0.1397)
			(layers "F.Cu" "F.Mask" "F.Paste")
			(net "P12V_B")
			(options
				(clearance outline)
				(anchor circle)
			)
			(primitives
				(gr_poly
					(pts
						(arc
							(start -0.1778 -0.2794)
							(mid -0.249642 -0.249642)
							(end -0.2794 -0.1778)
						)
						(arc
							(start -0.2794 0.1778)
							(mid -0.249642 0.249642)
							(end -0.1778 0.2794)
						)
						(arc
							(start 0.1778 0.2794)
							(mid 0.249642 0.249642)
							(end 0.2794 0.1778)
						)
						(arc
							(start 0.2794 -0.1778)
							(mid 0.249642 -0.249642)
							(end 0.1778 -0.2794)
						)
					)
					(width 0)
					(fill yes)
				)
			)
		)
		(pad "2" smd custom
			(at 0 0.4445 90)
			(size 0.1397 0.1397)
			(layers "F.Cu" "F.Mask" "F.Paste")
			(net "SW_HDD_R13")
			(options
				(clearance outline)
				(anchor circle)
			)
			(primitives
				(gr_poly
					(pts
						(arc
							(start -0.1778 -0.2794)
							(mid -0.249642 -0.249642)
							(end -0.2794 -0.1778)
						)
						(arc
							(start -0.2794 0.1778)
							(mid -0.249642 0.249642)
							(end -0.1778 0.2794)
						)
						(arc
							(start 0.1778 0.2794)
							(mid 0.249642 0.249642)
							(end 0.2794 0.1778)
						)
						(arc
							(start 0.2794 -0.1778)
							(mid 0.249642 -0.249642)
							(end 0.1778 -0.2794)
						)
					)
					(width 0)
					(fill yes)
				)
			)
		)
	)
	(footprint ""
		(layer "F.Cu")
		(at 23.876 -42.291)
		(property "Reference" "C347"
			(at 0 0 0)
			(layer "F.SilkS")
			(hide yes)
			(effects
				(font
					(size 1.27 1.27)
				)
			)
		)
		(property "Value" "SC4D7U25V5KX-1-GP"
			(at -0.0762 -6.1214 0)
			(unlocked yes)
			(layer "F.Fab")
			(hide yes)
			(effects
				(font
					(size 1.016 1.016)
					(thickness 0.1524)
				)
			)
		)
		(property "Device Type" "C805H58"
			(at -0.0762 -8.1534 0)
			(unlocked yes)
			(layer "F.Fab")
			(hide yes)
			(effects
				(font
					(size 1.016 1.016)
					(thickness 0.1524)
				)
			)
		)
		(duplicate_pad_numbers_are_jumpers no)
		(fp_line
			(start 0.635 0)
			(end -0.635 0)
			(stroke
				(width 0.508)
				(type default)
			)
			(layer "F.SilkS")
		)
		(fp_rect
			(start -0.9652 1.778)
			(end 0.9652 -1.778)
			(stroke
				(width 0)
				(type default)
			)
			(fill no)
			(layer "F.CrtYd")
		)
		(fp_poly
			(pts
				(xy -0.9652 -1.778) (xy 0.9652 -1.778) (xy 0.9652 1.778) (xy -0.9652 1.778)
			)
			(stroke
				(width 0)
				(type default)
			)
			(fill no)
			(layer "F.Fab")
		)
		(pad "1" smd rect
			(at 0 -0.9652)
			(size 1.397 1.143)
			(layers "F.Cu" "F.Mask" "F.Paste")
			(net "P12V_HDD24")
		)
		(pad "2" smd rect
			(at 0 0.9652)
			(size 1.397 1.143)
			(layers "F.Cu" "F.Mask" "F.Paste")
			(net "GND")
		)
	)
	(footprint ""
		(layer "F.Cu")
		(at 141.097 -246.634 90)
		(property "Reference" "R232"
			(at 0 0 90)
			(layer "F.SilkS")
			(hide yes)
			(effects
				(font
					(size 1.27 1.27)
				)
			)
		)
		(property "Value" "4K7R2J-2-GP"
			(at 0.064008 -3.993896 90)
			(unlocked yes)
			(layer "F.Fab")
			(hide yes)
			(effects
				(font
					(size 1.016 1.016)
					(thickness 0.1524)
				)
			)
		)
		(property "Device Type" "R402H16"
			(at 0.064008 -5.517896 90)
			(unlocked yes)
			(layer "F.Fab")
			(hide yes)
			(effects
				(font
					(size 1.016 1.016)
					(thickness 0.1524)
				)
			)
		)
		(duplicate_pad_numbers_are_jumpers no)
		(fp_line
			(start 0.508 -0.9398)
			(end -0.508 -0.9398)
			(stroke
				(width 0.1524)
				(type default)
			)
			(layer "F.SilkS")
		)
		(fp_line
			(start -0.508 -0.9398)
			(end -0.508 0.9398)
			(stroke
				(width 0.1524)
				(type default)
			)
			(layer "F.SilkS")
		)
		(fp_rect
			(start -0.508 0.9398)
			(end 0.508 -0.9398)
			(stroke
				(width 0)
				(type default)
			)
			(fill no)
			(layer "F.CrtYd")
		)
		(fp_rect
			(start -0.508 0.9398)
			(end 0.508 -0.9398)
			(stroke
				(width 0)
				(type default)
			)
			(fill no)
			(layer "F.Fab")
		)
		(pad "1" smd custom
			(at 0 -0.4445 90)
			(size 0.1397 0.1397)
			(layers "F.Cu" "F.Mask" "F.Paste")
			(net "P12V_B")
			(options
				(clearance outline)
				(anchor circle)
			)
			(primitives
				(gr_poly
					(pts
						(arc
							(start -0.1778 -0.2794)
							(mid -0.249642 -0.249642)
							(end -0.2794 -0.1778)
						)
						(arc
							(start -0.2794 0.1778)
							(mid -0.249642 0.249642)
							(end -0.1778 0.2794)
						)
						(arc
							(start 0.1778 0.2794)
							(mid 0.249642 0.249642)
							(end 0.2794 0.1778)
						)
						(arc
							(start 0.2794 -0.1778)
							(mid 0.249642 -0.249642)
							(end 0.1778 -0.2794)
						)
					)
					(width 0)
					(fill yes)
				)
			)
		)
		(pad "2" smd custom
			(at 0 0.4445 90)
			(size 0.1397 0.1397)
			(layers "F.Cu" "F.Mask" "F.Paste")
			(net "SW_HDD_R4")
			(options
				(clearance outline)
				(anchor circle)
			)
			(primitives
				(gr_poly
					(pts
						(arc
							(start -0.1778 -0.2794)
							(mid -0.249642 -0.249642)
							(end -0.2794 -0.1778)
						)
						(arc
							(start -0.2794 0.1778)
							(mid -0.249642 0.249642)
							(end -0.1778 0.2794)
						)
						(arc
							(start 0.1778 0.2794)
							(mid 0.249642 0.249642)
							(end 0.2794 0.1778)
						)
						(arc
							(start 0.2794 -0.1778)
							(mid 0.249642 -0.249642)
							(end 0.1778 -0.2794)
						)
					)
					(width 0)
					(fill yes)
				)
			)
		)
	)
	(footprint ""
		(layer "F.Cu")
		(at 209.775298 -223.585024 -90)
		(property "Reference" "R25"
			(at 0 0 270)
			(layer "F.SilkS")
			(hide yes)
			(effects
				(font
					(size 1.27 1.27)
				)
			)
		)
		(property "Value" "4K7R2F-GP"
			(at 0.064008 -3.993896 270)
			(unlocked yes)
			(layer "F.Fab")
			(hide yes)
			(effects
				(font
					(size 1.016 1.016)
					(thickness 0.1524)
				)
			)
		)
		(property "Device Type" "R402H16"
			(at 0.064008 -5.517896 270)
			(unlocked yes)
			(layer "F.Fab")
			(hide yes)
			(effects
				(font
					(size 1.016 1.016)
					(thickness 0.1524)
				)
			)
		)
		(duplicate_pad_numbers_are_jumpers no)
		(fp_line
			(start -0.508 -0.9398)
			(end -0.508 0.9398)
			(stroke
				(width 0.1524)
				(type default)
			)
			(layer "F.SilkS")
		)
		(fp_line
			(start 0.508 -0.9398)
			(end -0.508 -0.9398)
			(stroke
				(width 0.1524)
				(type default)
			)
			(layer "F.SilkS")
		)
		(fp_rect
			(start -0.508 0.9398)
			(end 0.508 -0.9398)
			(stroke
				(width 0)
				(type default)
			)
			(fill no)
			(layer "F.CrtYd")
		)
		(fp_rect
			(start -0.508 0.9398)
			(end 0.508 -0.9398)
			(stroke
				(width 0)
				(type default)
			)
			(fill no)
			(layer "F.Fab")
		)
		(pad "1" smd custom
			(at 0 -0.4445 270)
			(size 0.1397 0.1397)
			(layers "F.Cu" "F.Mask" "F.Paste")
			(net "IO_EXP1_HDD_FAULT_A2")
			(options
				(clearance outline)
				(anchor circle)
			)
			(primitives
				(gr_poly
					(pts
						(arc
							(start -0.1778 -0.2794)
							(mid -0.249642 -0.249642)
							(end -0.2794 -0.1778)
						)
						(arc
							(start -0.2794 0.1778)
							(mid -0.249642 0.249642)
							(end -0.1778 0.2794)
						)
						(arc
							(start 0.1778 0.2794)
							(mid 0.249642 0.249642)
							(end 0.2794 0.1778)
						)
						(arc
							(start 0.2794 -0.1778)
							(mid 0.249642 -0.249642)
							(end 0.1778 -0.2794)
						)
					)
					(width 0)
					(fill yes)
				)
			)
		)
		(pad "2" smd custom
			(at 0 0.4445 270)
			(size 0.1397 0.1397)
			(layers "F.Cu" "F.Mask" "F.Paste")
			(net "GND")
			(options
				(clearance outline)
				(anchor circle)
			)
			(primitives
				(gr_poly
					(pts
						(arc
							(start -0.1778 -0.2794)
							(mid -0.249642 -0.249642)
							(end -0.2794 -0.1778)
						)
						(arc
							(start -0.2794 0.1778)
							(mid -0.249642 0.249642)
							(end -0.1778 0.2794)
						)
						(arc
							(start 0.1778 0.2794)
							(mid 0.249642 0.249642)
							(end 0.2794 0.1778)
						)
						(arc
							(start 0.2794 -0.1778)
							(mid 0.249642 -0.249642)
							(end 0.1778 -0.2794)
						)
					)
					(width 0)
					(fill yes)
				)
			)
		)
	)
	(footprint ""
		(layer "F.Cu")
		(at 463.2706 -25.6032 90)
		(property "Reference" "R868"
			(at 0 0 90)
			(layer "F.SilkS")
			(hide yes)
			(effects
				(font
					(size 1.27 1.27)
				)
			)
		)
		(property "Value" "200KR2F-L-GP"
			(at 0.064008 -3.993896 90)
			(unlocked yes)
			(layer "F.Fab")
			(hide yes)
			(effects
				(font
					(size 1.016 1.016)
					(thickness 0.1524)
				)
			)
		)
		(property "Device Type" "R402H16"
			(at 0.064008 -5.517896 90)
			(unlocked yes)
			(layer "F.Fab")
			(hide yes)
			(effects
				(font
					(size 1.016 1.016)
					(thickness 0.1524)
				)
			)
		)
		(duplicate_pad_numbers_are_jumpers no)
		(fp_line
			(start 0.508 -0.9398)
			(end -0.508 -0.9398)
			(stroke
				(width 0.1524)
				(type default)
			)
			(layer "F.SilkS")
		)
		(fp_line
			(start -0.508 -0.9398)
			(end -0.508 0.9398)
			(stroke
				(width 0.1524)
				(type default)
			)
			(layer "F.SilkS")
		)
		(fp_rect
			(start -0.508 0.9398)
			(end 0.508 -0.9398)
			(stroke
				(width 0)
				(type default)
			)
			(fill no)
			(layer "F.CrtYd")
		)
		(fp_rect
			(start -0.508 0.9398)
			(end 0.508 -0.9398)
			(stroke
				(width 0)
				(type default)
			)
			(fill no)
			(layer "F.Fab")
		)
		(pad "1" smd custom
			(at 0 -0.4445 90)
			(size 0.1397 0.1397)
			(layers "F.Cu" "F.Mask" "F.Paste")
			(net "SW_HDD_R34")
			(options
				(clearance outline)
				(anchor circle)
			)
			(primitives
				(gr_poly
					(pts
						(arc
							(start -0.1778 -0.2794)
							(mid -0.249642 -0.249642)
							(end -0.2794 -0.1778)
						)
						(arc
							(start -0.2794 0.1778)
							(mid -0.249642 0.249642)
							(end -0.1778 0.2794)
						)
						(arc
							(start 0.1778 0.2794)
							(mid 0.249642 0.249642)
							(end 0.2794 0.1778)
						)
						(arc
							(start 0.2794 -0.1778)
							(mid 0.249642 -0.249642)
							(end 0.1778 -0.2794)
						)
					)
					(width 0)
					(fill yes)
				)
			)
		)
		(pad "2" smd custom
			(at 0 0.4445 90)
			(size 0.1397 0.1397)
			(layers "F.Cu" "F.Mask" "F.Paste")
			(net "SW_HDD_N34")
			(options
				(clearance outline)
				(anchor circle)
			)
			(primitives
				(gr_poly
					(pts
						(arc
							(start -0.1778 -0.2794)
							(mid -0.249642 -0.249642)
							(end -0.2794 -0.1778)
						)
						(arc
							(start -0.2794 0.1778)
							(mid -0.249642 0.249642)
							(end -0.1778 0.2794)
						)
						(arc
							(start 0.1778 0.2794)
							(mid 0.249642 0.249642)
							(end 0.2794 0.1778)
						)
						(arc
							(start 0.2794 -0.1778)
							(mid 0.249642 -0.249642)
							(end 0.1778 -0.2794)
						)
					)
					(width 0)
					(fill yes)
				)
			)
		)
	)
	(footprint ""
		(layer "F.Cu")
		(at 457.499974 -7.999984 180)
		(property "Reference" "U16"
			(at 0 0 180)
			(layer "F.SilkS")
			(hide yes)
			(effects
				(font
					(size 1.27 1.27)
				)
			)
		)
		(property "Value" "TMP75AIDGKR-GP"
			(at -0.1143 -9.1948 180)
			(unlocked yes)
			(layer "F.Fab")
			(hide yes)
			(effects
				(font
					(size 1.016 1.016)
					(thickness 0.1524)
				)
			)
		)
		(property "Device Type" "MSOP8-1H44"
			(at -0.1143 -10.795 180)
			(unlocked yes)
			(layer "F.Fab")
			(hide yes)
			(effects
				(font
					(size 1.016 1.016)
					(thickness 0.1524)
				)
			)
		)
		(duplicate_pad_numbers_are_jumpers no)
		(fp_line
			(start 1.0795 1.016)
			(end 1.0795 -1.016)
			(stroke
				(width 0.1524)
				(type default)
			)
			(layer "F.SilkS")
		)
		(fp_line
			(start 1.0795 -1.016)
			(end -1.9558 -1.016)
			(stroke
				(width 0.1524)
				(type default)
			)
			(layer "F.SilkS")
		)
		(fp_line
			(start -1.4478 -0.0381)
			(end -1.9558 0.4699)
			(stroke
				(width 0.1524)
				(type default)
			)
			(layer "F.SilkS")
		)
		(fp_line
			(start -1.778 1.0922)
			(end -1.778 3.048)
			(stroke
				(width 0.508)
				(type default)
			)
			(layer "F.SilkS")
		)
		(fp_line
			(start -1.9558 1.016)
			(end 1.0795 1.016)
			(stroke
				(width 0.1524)
				(type default)
			)
			(layer "F.SilkS")
		)
		(fp_line
			(start -1.9558 -0.5461)
			(end -1.4478 -0.0381)
			(stroke
				(width 0.1524)
				(type default)
			)
			(layer "F.SilkS")
		)
		(fp_line
			(start -1.9558 -1.016)
			(end -1.9558 1.016)
			(stroke
				(width 0.1524)
				(type default)
			)
			(layer "F.SilkS")
		)
		(fp_poly
			(pts
				(xy -1.1557 -1.016) (xy -1.1557 1.016) (xy 1.1557 1.016) (xy 1.1557 -1.016)
			)
			(stroke
				(width 0)
				(type default)
			)
			(fill yes)
			(layer "F.SilkS")
		)
		(fp_rect
			(start -1.4986 2.4511)
			(end 1.4986 -2.4511)
			(stroke
				(width 0)
				(type default)
			)
			(fill no)
			(layer "F.CrtYd")
		)
		(fp_poly
			(pts
				(xy -2.032 3.302) (xy -2.032 -3.302) (xy 2.032 -3.302) (xy 2.032 -2.1209) (xy 1.4986 -2.1209) (xy 1.4986 -2.4511)
				(xy -1.4986 -2.4511) (xy -1.4986 2.4511) (xy 1.4986 2.4511) (xy 1.4986 -2.1082) (xy 2.032 -2.1082)
				(xy 2.032 3.302)
			)
			(stroke
				(width 0)
				(type default)
			)
			(fill no)
			(layer "F.CrtYd")
		)
		(fp_rect
			(start -2.032 3.302)
			(end 2.032 -3.302)
			(stroke
				(width 0)
				(type default)
			)
			(fill no)
			(layer "F.Fab")
		)
		(pad "1" smd rect
			(at -0.97536 2.05486 180)
			(size 0.3556 1.524)
			(layers "F.Cu" "F.Mask" "F.Paste")
			(net "TEMP2_SDA")
		)
		(pad "2" smd rect
			(at -0.32512 2.05486 180)
			(size 0.3556 1.524)
			(layers "F.Cu" "F.Mask" "F.Paste")
			(net "TEMP2_SCL")
		)
		(pad "3" smd rect
			(at 0.32512 2.05486 180)
			(size 0.3556 1.524)
			(layers "F.Cu" "F.Mask" "F.Paste")
			(net "TEMP2_ALERT")
		)
		(pad "4" smd rect
			(at 0.97536 2.05486 180)
			(size 0.3556 1.524)
			(layers "F.Cu" "F.Mask" "F.Paste")
			(net "GND")
		)
		(pad "5" smd rect
			(at 0.97536 -2.05486 180)
			(size 0.3556 1.524)
			(layers "F.Cu" "F.Mask" "F.Paste")
			(net "TEMP2_A2")
		)
		(pad "6" smd rect
			(at 0.32512 -2.05486 180)
			(size 0.3556 1.524)
			(layers "F.Cu" "F.Mask" "F.Paste")
			(net "TEMP2_A1")
		)
		(pad "7" smd rect
			(at -0.32512 -2.05486 180)
			(size 0.3556 1.524)
			(layers "F.Cu" "F.Mask" "F.Paste")
			(net "TEMP2_A0")
		)
		(pad "8" smd rect
			(at -0.97536 -2.05486 180)
			(size 0.3556 1.524)
			(layers "F.Cu" "F.Mask" "F.Paste")
			(net "P3V3_STBY_B")
		)
	)
	(footprint ""
		(layer "F.Cu")
		(at 268.224 -206.883 90)
		(property "Reference" "R12"
			(at 0 0 90)
			(layer "F.SilkS")
			(hide yes)
			(effects
				(font
					(size 1.27 1.27)
				)
			)
		)
		(property "Value" "1KR2J-1-GP"
			(at 0.064008 -3.993896 90)
			(unlocked yes)
			(layer "F.Fab")
			(hide yes)
			(effects
				(font
					(size 1.016 1.016)
					(thickness 0.1524)
				)
			)
		)
		(property "Device Type" "R402H16"
			(at 0.064008 -5.517896 90)
			(unlocked yes)
			(layer "F.Fab")
			(hide yes)
			(effects
				(font
					(size 1.016 1.016)
					(thickness 0.1524)
				)
			)
		)
		(duplicate_pad_numbers_are_jumpers no)
		(fp_line
			(start 0.508 -0.9398)
			(end -0.508 -0.9398)
			(stroke
				(width 0.1524)
				(type default)
			)
			(layer "F.SilkS")
		)
		(fp_line
			(start -0.508 -0.9398)
			(end -0.508 0.9398)
			(stroke
				(width 0.1524)
				(type default)
			)
			(layer "F.SilkS")
		)
		(fp_rect
			(start -0.508 0.9398)
			(end 0.508 -0.9398)
			(stroke
				(width 0)
				(type default)
			)
			(fill no)
			(layer "F.CrtYd")
		)
		(fp_rect
			(start -0.508 0.9398)
			(end 0.508 -0.9398)
			(stroke
				(width 0)
				(type default)
			)
			(fill no)
			(layer "F.Fab")
		)
		(pad "1" smd custom
			(at 0 -0.4445 90)
			(size 0.1397 0.1397)
			(layers "F.Cu" "F.Mask" "F.Paste")
			(net "P3V3_STBY_B")
			(options
				(clearance outline)
				(anchor circle)
			)
			(primitives
				(gr_poly
					(pts
						(arc
							(start -0.1778 -0.2794)
							(mid -0.249642 -0.249642)
							(end -0.2794 -0.1778)
						)
						(arc
							(start -0.2794 0.1778)
							(mid -0.249642 0.249642)
							(end -0.1778 0.2794)
						)
						(arc
							(start 0.1778 0.2794)
							(mid 0.249642 0.249642)
							(end 0.2794 0.1778)
						)
						(arc
							(start 0.2794 -0.1778)
							(mid 0.249642 -0.249642)
							(end 0.1778 -0.2794)
						)
					)
					(width 0)
					(fill yes)
				)
			)
		)
		(pad "2" smd custom
			(at 0 0.4445 90)
			(size 0.1397 0.1397)
			(layers "F.Cu" "F.Mask" "F.Paste")
			(net "I2C_DRIVE_B_FLT_LED_SCL")
			(options
				(clearance outline)
				(anchor circle)
			)
			(primitives
				(gr_poly
					(pts
						(arc
							(start -0.1778 -0.2794)
							(mid -0.249642 -0.249642)
							(end -0.2794 -0.1778)
						)
						(arc
							(start -0.2794 0.1778)
							(mid -0.249642 0.249642)
							(end -0.1778 0.2794)
						)
						(arc
							(start 0.1778 0.2794)
							(mid 0.249642 0.249642)
							(end 0.2794 0.1778)
						)
						(arc
							(start 0.2794 -0.1778)
							(mid 0.249642 -0.249642)
							(end 0.1778 -0.2794)
						)
					)
					(width 0)
					(fill yes)
				)
			)
		)
	)
	(footprint ""
		(layer "F.Cu")
		(at 363.1184 -135.6106 -90)
		(property "Reference" "C285"
			(at 0 0 270)
			(layer "F.SilkS")
			(hide yes)
			(effects
				(font
					(size 1.27 1.27)
				)
			)
		)
		(property "Value" "SCD033U25V2KX-GP"
			(at 1.1811 -2.7051 270)
			(unlocked yes)
			(layer "F.Fab")
			(hide yes)
			(effects
				(font
					(size 1.016 1.016)
					(thickness 0.1524)
				)
			)
		)
		(property "Device Type" "C402H22"
			(at 1.1811 -4.2291 270)
			(unlocked yes)
			(layer "F.Fab")
			(hide yes)
			(effects
				(font
					(size 1.016 1.016)
					(thickness 0.1524)
				)
			)
		)
		(duplicate_pad_numbers_are_jumpers no)
		(fp_rect
			(start -0.4318 0.9525)
			(end 0.4318 -0.9525)
			(stroke
				(width 0)
				(type default)
			)
			(fill no)
			(layer "F.CrtYd")
		)
		(fp_rect
			(start -0.4318 0.9525)
			(end 0.4318 -0.9525)
			(stroke
				(width 0)
				(type default)
			)
			(fill no)
			(layer "F.Fab")
		)
		(pad "1" smd custom
			(at 0 -0.4445 270)
			(size 0.1524 0.1524)
			(layers "F.Cu" "F.Mask" "F.Paste")
			(net "SW_HDD_P19")
			(options
				(clearance outline)
				(anchor circle)
			)
			(primitives
				(gr_poly
					(pts
						(arc
							(start 0.3048 -0.2032)
							(mid 0.275042 -0.275042)
							(end 0.2032 -0.3048)
						)
						(arc
							(start -0.2032 -0.3048)
							(mid -0.275042 -0.275042)
							(end -0.3048 -0.2032)
						)
						(arc
							(start -0.3048 0.2032)
							(mid -0.275042 0.275042)
							(end -0.2032 0.3048)
						)
						(arc
							(start 0.2032 0.3048)
							(mid 0.275042 0.275042)
							(end 0.3048 0.2032)
						)
					)
					(width 0)
					(fill yes)
				)
			)
		)
		(pad "2" smd custom
			(at 0 0.4445 270)
			(size 0.1524 0.1524)
			(layers "F.Cu" "F.Mask" "F.Paste")
			(net "GND")
			(options
				(clearance outline)
				(anchor circle)
			)
			(primitives
				(gr_poly
					(pts
						(arc
							(start 0.3048 -0.2032)
							(mid 0.275042 -0.275042)
							(end 0.2032 -0.3048)
						)
						(arc
							(start -0.2032 -0.3048)
							(mid -0.275042 -0.275042)
							(end -0.3048 -0.2032)
						)
						(arc
							(start -0.3048 0.2032)
							(mid -0.275042 0.275042)
							(end -0.2032 0.3048)
						)
						(arc
							(start 0.2032 0.3048)
							(mid 0.275042 0.275042)
							(end 0.3048 0.2032)
						)
					)
					(width 0)
					(fill yes)
				)
			)
		)
	)
	(footprint ""
		(layer "F.Cu")
		(at 313.8424 -327.858882)
		(property "Reference" "R103"
			(at 0 0 0)
			(layer "F.SilkS")
			(hide yes)
			(effects
				(font
					(size 1.27 1.27)
				)
			)
		)
		(property "Value" "100KR2F-L1-GP"
			(at 0.064008 -3.993896 0)
			(unlocked yes)
			(layer "F.Fab")
			(hide yes)
			(effects
				(font
					(size 1.016 1.016)
					(thickness 0.1524)
				)
			)
		)
		(property "Device Type" "R402H16"
			(at 0.064008 -5.517896 0)
			(unlocked yes)
			(layer "F.Fab")
			(hide yes)
			(effects
				(font
					(size 1.016 1.016)
					(thickness 0.1524)
				)
			)
		)
		(duplicate_pad_numbers_are_jumpers no)
		(fp_line
			(start -0.508 -0.9398)
			(end -0.508 0.9398)
			(stroke
				(width 0.1524)
				(type default)
			)
			(layer "F.SilkS")
		)
		(fp_line
			(start 0.508 -0.9398)
			(end -0.508 -0.9398)
			(stroke
				(width 0.1524)
				(type default)
			)
			(layer "F.SilkS")
		)
		(fp_rect
			(start -0.508 0.9398)
			(end 0.508 -0.9398)
			(stroke
				(width 0)
				(type default)
			)
			(fill no)
			(layer "F.CrtYd")
		)
		(fp_rect
			(start -0.508 0.9398)
			(end 0.508 -0.9398)
			(stroke
				(width 0)
				(type default)
			)
			(fill no)
			(layer "F.Fab")
		)
		(pad "1" smd custom
			(at 0 -0.4445)
			(size 0.1397 0.1397)
			(layers "F.Cu" "F.Mask" "F.Paste")
			(net "PWM_BMC_B_ZONE_D")
			(options
				(clearance outline)
				(anchor circle)
			)
			(primitives
				(gr_poly
					(pts
						(arc
							(start -0.1778 -0.2794)
							(mid -0.249642 -0.249642)
							(end -0.2794 -0.1778)
						)
						(arc
							(start -0.2794 0.1778)
							(mid -0.249642 0.249642)
							(end -0.1778 0.2794)
						)
						(arc
							(start 0.1778 0.2794)
							(mid 0.249642 0.249642)
							(end 0.2794 0.1778)
						)
						(arc
							(start 0.2794 -0.1778)
							(mid 0.249642 -0.249642)
							(end 0.1778 -0.2794)
						)
					)
					(width 0)
					(fill yes)
				)
			)
		)
		(pad "2" smd custom
			(at 0 0.4445)
			(size 0.1397 0.1397)
			(layers "F.Cu" "F.Mask" "F.Paste")
			(net "GND")
			(options
				(clearance outline)
				(anchor circle)
			)
			(primitives
				(gr_poly
					(pts
						(arc
							(start -0.1778 -0.2794)
							(mid -0.249642 -0.249642)
							(end -0.2794 -0.1778)
						)
						(arc
							(start -0.2794 0.1778)
							(mid -0.249642 0.249642)
							(end -0.1778 0.2794)
						)
						(arc
							(start 0.1778 0.2794)
							(mid 0.249642 0.249642)
							(end 0.2794 0.1778)
						)
						(arc
							(start 0.2794 -0.1778)
							(mid 0.249642 -0.249642)
							(end 0.1778 -0.2794)
						)
					)
					(width 0)
					(fill yes)
				)
			)
		)
	)
	(footprint ""
		(layer "F.Cu")
		(at 350.942402 -244.889274 90)
		(property "Reference" "VIA15"
			(at 0 0 90)
			(layer "F.SilkS")
			(hide yes)
			(effects
				(font
					(size 1.27 1.27)
				)
			)
		)
		(property "Value" "100OHM-8L-2D36MM-L18-GP"
			(at 3.8989 0.5715 90)
			(unlocked yes)
			(layer "F.Fab")
			(hide yes)
			(effects
				(font
					(size 1.016 1.016)
					(thickness 0.1524)
				)
			)
		)
		(property "Device Type" "VIA-PCIE-4P-414097"
			(at 3.8989 -0.9525 90)
			(unlocked yes)
			(layer "F.Fab")
			(hide yes)
			(effects
				(font
					(size 1.016 1.016)
					(thickness 0.1524)
				)
			)
		)
		(duplicate_pad_numbers_are_jumpers no)
		(fp_rect
			(start -2.0701 0.4826)
			(end 2.0701 -0.4826)
			(stroke
				(width 0)
				(type default)
			)
			(fill no)
			(layer "F.CrtYd")
		)
		(fp_rect
			(start -2.0701 0.4826)
			(end 2.0701 -0.4826)
			(stroke
				(width 0)
				(type default)
			)
			(fill no)
			(layer "F.Fab")
		)
		(pad "1" thru_hole circle
			(at -1.5875 0 90)
			(size 0.508 0.508)
			(drill 0.254)
			(layers "*.Cu" "*.Mask")
			(remove_unused_layers no)
			(net "GND")
			(clearance 0.2286)
			(thermal_gap 0.2286)
		)
		(pad "2" thru_hole circle
			(at -0.5715 0 90)
			(size 0.508 0.508)
			(drill 0.254)
			(layers "*.Cu" "*.Mask")
			(remove_unused_layers no)
			(net "PHY_SCC_B_TO_DRV_B_7_DP")
			(clearance 0.2286)
			(thermal_gap 0.2286)
		)
		(pad "3" thru_hole circle
			(at 0.5715 0 90)
			(size 0.508 0.508)
			(drill 0.254)
			(layers "*.Cu" "*.Mask")
			(remove_unused_layers no)
			(net "PHY_SCC_B_TO_DRV_B_7_DN")
			(clearance 0.2286)
			(thermal_gap 0.2286)
		)
		(pad "4" thru_hole circle
			(at 1.5875 0 90)
			(size 0.508 0.508)
			(drill 0.254)
			(layers "*.Cu" "*.Mask")
			(remove_unused_layers no)
			(net "GND")
			(clearance 0.2286)
			(thermal_gap 0.2286)
		)
	)
	(footprint ""
		(layer "F.Cu")
		(at 141.097 -140.462 90)
		(property "Reference" "C247"
			(at 0 0 90)
			(layer "F.SilkS")
			(hide yes)
			(effects
				(font
					(size 1.27 1.27)
				)
			)
		)
		(property "Value" "SCD033U25V2KX-GP"
			(at 1.1811 -2.7051 90)
			(unlocked yes)
			(layer "F.Fab")
			(hide yes)
			(effects
				(font
					(size 1.016 1.016)
					(thickness 0.1524)
				)
			)
		)
		(property "Device Type" "C402H22"
			(at 1.1811 -4.2291 90)
			(unlocked yes)
			(layer "F.Fab")
			(hide yes)
			(effects
				(font
					(size 1.016 1.016)
					(thickness 0.1524)
				)
			)
		)
		(duplicate_pad_numbers_are_jumpers no)
		(fp_rect
			(start -0.4318 0.9525)
			(end 0.4318 -0.9525)
			(stroke
				(width 0)
				(type default)
			)
			(fill no)
			(layer "F.CrtYd")
		)
		(fp_rect
			(start -0.4318 0.9525)
			(end 0.4318 -0.9525)
			(stroke
				(width 0)
				(type default)
			)
			(fill no)
			(layer "F.Fab")
		)
		(pad "1" smd custom
			(at 0 -0.4445 90)
			(size 0.1524 0.1524)
			(layers "F.Cu" "F.Mask" "F.Paste")
			(net "P12V_B")
			(options
				(clearance outline)
				(anchor circle)
			)
			(primitives
				(gr_poly
					(pts
						(arc
							(start 0.3048 -0.2032)
							(mid 0.275042 -0.275042)
							(end 0.2032 -0.3048)
						)
						(arc
							(start -0.2032 -0.3048)
							(mid -0.275042 -0.275042)
							(end -0.3048 -0.2032)
						)
						(arc
							(start -0.3048 0.2032)
							(mid -0.275042 0.275042)
							(end -0.2032 0.3048)
						)
						(arc
							(start 0.2032 0.3048)
							(mid 0.275042 0.275042)
							(end 0.3048 0.2032)
						)
					)
					(width 0)
					(fill yes)
				)
			)
		)
		(pad "2" smd custom
			(at 0 0.4445 90)
			(size 0.1524 0.1524)
			(layers "F.Cu" "F.Mask" "F.Paste")
			(net "SW_HDD_N16")
			(options
				(clearance outline)
				(anchor circle)
			)
			(primitives
				(gr_poly
					(pts
						(arc
							(start 0.3048 -0.2032)
							(mid 0.275042 -0.275042)
							(end 0.2032 -0.3048)
						)
						(arc
							(start -0.2032 -0.3048)
							(mid -0.275042 -0.275042)
							(end -0.3048 -0.2032)
						)
						(arc
							(start -0.3048 0.2032)
							(mid -0.275042 0.275042)
							(end -0.2032 0.3048)
						)
						(arc
							(start 0.2032 0.3048)
							(mid 0.275042 0.275042)
							(end 0.3048 0.2032)
						)
					)
					(width 0)
					(fill yes)
				)
			)
		)
	)
	(footprint ""
		(layer "F.Cu")
		(at 431.419 -263.017)
		(property "Reference" "Q36"
			(at 0 0 0)
			(layer "F.SilkS")
			(hide yes)
			(effects
				(font
					(size 1.27 1.27)
				)
			)
		)
		(property "Value" "AO4407AL-GP"
			(at -3.707384 -1.5367 0)
			(unlocked yes)
			(layer "F.Fab")
			(hide yes)
			(effects
				(font
					(size 1.016 1.016)
					(thickness 0.1524)
				)
			)
		)
		(property "Device Type" "SOIC8H69"
			(at -3.707384 -3.0607 0)
			(unlocked yes)
			(layer "F.Fab")
			(hide yes)
			(effects
				(font
					(size 1.016 1.016)
					(thickness 0.1524)
				)
			)
		)
		(duplicate_pad_numbers_are_jumpers no)
		(fp_line
			(start -2.7432 -1.4224)
			(end -2.7432 1.4224)
			(stroke
				(width 0.1524)
				(type default)
			)
			(layer "F.SilkS")
		)
		(fp_line
			(start -2.7432 1.4224)
			(end -2.6416 1.4224)
			(stroke
				(width 0.1524)
				(type default)
			)
			(layer "F.SilkS")
		)
		(fp_line
			(start -2.7432 1.4224)
			(end 2.1336 1.4224)
			(stroke
				(width 0.1524)
				(type default)
			)
			(layer "F.SilkS")
		)
		(fp_line
			(start -2.7178 -0.508)
			(end -2.1844 -0.0508)
			(stroke
				(width 0.1524)
				(type default)
			)
			(layer "F.SilkS")
		)
		(fp_line
			(start -2.6289 3.4417)
			(end -2.6289 1.4732)
			(stroke
				(width 0.381)
				(type default)
			)
			(layer "F.SilkS")
		)
		(fp_line
			(start -2.1844 -0.0508)
			(end -2.7178 0.508)
			(stroke
				(width 0.1524)
				(type default)
			)
			(layer "F.SilkS")
		)
		(fp_line
			(start 2.1336 -1.4224)
			(end -2.7432 -1.4224)
			(stroke
				(width 0.1524)
				(type default)
			)
			(layer "F.SilkS")
		)
		(fp_line
			(start 2.1336 1.4224)
			(end 2.1336 -1.4224)
			(stroke
				(width 0.1524)
				(type default)
			)
			(layer "F.SilkS")
		)
		(fp_poly
			(pts
				(xy -2.2098 -1.4224) (xy -2.2098 1.4224) (xy 2.2098 1.4224) (xy 2.2098 -1.4224)
			)
			(stroke
				(width 0)
				(type default)
			)
			(fill yes)
			(layer "F.SilkS")
		)
		(fp_rect
			(start -2.450084 2.999994)
			(end 2.450084 -2.999994)
			(stroke
				(width 0)
				(type default)
			)
			(fill no)
			(layer "F.CrtYd")
		)
		(fp_poly
			(pts
				(xy -2.8194 3.6322) (xy -2.8194 -3.6322) (xy 2.8194 -3.6322) (xy 2.8194 1.18364) (xy 2.450084 1.18364)
				(xy 2.450084 -2.999994) (xy -2.450084 -2.999994) (xy -2.450084 2.999994) (xy 2.450084 2.999994)
				(xy 2.450084 1.18618) (xy 2.8194 1.18618) (xy 2.8194 3.6322)
			)
			(stroke
				(width 0)
				(type default)
			)
			(fill no)
			(layer "F.CrtYd")
		)
		(fp_rect
			(start -2.8194 3.6322)
			(end 2.8194 -3.6322)
			(stroke
				(width 0)
				(type default)
			)
			(fill no)
			(layer "F.Fab")
		)
		(pad "1" smd rect
			(at -1.905 2.54)
			(size 0.635 1.651)
			(layers "F.Cu" "F.Mask" "F.Paste")
			(net "P12V_B")
		)
		(pad "2" smd rect
			(at -0.635 2.54)
			(size 0.635 1.651)
			(layers "F.Cu" "F.Mask" "F.Paste")
			(net "P12V_B")
		)
		(pad "3" smd rect
			(at 0.635 2.54)
			(size 0.635 1.651)
			(layers "F.Cu" "F.Mask" "F.Paste")
			(net "P12V_B")
		)
		(pad "4" smd rect
			(at 1.905 2.54)
			(size 0.635 1.651)
			(layers "F.Cu" "F.Mask" "F.Paste")
			(net "SW_HDD_N9")
		)
		(pad "5" smd rect
			(at 1.905 -2.54)
			(size 0.635 1.651)
			(layers "F.Cu" "F.Mask" "F.Paste")
			(net "P12V_HDD9")
		)
		(pad "6" smd rect
			(at 0.635 -2.54)
			(size 0.635 1.651)
			(layers "F.Cu" "F.Mask" "F.Paste")
			(net "P12V_HDD9")
		)
		(pad "7" smd rect
			(at -0.635 -2.54)
			(size 0.635 1.651)
			(layers "F.Cu" "F.Mask" "F.Paste")
			(net "P12V_HDD9")
		)
		(pad "8" smd rect
			(at -1.905 -2.54)
			(size 0.635 1.651)
			(layers "F.Cu" "F.Mask" "F.Paste")
			(net "P12V_HDD9")
		)
	)
	(footprint ""
		(layer "F.Cu")
		(at 91.300046 -258.910074 -90)
		(property "Reference" "HDDSAS2"
			(at 0 0 270)
			(layer "F.SilkS")
			(hide yes)
			(effects
				(font
					(size 1.27 1.27)
				)
			)
		)
		(property "Value" "SKT-SAS15P-14P-45-GP"
			(at -20.7645 -8.9789 270)
			(unlocked yes)
			(layer "F.Fab")
			(hide yes)
			(effects
				(font
					(size 1.016 1.016)
					(thickness 0.1524)
				)
			)
		)
		(property "Device Type" "10120818-001C-TRLF"
			(at -20.7645 -10.5029 270)
			(unlocked yes)
			(layer "F.Fab")
			(hide yes)
			(effects
				(font
					(size 1.016 1.016)
					(thickness 0.1524)
				)
			)
		)
		(duplicate_pad_numbers_are_jumpers no)
		(fp_line
			(start 1.651 4.2926)
			(end 1.651 3.0099)
			(stroke
				(width 0.1524)
				(type default)
			)
			(layer "F.SilkS")
		)
		(fp_line
			(start 8.509 4.2926)
			(end 1.651 4.2926)
			(stroke
				(width 0.1524)
				(type default)
			)
			(layer "F.SilkS")
		)
		(fp_line
			(start -23.4188 3.0099)
			(end -23.4188 -3.2512)
			(stroke
				(width 0.1524)
				(type default)
			)
			(layer "F.SilkS")
		)
		(fp_line
			(start 1.651 3.0099)
			(end -23.4188 3.0099)
			(stroke
				(width 0.1524)
				(type default)
			)
			(layer "F.SilkS")
		)
		(fp_line
			(start 8.509 3.0099)
			(end 8.509 4.2926)
			(stroke
				(width 0.1524)
				(type default)
			)
			(layer "F.SilkS")
		)
		(fp_line
			(start 23.4188 3.0099)
			(end 8.509 3.0099)
			(stroke
				(width 0.1524)
				(type default)
			)
			(layer "F.SilkS")
		)
		(fp_line
			(start -23.4188 -3.2512)
			(end 23.4188 -3.2512)
			(stroke
				(width 0.1524)
				(type default)
			)
			(layer "F.SilkS")
		)
		(fp_line
			(start 23.4188 -3.2512)
			(end 23.4188 3.0099)
			(stroke
				(width 0.1524)
				(type default)
			)
			(layer "F.SilkS")
		)
		(fp_line
			(start 15.5067 -3.3401)
			(end 16.2687 -3.3401)
			(stroke
				(width 0.3302)
				(type default)
			)
			(layer "F.SilkS")
		)
		(fp_poly
			(pts
				(xy 15.868904 -3.230372) (xy 16.503904 -3.865372) (xy 15.233904 -3.865372)
			)
			(stroke
				(width 0)
				(type default)
			)
			(fill yes)
			(layer "F.SilkS")
		)
		(fp_poly
			(pts
				(xy -22.8727 -2.7559) (xy 22.8727 -2.7559) (xy 22.8727 2.7559) (xy 8.255 2.7559) (xy 8.255 3.5179)
				(xy 1.905 3.5179) (xy 1.905 2.7559) (xy -22.8727 2.7559)
			)
			(stroke
				(width 0)
				(type default)
			)
			(fill no)
			(layer "F.CrtYd")
		)
		(fp_poly
			(pts
				(xy 1.397 4.5466) (xy 1.397 3.2639) (xy -23.6728 3.2639) (xy -23.6728 -3.5052) (xy 23.6728 -3.5052)
				(xy 23.6728 -0.00635) (xy 22.8727 -0.00635) (xy 22.8727 -2.7559) (xy -22.8727 -2.7559) (xy -22.8727 2.7559)
				(xy 1.905 2.7559) (xy 1.905 3.5179) (xy 8.255 3.5179) (xy 8.255 2.7559) (xy 22.8727 2.7559) (xy 22.8727 0.00635)
				(xy 23.6728 0.00635) (xy 23.6728 3.2639) (xy 8.763 3.2639) (xy 8.763 4.5466)
			)
			(stroke
				(width 0)
				(type default)
			)
			(fill no)
			(layer "F.CrtYd")
		)
		(fp_poly
			(pts
				(xy 1.397 4.5466) (xy 1.397 3.2639) (xy -23.6728 3.2639) (xy -23.6728 -3.5052) (xy 23.6728 -3.5052)
				(xy 23.6728 3.2639) (xy 8.763 3.2639) (xy 8.763 4.5466)
			)
			(stroke
				(width 0)
				(type default)
			)
			(fill no)
			(layer "F.Fab")
		)
		(pad "" np_thru_hole circle
			(at -18.874994 0 270)
			(size 0.254 0.254)
			(drill 1.3462)
			(layers "*.Cu" "*.Mask")
			(clearance 0.9017)
			(thermal_gap 0.9017)
		)
		(pad "" np_thru_hole circle
			(at 18.874994 0 270)
			(size 0.254 0.254)
			(drill 0.9398)
			(layers "*.Cu" "*.Mask")
			(clearance 0.6985)
			(thermal_gap 0.6985)
		)
		(pad "G1" smd rect
			(at 21.874988 0 270)
			(size 2.5908 2.5908)
			(layers "F.Cu" "F.Mask" "F.Paste")
			(net "GND")
		)
		(pad "G2" smd rect
			(at -21.874988 0 270)
			(size 2.5908 2.5908)
			(layers "F.Cu" "F.Mask" "F.Paste")
			(net "GND")
		)
		(pad "P1" smd rect
			(at 1.905 -1.82499 270)
			(size 0.6096 2.3622)
			(layers "F.Cu" "F.Mask" "F.Paste")
			(net "Net_1654")
		)
		(pad "P2" smd rect
			(at 0.635 -1.82499 270)
			(size 0.6096 2.3622)
			(layers "F.Cu" "F.Mask" "F.Paste")
			(net "Net_1655")
		)
		(pad "P3" smd rect
			(at -0.635 -1.82499 270)
			(size 0.6096 2.3622)
			(layers "F.Cu" "F.Mask" "F.Paste")
			(net "Net_1656")
		)
		(pad "P4" smd rect
			(at -1.905 -1.82499 270)
			(size 0.6096 2.3622)
			(layers "F.Cu" "F.Mask" "F.Paste")
			(net "GND")
		)
		(pad "P5" smd rect
			(at -3.175 -1.82499 270)
			(size 0.6096 2.3622)
			(layers "F.Cu" "F.Mask" "F.Paste")
			(net "HDD_PRSNT_2")
		)
		(pad "P6" smd rect
			(at -4.445 -1.82499 270)
			(size 0.6096 2.3622)
			(layers "F.Cu" "F.Mask" "F.Paste")
			(net "GND")
		)
		(pad "P7" smd rect
			(at -5.715 -1.82499 270)
			(size 0.6096 2.3622)
			(layers "F.Cu" "F.Mask" "F.Paste")
			(net "5V_PRE_2")
		)
		(pad "P8" smd rect
			(at -6.985 -1.82499 270)
			(size 0.6096 2.3622)
			(layers "F.Cu" "F.Mask" "F.Paste")
			(net "P5V_HDD2")
		)
		(pad "P9" smd rect
			(at -8.255 -1.82499 270)
			(size 0.6096 2.3622)
			(layers "F.Cu" "F.Mask" "F.Paste")
			(net "P5V_HDD2")
		)
		(pad "P10" smd rect
			(at -9.525 -1.82499 270)
			(size 0.6096 2.3622)
			(layers "F.Cu" "F.Mask" "F.Paste")
			(net "GND")
		)
		(pad "P11" smd rect
			(at -10.795 -1.82499 270)
			(size 0.6096 2.3622)
			(layers "F.Cu" "F.Mask" "F.Paste")
			(net "ACT_HDD_2")
		)
		(pad "P12" smd rect
			(at -12.065 -1.82499 270)
			(size 0.6096 2.3622)
			(layers "F.Cu" "F.Mask" "F.Paste")
			(net "GND")
		)
		(pad "P13" smd rect
			(at -13.335 -1.82499 270)
			(size 0.6096 2.3622)
			(layers "F.Cu" "F.Mask" "F.Paste")
			(net "12V_PRE_2")
		)
		(pad "P14" smd rect
			(at -14.605 -1.82499 270)
			(size 0.6096 2.3622)
			(layers "F.Cu" "F.Mask" "F.Paste")
			(net "P12V_HDD2")
		)
		(pad "P15" smd rect
			(at -15.875 -1.82499 270)
			(size 0.6096 2.3622)
			(layers "F.Cu" "F.Mask" "F.Paste")
			(net "P12V_HDD2")
		)
		(pad "S1" smd rect
			(at 15.875 -1.82499 270)
			(size 0.6096 2.3622)
			(layers "F.Cu" "F.Mask" "F.Paste")
			(net "GND")
		)
		(pad "S2" smd rect
			(at 14.605 -1.82499 270)
			(size 0.6096 2.3622)
			(layers "F.Cu" "F.Mask" "F.Paste")
			(net "SAS_HDD_RX_P2")
		)
		(pad "S3" smd rect
			(at 13.335 -1.82499 270)
			(size 0.6096 2.3622)
			(layers "F.Cu" "F.Mask" "F.Paste")
			(net "SAS_HDD_RX_N2")
		)
		(pad "S4" smd rect
			(at 12.065 -1.82499 270)
			(size 0.6096 2.3622)
			(layers "F.Cu" "F.Mask" "F.Paste")
			(net "GND")
		)
		(pad "S5" smd rect
			(at 10.795 -1.82499 270)
			(size 0.6096 2.3622)
			(layers "F.Cu" "F.Mask" "F.Paste")
			(net "PHY_DRV_B_TO_SCC_B_2_DN")
		)
		(pad "S6" smd rect
			(at 9.525 -1.82499 270)
			(size 0.6096 2.3622)
			(layers "F.Cu" "F.Mask" "F.Paste")
			(net "PHY_DRV_B_TO_SCC_B_2_DP")
		)
		(pad "S7" smd rect
			(at 8.255 -1.82499 270)
			(size 0.6096 2.3622)
			(layers "F.Cu" "F.Mask" "F.Paste")
			(net "GND")
		)
		(pad "S8" smd rect
			(at 7.480046 2.845054 270)
			(size 0.508 2.3622)
			(layers "F.Cu" "F.Mask" "F.Paste")
			(net "GND")
		)
		(pad "S9" smd rect
			(at 6.679946 2.845054 270)
			(size 0.508 2.3622)
			(layers "F.Cu" "F.Mask" "F.Paste")
			(net "Net_453")
		)
		(pad "S10" smd rect
			(at 5.8801 2.845054 270)
			(size 0.508 2.3622)
			(layers "F.Cu" "F.Mask" "F.Paste")
			(net "Net_345")
		)
		(pad "S11" smd rect
			(at 5.08 2.845054 270)
			(size 0.508 2.3622)
			(layers "F.Cu" "F.Mask" "F.Paste")
			(net "GND")
		)
		(pad "S12" smd rect
			(at 4.2799 2.845054 270)
			(size 0.508 2.3622)
			(layers "F.Cu" "F.Mask" "F.Paste")
			(net "Net_381")
		)
		(pad "S13" smd rect
			(at 3.480054 2.845054 270)
			(size 0.508 2.3622)
			(layers "F.Cu" "F.Mask" "F.Paste")
			(net "Net_417")
		)
		(pad "S14" smd rect
			(at 2.679954 2.845054 270)
			(size 0.508 2.3622)
			(layers "F.Cu" "F.Mask" "F.Paste")
			(net "GND")
		)
		(zone
			(layer "F.Cu")
			(hatch none 0.5)
			(connect_pads
				(clearance 0)
			)
			(min_thickness 0.25)
			(keepout
				(tracks not_allowed)
				(vias allowed)
				(pads allowed)
				(copperpour not_allowed)
				(footprints allowed)
			)
			(placement
				(enabled no)
				(sheetname "")
			)
			(fill
				(thermal_gap 0.5)
				(thermal_bridge_width 0.5)
				(island_removal_mode 0)
			)
			(polygon
				(pts
					(xy 94.957646 -275.648674) (xy 87.883746 -275.648674) (xy 87.883746 -282.582874) (xy 88.988646 -282.582874)
					(xy 88.988646 -278.468074) (xy 93.611446 -278.468074) (xy 93.611446 -282.582874) (xy 94.957646 -282.582874)
				)
			)
		)
		(zone
			(layer "F.Cu")
			(hatch none 0.5)
			(connect_pads
				(clearance 0)
			)
			(min_thickness 0.25)
			(keepout
				(tracks allowed)
				(vias not_allowed)
				(pads allowed)
				(copperpour not_allowed)
				(footprints allowed)
			)
			(placement
				(enabled no)
				(sheetname "")
			)
			(fill
				(thermal_gap 0.5)
				(thermal_bridge_width 0.5)
				(island_removal_mode 0)
			)
			(polygon
				(pts
					(xy 94.957646 -275.648674) (xy 87.883746 -275.648674) (xy 87.883746 -282.582874) (xy 88.988646 -282.582874)
					(xy 88.988646 -278.468074) (xy 93.611446 -278.468074) (xy 93.611446 -282.582874) (xy 94.957646 -282.582874)
				)
			)
		)
		(zone
			(layer "F.Cu")
			(hatch none 0.5)
			(connect_pads
				(clearance 0)
			)
			(min_thickness 0.25)
			(keepout
				(tracks not_allowed)
				(vias allowed)
				(pads allowed)
				(copperpour not_allowed)
				(footprints allowed)
			)
			(placement
				(enabled no)
				(sheetname "")
			)
			(fill
				(thermal_gap 0.5)
				(thermal_bridge_width 0.5)
				(island_removal_mode 0)
			)
			(polygon
				(pts
					(xy 94.957646 -242.171474) (xy 87.883746 -242.171474) (xy 87.883746 -235.237274) (xy 88.988646 -235.237274)
					(xy 88.988646 -239.352074) (xy 93.611446 -239.352074) (xy 93.611446 -235.237274) (xy 94.957646 -235.237274)
				)
			)
		)
		(zone
			(layer "F.Cu")
			(hatch none 0.5)
			(connect_pads
				(clearance 0)
			)
			(min_thickness 0.25)
			(keepout
				(tracks allowed)
				(vias not_allowed)
				(pads allowed)
				(copperpour not_allowed)
				(footprints allowed)
			)
			(placement
				(enabled no)
				(sheetname "")
			)
			(fill
				(thermal_gap 0.5)
				(thermal_bridge_width 0.5)
				(island_removal_mode 0)
			)
			(polygon
				(pts
					(xy 94.957646 -242.171474) (xy 87.883746 -242.171474) (xy 87.883746 -235.237274) (xy 88.988646 -235.237274)
					(xy 88.988646 -239.352074) (xy 93.611446 -239.352074) (xy 93.611446 -235.237274) (xy 94.957646 -235.237274)
				)
			)
		)
		(zone
			(layers "F.Cu" "B.Cu" "In1.Cu" "In2.Cu" "In3.Cu" "In4.Cu" "In5.Cu" "In6.Cu")
			(hatch none 0.5)
			(connect_pads
				(clearance 0)
			)
			(min_thickness 0.25)
			(keepout
				(tracks not_allowed)
				(vias allowed)
				(pads allowed)
				(copperpour not_allowed)
				(footprints allowed)
			)
			(placement
				(enabled no)
				(sheetname "")
			)
			(fill
				(thermal_gap 0.5)
				(thermal_bridge_width 0.5)
				(island_removal_mode 0)
			)
			(polygon
				(pts
					(arc
						(start 92.074746 -240.03508)
						(mid 90.525346 -240.03508)
						(end 92.074746 -240.03508)
					)
				)
			)
		)
		(zone
			(layers "F.Cu" "B.Cu" "In1.Cu" "In2.Cu" "In3.Cu" "In4.Cu" "In5.Cu" "In6.Cu")
			(hatch none 0.5)
			(connect_pads
				(clearance 0)
			)
			(min_thickness 0.25)
			(keepout
				(tracks not_allowed)
				(vias allowed)
				(pads allowed)
				(copperpour not_allowed)
				(footprints allowed)
			)
			(placement
				(enabled no)
				(sheetname "")
			)
			(fill
				(thermal_gap 0.5)
				(thermal_bridge_width 0.5)
				(island_removal_mode 0)
			)
			(polygon
				(pts
					(arc
						(start 92.277946 -277.785068)
						(mid 90.322146 -277.785068)
						(end 92.277946 -277.785068)
					)
				)
			)
		)
	)
	(footprint ""
		(layer "F.Cu")
		(at 335.153 -358.3559)
		(property "Reference" "R145"
			(at 0 0 0)
			(layer "F.SilkS")
			(hide yes)
			(effects
				(font
					(size 1.27 1.27)
				)
			)
		)
		(property "Value" "200KR2F-L-GP"
			(at 0.064008 -3.993896 0)
			(unlocked yes)
			(layer "F.Fab")
			(hide yes)
			(effects
				(font
					(size 1.016 1.016)
					(thickness 0.1524)
				)
			)
		)
		(property "Device Type" "R402H16"
			(at 0.064008 -5.517896 0)
			(unlocked yes)
			(layer "F.Fab")
			(hide yes)
			(effects
				(font
					(size 1.016 1.016)
					(thickness 0.1524)
				)
			)
		)
		(duplicate_pad_numbers_are_jumpers no)
		(fp_line
			(start -0.508 -0.9398)
			(end -0.508 0.9398)
			(stroke
				(width 0.1524)
				(type default)
			)
			(layer "F.SilkS")
		)
		(fp_line
			(start 0.508 -0.9398)
			(end -0.508 -0.9398)
			(stroke
				(width 0.1524)
				(type default)
			)
			(layer "F.SilkS")
		)
		(fp_rect
			(start -0.508 0.9398)
			(end 0.508 -0.9398)
			(stroke
				(width 0)
				(type default)
			)
			(fill no)
			(layer "F.CrtYd")
		)
		(fp_rect
			(start -0.508 0.9398)
			(end 0.508 -0.9398)
			(stroke
				(width 0)
				(type default)
			)
			(fill no)
			(layer "F.Fab")
		)
		(pad "1" smd custom
			(at 0 -0.4445)
			(size 0.1397 0.1397)
			(layers "F.Cu" "F.Mask" "F.Paste")
			(net "GATE_FAN2")
			(options
				(clearance outline)
				(anchor circle)
			)
			(primitives
				(gr_poly
					(pts
						(arc
							(start -0.1778 -0.2794)
							(mid -0.249642 -0.249642)
							(end -0.2794 -0.1778)
						)
						(arc
							(start -0.2794 0.1778)
							(mid -0.249642 0.249642)
							(end -0.1778 0.2794)
						)
						(arc
							(start 0.1778 0.2794)
							(mid 0.249642 0.249642)
							(end 0.2794 0.1778)
						)
						(arc
							(start 0.2794 -0.1778)
							(mid 0.249642 -0.249642)
							(end 0.1778 -0.2794)
						)
					)
					(width 0)
					(fill yes)
				)
			)
		)
		(pad "2" smd custom
			(at 0 0.4445)
			(size 0.1397 0.1397)
			(layers "F.Cu" "F.Mask" "F.Paste")
			(net "GATE_FAN2_R")
			(options
				(clearance outline)
				(anchor circle)
			)
			(primitives
				(gr_poly
					(pts
						(arc
							(start -0.1778 -0.2794)
							(mid -0.249642 -0.249642)
							(end -0.2794 -0.1778)
						)
						(arc
							(start -0.2794 0.1778)
							(mid -0.249642 0.249642)
							(end -0.1778 0.2794)
						)
						(arc
							(start 0.1778 0.2794)
							(mid 0.249642 0.249642)
							(end 0.2794 0.1778)
						)
						(arc
							(start 0.2794 -0.1778)
							(mid 0.249642 -0.249642)
							(end 0.1778 -0.2794)
						)
					)
					(width 0)
					(fill yes)
				)
			)
		)
	)
	(footprint ""
		(layer "F.Cu")
		(at 473.583 -20.828 90)
		(property "Reference" "C493"
			(at 0 0 90)
			(layer "F.SilkS")
			(hide yes)
			(effects
				(font
					(size 1.27 1.27)
				)
			)
		)
		(property "Value" "SCD033U25V2KX-GP"
			(at 1.1811 -2.7051 90)
			(unlocked yes)
			(layer "F.Fab")
			(hide yes)
			(effects
				(font
					(size 1.016 1.016)
					(thickness 0.1524)
				)
			)
		)
		(property "Device Type" "C402H22"
			(at 1.1811 -4.2291 90)
			(unlocked yes)
			(layer "F.Fab")
			(hide yes)
			(effects
				(font
					(size 1.016 1.016)
					(thickness 0.1524)
				)
			)
		)
		(duplicate_pad_numbers_are_jumpers no)
		(fp_rect
			(start -0.4318 0.9525)
			(end 0.4318 -0.9525)
			(stroke
				(width 0)
				(type default)
			)
			(fill no)
			(layer "F.CrtYd")
		)
		(fp_rect
			(start -0.4318 0.9525)
			(end 0.4318 -0.9525)
			(stroke
				(width 0)
				(type default)
			)
			(fill no)
			(layer "F.Fab")
		)
		(pad "1" smd custom
			(at 0 -0.4445 90)
			(size 0.1524 0.1524)
			(layers "F.Cu" "F.Mask" "F.Paste")
			(net "SW_HDD_P35")
			(options
				(clearance outline)
				(anchor circle)
			)
			(primitives
				(gr_poly
					(pts
						(arc
							(start 0.3048 -0.2032)
							(mid 0.275042 -0.275042)
							(end 0.2032 -0.3048)
						)
						(arc
							(start -0.2032 -0.3048)
							(mid -0.275042 -0.275042)
							(end -0.3048 -0.2032)
						)
						(arc
							(start -0.3048 0.2032)
							(mid -0.275042 0.275042)
							(end -0.2032 0.3048)
						)
						(arc
							(start 0.2032 0.3048)
							(mid 0.275042 0.275042)
							(end 0.3048 0.2032)
						)
					)
					(width 0)
					(fill yes)
				)
			)
		)
		(pad "2" smd custom
			(at 0 0.4445 90)
			(size 0.1524 0.1524)
			(layers "F.Cu" "F.Mask" "F.Paste")
			(net "GND")
			(options
				(clearance outline)
				(anchor circle)
			)
			(primitives
				(gr_poly
					(pts
						(arc
							(start 0.3048 -0.2032)
							(mid 0.275042 -0.275042)
							(end 0.2032 -0.3048)
						)
						(arc
							(start -0.2032 -0.3048)
							(mid -0.275042 -0.275042)
							(end -0.3048 -0.2032)
						)
						(arc
							(start -0.3048 0.2032)
							(mid -0.275042 0.275042)
							(end -0.2032 0.3048)
						)
						(arc
							(start 0.2032 0.3048)
							(mid 0.275042 0.275042)
							(end 0.3048 0.2032)
						)
					)
					(width 0)
					(fill yes)
				)
			)
		)
	)
	(footprint ""
		(layer "F.Cu")
		(at 148.717 -16.3322 -90)
		(property "Reference" "R725"
			(at 0 0 270)
			(layer "F.SilkS")
			(hide yes)
			(effects
				(font
					(size 1.27 1.27)
				)
			)
		)
		(property "Value" "0R2J-2-GP"
			(at 0.064008 -3.993896 270)
			(unlocked yes)
			(layer "F.Fab")
			(hide yes)
			(effects
				(font
					(size 1.016 1.016)
					(thickness 0.1524)
				)
			)
		)
		(property "Device Type" "R402H16"
			(at 0.064008 -5.517896 270)
			(unlocked yes)
			(layer "F.Fab")
			(hide yes)
			(effects
				(font
					(size 1.016 1.016)
					(thickness 0.1524)
				)
			)
		)
		(duplicate_pad_numbers_are_jumpers no)
		(fp_line
			(start -0.508 -0.9398)
			(end -0.508 0.9398)
			(stroke
				(width 0.1524)
				(type default)
			)
			(layer "F.SilkS")
		)
		(fp_line
			(start 0.508 -0.9398)
			(end -0.508 -0.9398)
			(stroke
				(width 0.1524)
				(type default)
			)
			(layer "F.SilkS")
		)
		(fp_rect
			(start -0.508 0.9398)
			(end 0.508 -0.9398)
			(stroke
				(width 0)
				(type default)
			)
			(fill no)
			(layer "F.CrtYd")
		)
		(fp_rect
			(start -0.508 0.9398)
			(end 0.508 -0.9398)
			(stroke
				(width 0)
				(type default)
			)
			(fill no)
			(layer "F.Fab")
		)
		(pad "1" smd custom
			(at 0 -0.4445 270)
			(size 0.1397 0.1397)
			(layers "F.Cu" "F.Mask" "F.Paste")
			(net "DRIVE_B_28_PWR")
			(options
				(clearance outline)
				(anchor circle)
			)
			(primitives
				(gr_poly
					(pts
						(arc
							(start -0.1778 -0.2794)
							(mid -0.249642 -0.249642)
							(end -0.2794 -0.1778)
						)
						(arc
							(start -0.2794 0.1778)
							(mid -0.249642 0.249642)
							(end -0.1778 0.2794)
						)
						(arc
							(start 0.1778 0.2794)
							(mid 0.249642 0.249642)
							(end 0.2794 0.1778)
						)
						(arc
							(start 0.2794 -0.1778)
							(mid 0.249642 -0.249642)
							(end 0.1778 -0.2794)
						)
					)
					(width 0)
					(fill yes)
				)
			)
		)
		(pad "2" smd custom
			(at 0 0.4445 270)
			(size 0.1397 0.1397)
			(layers "F.Cu" "F.Mask" "F.Paste")
			(net "SW_PWR_R_HDD28")
			(options
				(clearance outline)
				(anchor circle)
			)
			(primitives
				(gr_poly
					(pts
						(arc
							(start -0.1778 -0.2794)
							(mid -0.249642 -0.249642)
							(end -0.2794 -0.1778)
						)
						(arc
							(start -0.2794 0.1778)
							(mid -0.249642 0.249642)
							(end -0.1778 0.2794)
						)
						(arc
							(start 0.1778 0.2794)
							(mid 0.249642 0.249642)
							(end 0.2794 0.1778)
						)
						(arc
							(start 0.2794 -0.1778)
							(mid 0.249642 -0.249642)
							(end 0.1778 -0.2794)
						)
					)
					(width 0)
					(fill yes)
				)
			)
		)
	)
	(footprint ""
		(layer "F.Cu")
		(at 352.298 -261.6454 180)
		(property "Reference" "R271"
			(at 0 0 180)
			(layer "F.SilkS")
			(hide yes)
			(effects
				(font
					(size 1.27 1.27)
				)
			)
		)
		(property "Value" "10KR2F-2-GP"
			(at 0.064008 -3.993896 180)
			(unlocked yes)
			(layer "F.Fab")
			(hide yes)
			(effects
				(font
					(size 1.016 1.016)
					(thickness 0.1524)
				)
			)
		)
		(property "Device Type" "R402H16"
			(at 0.064008 -5.517896 180)
			(unlocked yes)
			(layer "F.Fab")
			(hide yes)
			(effects
				(font
					(size 1.016 1.016)
					(thickness 0.1524)
				)
			)
		)
		(duplicate_pad_numbers_are_jumpers no)
		(fp_line
			(start 0.508 -0.9398)
			(end -0.508 -0.9398)
			(stroke
				(width 0.1524)
				(type default)
			)
			(layer "F.SilkS")
		)
		(fp_line
			(start -0.508 -0.9398)
			(end -0.508 0.9398)
			(stroke
				(width 0.1524)
				(type default)
			)
			(layer "F.SilkS")
		)
		(fp_rect
			(start -0.508 0.9398)
			(end 0.508 -0.9398)
			(stroke
				(width 0)
				(type default)
			)
			(fill no)
			(layer "F.CrtYd")
		)
		(fp_rect
			(start -0.508 0.9398)
			(end 0.508 -0.9398)
			(stroke
				(width 0)
				(type default)
			)
			(fill no)
			(layer "F.Fab")
		)
		(pad "1" smd custom
			(at 0 -0.4445 180)
			(size 0.1397 0.1397)
			(layers "F.Cu" "F.Mask" "F.Paste")
			(net "P3V3_STBY_B")
			(options
				(clearance outline)
				(anchor circle)
			)
			(primitives
				(gr_poly
					(pts
						(arc
							(start -0.1778 -0.2794)
							(mid -0.249642 -0.249642)
							(end -0.2794 -0.1778)
						)
						(arc
							(start -0.2794 0.1778)
							(mid -0.249642 0.249642)
							(end -0.1778 0.2794)
						)
						(arc
							(start 0.1778 0.2794)
							(mid 0.249642 0.249642)
							(end 0.2794 0.1778)
						)
						(arc
							(start 0.2794 -0.1778)
							(mid 0.249642 -0.249642)
							(end 0.1778 -0.2794)
						)
					)
					(width 0)
					(fill yes)
				)
			)
		)
		(pad "2" smd custom
			(at 0 0.4445 180)
			(size 0.1397 0.1397)
			(layers "F.Cu" "F.Mask" "F.Paste")
			(net "HDD_PRSNT_7")
			(options
				(clearance outline)
				(anchor circle)
			)
			(primitives
				(gr_poly
					(pts
						(arc
							(start -0.1778 -0.2794)
							(mid -0.249642 -0.249642)
							(end -0.2794 -0.1778)
						)
						(arc
							(start -0.2794 0.1778)
							(mid -0.249642 0.249642)
							(end -0.1778 0.2794)
						)
						(arc
							(start 0.1778 0.2794)
							(mid 0.249642 0.249642)
							(end 0.2794 0.1778)
						)
						(arc
							(start 0.2794 -0.1778)
							(mid 0.249642 -0.249642)
							(end 0.1778 -0.2794)
						)
					)
					(width 0)
					(fill yes)
				)
			)
		)
	)
	(footprint ""
		(layer "F.Cu")
		(at 246.486934 -139.591034 -90)
		(property "Reference" "U24"
			(at 0 0 270)
			(layer "F.SilkS")
			(hide yes)
			(effects
				(font
					(size 1.27 1.27)
				)
			)
		)
		(property "Value" "PCA9511ADP-T-GP"
			(at 0 -13.1572 270)
			(unlocked yes)
			(layer "F.Fab")
			(hide yes)
			(effects
				(font
					(size 1.016 1.016)
					(thickness 0.1524)
				)
			)
		)
		(property "Device Type" "SSOIC8-2H44"
			(at 0 -15.1892 270)
			(unlocked yes)
			(layer "F.Fab")
			(hide yes)
			(effects
				(font
					(size 1.016 1.016)
					(thickness 0.1524)
				)
			)
		)
		(duplicate_pad_numbers_are_jumpers no)
		(fp_line
			(start -1.7018 1.0414)
			(end -1.7018 2.9718)
			(stroke
				(width 0.635)
				(type default)
			)
			(layer "F.SilkS")
		)
		(fp_line
			(start -1.9304 1.016)
			(end -1.9304 -1.016)
			(stroke
				(width 0.1524)
				(type default)
			)
			(layer "F.SilkS")
		)
		(fp_line
			(start 1.0922 1.016)
			(end -1.9304 1.016)
			(stroke
				(width 0.1524)
				(type default)
			)
			(layer "F.SilkS")
		)
		(fp_line
			(start -1.524 0)
			(end -1.9304 0.4064)
			(stroke
				(width 0.1524)
				(type default)
			)
			(layer "F.SilkS")
		)
		(fp_line
			(start -1.524 0)
			(end -1.9304 -0.4064)
			(stroke
				(width 0.1524)
				(type default)
			)
			(layer "F.SilkS")
		)
		(fp_line
			(start -1.9304 -1.016)
			(end 1.0922 -1.016)
			(stroke
				(width 0.1524)
				(type default)
			)
			(layer "F.SilkS")
		)
		(fp_line
			(start 1.0922 -1.016)
			(end 1.0922 1.016)
			(stroke
				(width 0.1524)
				(type default)
			)
			(layer "F.SilkS")
		)
		(fp_poly
			(pts
				(xy -1.1938 -1.016) (xy 1.0922 -1.016) (xy 1.0922 1.016) (xy -1.1938 1.016)
			)
			(stroke
				(width 0)
				(type default)
			)
			(fill yes)
			(layer "F.SilkS")
		)
		(fp_rect
			(start -2.0066 3.3401)
			(end 2.0066 -3.3401)
			(stroke
				(width 0)
				(type default)
			)
			(fill no)
			(layer "F.CrtYd")
		)
		(fp_poly
			(pts
				(xy -2.0066 -3.3401) (xy 2.0066 -3.3401) (xy 2.0066 3.3401) (xy -2.0066 3.3401)
			)
			(stroke
				(width 0)
				(type default)
			)
			(fill no)
			(layer "F.Fab")
		)
		(pad "1" smd rect
			(at -0.97536 2.0701 270)
			(size 0.4064 1.524)
			(layers "F.Cu" "F.Mask" "F.Paste")
			(net "I2C_SCC_BUFF_EN")
		)
		(pad "2" smd rect
			(at -0.32512 2.0701 270)
			(size 0.4064 1.524)
			(layers "F.Cu" "F.Mask" "F.Paste")
			(net "I2C_SCC_B_SCL_BUF")
		)
		(pad "3" smd rect
			(at 0.32512 2.0701 270)
			(size 0.4064 1.524)
			(layers "F.Cu" "F.Mask" "F.Paste")
			(net "I2C_SCC_B_SCL")
		)
		(pad "4" smd rect
			(at 0.97536 2.0701 270)
			(size 0.4064 1.524)
			(layers "F.Cu" "F.Mask" "F.Paste")
			(net "GND")
		)
		(pad "5" smd rect
			(at 0.97536 -2.0701 270)
			(size 0.4064 1.524)
			(layers "F.Cu" "F.Mask" "F.Paste")
			(net "I2C_SCC_BUFF_READY")
		)
		(pad "6" smd rect
			(at 0.32512 -2.0701 270)
			(size 0.4064 1.524)
			(layers "F.Cu" "F.Mask" "F.Paste")
			(net "I2C_SCC_B_SDA")
		)
		(pad "7" smd rect
			(at -0.32512 -2.0701 270)
			(size 0.4064 1.524)
			(layers "F.Cu" "F.Mask" "F.Paste")
			(net "I2C_SCC_B_SDA_BUF")
		)
		(pad "8" smd rect
			(at -0.97536 -2.0701 270)
			(size 0.4064 1.524)
			(layers "F.Cu" "F.Mask" "F.Paste")
			(net "P3V3_STBY_B")
		)
	)
	(footprint ""
		(layer "F.Cu")
		(at 246.745252 -368.784632)
		(property "Reference" "C553"
			(at 0 0 0)
			(layer "F.SilkS")
			(hide yes)
			(effects
				(font
					(size 1.27 1.27)
				)
			)
		)
		(property "Value" "SC1KP50V2KX-1GP"
			(at 1.1811 -2.7051 0)
			(unlocked yes)
			(layer "F.Fab")
			(hide yes)
			(effects
				(font
					(size 1.016 1.016)
					(thickness 0.1524)
				)
			)
		)
		(property "Device Type" "C402H22"
			(at 1.1811 -4.2291 0)
			(unlocked yes)
			(layer "F.Fab")
			(hide yes)
			(effects
				(font
					(size 1.016 1.016)
					(thickness 0.1524)
				)
			)
		)
		(duplicate_pad_numbers_are_jumpers no)
		(fp_rect
			(start -0.4318 0.9525)
			(end 0.4318 -0.9525)
			(stroke
				(width 0)
				(type default)
			)
			(fill no)
			(layer "F.CrtYd")
		)
		(fp_rect
			(start -0.4318 0.9525)
			(end 0.4318 -0.9525)
			(stroke
				(width 0)
				(type default)
			)
			(fill no)
			(layer "F.Fab")
		)
		(pad "1" smd custom
			(at 0 -0.4445)
			(size 0.1524 0.1524)
			(layers "F.Cu" "F.Mask" "F.Paste")
			(net "MB3_TEMP_B")
			(options
				(clearance outline)
				(anchor circle)
			)
			(primitives
				(gr_poly
					(pts
						(arc
							(start 0.3048 -0.2032)
							(mid 0.275042 -0.275042)
							(end 0.2032 -0.3048)
						)
						(arc
							(start -0.2032 -0.3048)
							(mid -0.275042 -0.275042)
							(end -0.3048 -0.2032)
						)
						(arc
							(start -0.3048 0.2032)
							(mid -0.275042 0.275042)
							(end -0.2032 0.3048)
						)
						(arc
							(start 0.2032 0.3048)
							(mid 0.275042 0.275042)
							(end 0.3048 0.2032)
						)
					)
					(width 0)
					(fill yes)
				)
			)
		)
		(pad "2" smd custom
			(at 0 0.4445)
			(size 0.1524 0.1524)
			(layers "F.Cu" "F.Mask" "F.Paste")
			(net "MB3_TEMP_E")
			(options
				(clearance outline)
				(anchor circle)
			)
			(primitives
				(gr_poly
					(pts
						(arc
							(start 0.3048 -0.2032)
							(mid 0.275042 -0.275042)
							(end 0.2032 -0.3048)
						)
						(arc
							(start -0.2032 -0.3048)
							(mid -0.275042 -0.275042)
							(end -0.3048 -0.2032)
						)
						(arc
							(start -0.3048 0.2032)
							(mid -0.275042 0.275042)
							(end -0.2032 0.3048)
						)
						(arc
							(start 0.2032 0.3048)
							(mid 0.275042 0.275042)
							(end 0.3048 0.2032)
						)
					)
					(width 0)
					(fill yes)
				)
			)
		)
	)
	(footprint ""
		(layer "F.Cu")
		(at 32.463486 -14.660626 90)
		(property "Reference" "C341"
			(at 0 0 90)
			(layer "F.SilkS")
			(hide yes)
			(effects
				(font
					(size 1.27 1.27)
				)
			)
		)
		(property "Value" "SCD01U16V1KX-GP"
			(at -2.8321 -1.7399 90)
			(unlocked yes)
			(layer "F.Fab")
			(hide yes)
			(effects
				(font
					(size 1.016 1.016)
					(thickness 0.1524)
				)
			)
		)
		(property "Device Type" "C0201H13"
			(at -2.8321 -3.2639 90)
			(unlocked yes)
			(layer "F.Fab")
			(hide yes)
			(effects
				(font
					(size 1.016 1.016)
					(thickness 0.1524)
				)
			)
		)
		(duplicate_pad_numbers_are_jumpers no)
		(fp_rect
			(start -0.2794 0.6477)
			(end 0.2794 -0.6477)
			(stroke
				(width 0)
				(type default)
			)
			(fill no)
			(layer "F.CrtYd")
		)
		(fp_rect
			(start -0.2794 0.6477)
			(end 0.2794 -0.6477)
			(stroke
				(width 0)
				(type default)
			)
			(fill no)
			(layer "F.Fab")
		)
		(pad "1" smd custom
			(at 0 -0.2794 90)
			(size 0.0762 0.0762)
			(layers "F.Cu" "F.Mask" "F.Paste")
			(net "SAS_HDD_RX_P24")
			(options
				(clearance outline)
				(anchor circle)
			)
			(primitives
				(gr_poly
					(pts
						(arc
							(start 0.1524 -0.127)
							(mid 0.137521 -0.162921)
							(end 0.1016 -0.1778)
						)
						(arc
							(start -0.1016 -0.1778)
							(mid -0.137521 -0.162921)
							(end -0.1524 -0.127)
						)
						(arc
							(start -0.1524 0.127)
							(mid -0.137521 0.162921)
							(end -0.1016 0.1778)
						)
						(arc
							(start 0.1016 0.1778)
							(mid 0.137521 0.162921)
							(end 0.1524 0.127)
						)
					)
					(width 0)
					(fill yes)
				)
			)
		)
		(pad "2" smd custom
			(at 0 0.2794 90)
			(size 0.0762 0.0762)
			(layers "F.Cu" "F.Mask" "F.Paste")
			(net "PHY_SCC_B_TO_DRV_B_24_DP")
			(options
				(clearance outline)
				(anchor circle)
			)
			(primitives
				(gr_poly
					(pts
						(arc
							(start 0.1524 -0.127)
							(mid 0.137521 -0.162921)
							(end 0.1016 -0.1778)
						)
						(arc
							(start -0.1016 -0.1778)
							(mid -0.137521 -0.162921)
							(end -0.1524 -0.127)
						)
						(arc
							(start -0.1524 0.127)
							(mid -0.137521 0.162921)
							(end -0.1016 0.1778)
						)
						(arc
							(start 0.1016 0.1778)
							(mid 0.137521 0.162921)
							(end 0.1524 0.127)
						)
					)
					(width 0)
					(fill yes)
				)
			)
		)
	)
	(footprint ""
		(layer "F.Cu")
		(at 264.999978 -65.000124 180)
		(property "Reference" "DPB2"
			(at 0 0 180)
			(layer "F.SilkS")
			(hide yes)
			(effects
				(font
					(size 1.27 1.27)
				)
			)
		)
		(property "Value" "AMP-CONN54-6R-1-GP"
			(at 31.115 10.541 180)
			(unlocked yes)
			(layer "F.Fab")
			(hide yes)
			(effects
				(font
					(size 1.016 1.016)
					(thickness 0.1524)
				)
			)
		)
		(property "Device Type" "PREFIT-54P-216327H571"
			(at 31.115 9.017 180)
			(unlocked yes)
			(layer "F.Fab")
			(hide yes)
			(effects
				(font
					(size 1.016 1.016)
					(thickness 0.1524)
				)
			)
		)
		(duplicate_pad_numbers_are_jumpers no)
		(fp_line
			(start 19.9136 17.5514)
			(end -2.1844 17.5514)
			(stroke
				(width 0.1524)
				(type default)
			)
			(layer "F.SilkS")
		)
		(fp_line
			(start 19.9136 -1.999996)
			(end 19.9136 17.5514)
			(stroke
				(width 0.1524)
				(type default)
			)
			(layer "F.SilkS")
		)
		(fp_line
			(start -2.1844 17.5514)
			(end -2.1844 -1.999996)
			(stroke
				(width 0.1524)
				(type default)
			)
			(layer "F.SilkS")
		)
		(fp_line
			(start -2.1844 -1.999996)
			(end 19.9136 -1.999996)
			(stroke
				(width 0.1524)
				(type default)
			)
			(layer "F.SilkS")
		)
		(fp_poly
			(pts
				(xy -2.1844 17.5514) (xy -2.1844 -1.999996) (xy 19.9136 -1.999996) (xy 19.9136 17.5514) (xy 14.224 17.5514)
				(xy 14.224 15.363698) (xy 19.558 15.363698) (xy 19.558 -0.8636) (xy -0.8636 -0.8636) (xy -0.8636 15.363698)
				(xy 3.048 15.363698) (xy 3.048 17.5514)
			)
			(stroke
				(width 0)
				(type default)
			)
			(fill yes)
			(layer "F.SilkS")
		)
		(fp_poly
			(pts
				(arc
					(start 19.304 14.627352)
					(mid 19.05 14.881352)
					(end 18.796 14.627352)
				)
				(arc
					(start 18.796 14.373352)
					(mid 19.05 14.119352)
					(end 19.304 14.373352)
				)
			)
			(stroke
				(width 0)
				(type default)
			)
			(fill yes)
			(layer "F.SilkS")
		)
		(fp_poly
			(pts
				(arc
					(start 19.304 13.127228)
					(mid 19.05 13.381228)
					(end 18.796 13.127228)
				)
				(arc
					(start 18.796 12.873228)
					(mid 19.05 12.619228)
					(end 19.304 12.873228)
				)
			)
			(stroke
				(width 0)
				(type default)
			)
			(fill yes)
			(layer "F.SilkS")
		)
		(fp_poly
			(pts
				(arc
					(start 19.304 11.627104)
					(mid 19.05 11.881104)
					(end 18.796 11.627104)
				)
				(arc
					(start 18.796 11.373104)
					(mid 19.05 11.119104)
					(end 19.304 11.373104)
				)
			)
			(stroke
				(width 0)
				(type default)
			)
			(fill yes)
			(layer "F.SilkS")
		)
		(fp_poly
			(pts
				(arc
					(start 19.304 8.8773)
					(mid 19.05 9.1313)
					(end 18.796 8.8773)
				)
				(arc
					(start 18.796 8.6233)
					(mid 19.05 8.3693)
					(end 19.304 8.6233)
				)
			)
			(stroke
				(width 0)
				(type default)
			)
			(fill yes)
			(layer "F.SilkS")
		)
		(fp_poly
			(pts
				(arc
					(start 19.304 7.377176)
					(mid 19.05 7.631176)
					(end 18.796 7.377176)
				)
				(arc
					(start 18.796 7.123176)
					(mid 19.05 6.869176)
					(end 19.304 7.123176)
				)
			)
			(stroke
				(width 0)
				(type default)
			)
			(fill yes)
			(layer "F.SilkS")
		)
		(fp_poly
			(pts
				(arc
					(start 19.304 5.877052)
					(mid 19.05 6.131052)
					(end 18.796 5.877052)
				)
				(arc
					(start 18.796 5.623052)
					(mid 19.05 5.369052)
					(end 19.304 5.623052)
				)
			)
			(stroke
				(width 0)
				(type default)
			)
			(fill yes)
			(layer "F.SilkS")
		)
		(fp_poly
			(pts
				(arc
					(start 19.304 3.127248)
					(mid 19.05 3.381248)
					(end 18.796 3.127248)
				)
				(arc
					(start 18.796 2.873248)
					(mid 19.05 2.619248)
					(end 19.304 2.873248)
				)
			)
			(stroke
				(width 0)
				(type default)
			)
			(fill yes)
			(layer "F.SilkS")
		)
		(fp_poly
			(pts
				(arc
					(start 19.304 1.627124)
					(mid 19.05 1.881124)
					(end 18.796 1.627124)
				)
				(arc
					(start 18.796 1.373124)
					(mid 19.05 1.119124)
					(end 19.304 1.373124)
				)
			)
			(stroke
				(width 0)
				(type default)
			)
			(fill yes)
			(layer "F.SilkS")
		)
		(fp_poly
			(pts
				(arc
					(start 19.304 0.127)
					(mid 19.05 0.381)
					(end 18.796 0.127)
				)
				(arc
					(start 18.796 -0.127)
					(mid 19.05 -0.381)
					(end 19.304 -0.127)
				)
			)
			(stroke
				(width 0)
				(type default)
			)
			(fill yes)
			(layer "F.SilkS")
		)
		(fp_rect
			(start -5.6134 20.1168)
			(end 23.2156 -5.6134)
			(stroke
				(width 0)
				(type default)
			)
			(fill no)
			(layer "B.CrtYd")
		)
		(fp_rect
			(start -1.9304 17.2974)
			(end 19.6596 -15.3924)
			(stroke
				(width 0)
				(type default)
			)
			(fill no)
			(layer "F.CrtYd")
		)
		(fp_poly
			(pts
				(xy -2.4384 17.8054) (xy -2.4384 -15.9004) (xy 20.1676 -15.9004) (xy 20.1676 0) (xy 19.6596 0) (xy 19.6596 -15.3924)
				(xy -1.9304 -15.3924) (xy -1.9304 17.2974) (xy 19.6596 17.2974) (xy 19.6596 0.0127) (xy 20.1676 0.0127)
				(xy 20.1676 17.8054)
			)
			(stroke
				(width 0)
				(type default)
			)
			(fill no)
			(layer "F.CrtYd")
		)
		(fp_poly
			(pts
				(xy -6.9342 22.3012) (xy -6.9342 -20.3962) (xy 24.6634 -20.3962) (xy 24.6634 0) (xy 20.1676 0) (xy 20.1676 -15.9004)
				(xy -2.4384 -15.9004) (xy -2.4384 17.8054) (xy 20.1676 17.8054) (xy 20.1676 0.0127) (xy 24.6634 0.0127)
				(xy 24.6634 22.3012)
			)
			(stroke
				(width 0)
				(type default)
			)
			(fill no)
			(layer "F.CrtYd")
		)
		(fp_rect
			(start -5.6134 20.1168)
			(end 23.2156 -5.6134)
			(stroke
				(width 0)
				(type default)
			)
			(fill no)
			(layer "B.Fab")
		)
		(fp_rect
			(start -10.6172 25.1206)
			(end 28.2194 -10.6172)
			(stroke
				(width 0)
				(type default)
			)
			(fill no)
			(layer "B.Fab")
		)
		(fp_rect
			(start -2.4384 17.8054)
			(end 20.1676 -15.9004)
			(stroke
				(width 0)
				(type default)
			)
			(fill no)
			(layer "F.Fab")
		)
		(fp_rect
			(start -6.9342 22.3012)
			(end 24.6634 -20.3962)
			(stroke
				(width 0)
				(type default)
			)
			(fill no)
			(layer "F.Fab")
		)
		(fp_rect
			(start -11.938 27.305)
			(end 29.6672 -25.4)
			(stroke
				(width 0)
				(type default)
			)
			(fill no)
			(layer "F.Fab")
		)
		(fp_text user "Slit"
			(at 5.715 -4.3942 180)
			(unlocked yes)
			(layer "F.SilkS")
			(effects
				(font
					(size 1.016 1.016)
					(thickness 0.1524)
				)
				(justify left)
			)
		)
		(fp_text user "Press Fit"
			(at 3.683 16.5608 180)
			(unlocked yes)
			(layer "F.SilkS")
			(effects
				(font
					(size 1.016 1.016)
					(thickness 0.1524)
				)
				(justify left)
			)
		)
		(fp_text user "Can not place BGA,CSP,Wave Solder Component"
			(at -16.256 23.6728 180)
			(unlocked yes)
			(layer "B.Fab")
			(effects
				(font
					(size 1.016 1.016)
					(thickness 0.1524)
				)
				(justify left)
			)
		)
		(fp_text user "High Limit 2mm"
			(at 0.381 21.0058 180)
			(unlocked yes)
			(layer "F.Fab")
			(effects
				(font
					(size 1.016 1.016)
					(thickness 0.1524)
				)
				(justify left)
			)
		)
		(fp_text user "Can not place BGA,CSP,Wave Solder Component"
			(at -15.875 25.1968 180)
			(unlocked yes)
			(layer "F.Fab")
			(effects
				(font
					(size 1.016 1.016)
					(thickness 0.1524)
				)
				(justify left)
			)
		)
		(pad "A1" thru_hole circle
			(at 0 0 180)
			(size 1.2192 1.2192)
			(drill 0.739902)
			(layers "*.Cu" "*.Mask")
			(remove_unused_layers no)
			(net "P12V_IN")
			(clearance 0.127)
			(thermal_gap 0.127)
		)
		(pad "A2" thru_hole circle
			(at 3.199892 0 180)
			(size 1.2192 1.2192)
			(drill 0.739902)
			(layers "*.Cu" "*.Mask")
			(remove_unused_layers no)
			(net "P12V_IN")
			(clearance 0.127)
			(thermal_gap 0.127)
		)
		(pad "A3" thru_hole circle
			(at 7.200138 0 180)
			(size 1.2192 1.2192)
			(drill 0.739902)
			(layers "*.Cu" "*.Mask")
			(remove_unused_layers no)
			(net "P12V_IN")
			(clearance 0.127)
			(thermal_gap 0.127)
		)
		(pad "A4" thru_hole circle
			(at 10.40003 0 180)
			(size 1.2192 1.2192)
			(drill 0.739902)
			(layers "*.Cu" "*.Mask")
			(remove_unused_layers no)
			(net "P12V_IN")
			(clearance 0.127)
			(thermal_gap 0.127)
		)
		(pad "A5" thru_hole circle
			(at 14.400022 0 180)
			(size 1.2192 1.2192)
			(drill 0.739902)
			(layers "*.Cu" "*.Mask")
			(remove_unused_layers no)
			(net "P12V_B")
			(clearance 0.127)
			(thermal_gap 0.127)
		)
		(pad "A6" thru_hole circle
			(at 17.600168 0 180)
			(size 1.2192 1.2192)
			(drill 0.739902)
			(layers "*.Cu" "*.Mask")
			(remove_unused_layers no)
			(net "P12V_B")
			(clearance 0.127)
			(thermal_gap 0.127)
		)
		(pad "B1" thru_hole oval
			(at 0 1.500124 180)
			(size 1.2192 4.2164)
			(drill 0.739902)
			(layers "*.Cu" "*.Mask")
			(remove_unused_layers no)
			(net "P12V_IN")
			(clearance 0.127)
			(thermal_gap 0.127)
			(padstack
				(mode front_inner_back)
				(layer "Inner"
					(shape circle)
					(size 1.2192 1.2192)
					(clearance 0.127)
				)
				(layer "B.Cu"
					(shape circle)
					(size 1.2192 1.2192)
					(clearance 0.127)
				)
			)
		)
		(pad "B2" thru_hole oval
			(at 3.199892 1.500124 180)
			(size 1.2192 4.2164)
			(drill 0.739902)
			(layers "*.Cu" "*.Mask")
			(remove_unused_layers no)
			(net "P12V_IN")
			(clearance 0.127)
			(thermal_gap 0.127)
			(padstack
				(mode front_inner_back)
				(layer "Inner"
					(shape circle)
					(size 1.2192 1.2192)
					(clearance 0.127)
				)
				(layer "B.Cu"
					(shape circle)
					(size 1.2192 1.2192)
					(clearance 0.127)
				)
			)
		)
		(pad "B3" thru_hole oval
			(at 7.200138 1.500124 180)
			(size 1.2192 4.2164)
			(drill 0.739902)
			(layers "*.Cu" "*.Mask")
			(remove_unused_layers no)
			(net "P12V_IN")
			(clearance 0.127)
			(thermal_gap 0.127)
			(padstack
				(mode front_inner_back)
				(layer "Inner"
					(shape circle)
					(size 1.2192 1.2192)
					(clearance 0.127)
				)
				(layer "B.Cu"
					(shape circle)
					(size 1.2192 1.2192)
					(clearance 0.127)
				)
			)
		)
		(pad "B4" thru_hole oval
			(at 10.40003 1.500124 180)
			(size 1.2192 4.2164)
			(drill 0.739902)
			(layers "*.Cu" "*.Mask")
			(remove_unused_layers no)
			(net "P12V_IN")
			(clearance 0.127)
			(thermal_gap 0.127)
			(padstack
				(mode front_inner_back)
				(layer "Inner"
					(shape circle)
					(size 1.2192 1.2192)
					(clearance 0.127)
				)
				(layer "B.Cu"
					(shape circle)
					(size 1.2192 1.2192)
					(clearance 0.127)
				)
			)
		)
		(pad "B5" thru_hole oval
			(at 14.400022 1.500124 180)
			(size 1.2192 4.2164)
			(drill 0.739902)
			(layers "*.Cu" "*.Mask")
			(remove_unused_layers no)
			(net "P12V_B")
			(clearance 0.127)
			(thermal_gap 0.127)
			(padstack
				(mode front_inner_back)
				(layer "Inner"
					(shape circle)
					(size 1.2192 1.2192)
					(clearance 0.127)
				)
				(layer "B.Cu"
					(shape circle)
					(size 1.2192 1.2192)
					(clearance 0.127)
				)
			)
		)
		(pad "B6" thru_hole oval
			(at 17.600168 1.500124 180)
			(size 1.2192 4.2164)
			(drill 0.739902)
			(layers "*.Cu" "*.Mask")
			(remove_unused_layers no)
			(net "P12V_B")
			(clearance 0.127)
			(thermal_gap 0.127)
			(padstack
				(mode front_inner_back)
				(layer "Inner"
					(shape circle)
					(size 1.2192 1.2192)
					(clearance 0.127)
				)
				(layer "B.Cu"
					(shape circle)
					(size 1.2192 1.2192)
					(clearance 0.127)
				)
			)
		)
		(pad "C1" thru_hole circle
			(at 0 2.999994 180)
			(size 1.2192 1.2192)
			(drill 0.739902)
			(layers "*.Cu" "*.Mask")
			(remove_unused_layers no)
			(net "P12V_IN")
			(clearance 0.127)
			(thermal_gap 0.127)
		)
		(pad "C2" thru_hole circle
			(at 3.199892 2.999994 180)
			(size 1.2192 1.2192)
			(drill 0.739902)
			(layers "*.Cu" "*.Mask")
			(remove_unused_layers no)
			(net "P12V_IN")
			(clearance 0.127)
			(thermal_gap 0.127)
		)
		(pad "C3" thru_hole circle
			(at 7.200138 2.999994 180)
			(size 1.2192 1.2192)
			(drill 0.739902)
			(layers "*.Cu" "*.Mask")
			(remove_unused_layers no)
			(net "P12V_IN")
			(clearance 0.127)
			(thermal_gap 0.127)
		)
		(pad "C4" thru_hole circle
			(at 10.40003 2.999994 180)
			(size 1.2192 1.2192)
			(drill 0.739902)
			(layers "*.Cu" "*.Mask")
			(remove_unused_layers no)
			(net "P12V_IN")
			(clearance 0.127)
			(thermal_gap 0.127)
		)
		(pad "C5" thru_hole circle
			(at 14.400022 2.999994 180)
			(size 1.2192 1.2192)
			(drill 0.739902)
			(layers "*.Cu" "*.Mask")
			(remove_unused_layers no)
			(net "P12V_B")
			(clearance 0.127)
			(thermal_gap 0.127)
		)
		(pad "C6" thru_hole circle
			(at 17.600168 2.999994 180)
			(size 1.2192 1.2192)
			(drill 0.739902)
			(layers "*.Cu" "*.Mask")
			(remove_unused_layers no)
			(net "P12V_B")
			(clearance 0.127)
			(thermal_gap 0.127)
		)
		(pad "D1" thru_hole circle
			(at 0 5.750052 180)
			(size 1.2192 1.2192)
			(drill 0.739902)
			(layers "*.Cu" "*.Mask")
			(remove_unused_layers no)
			(net "P12V_IN")
			(clearance 0.127)
			(thermal_gap 0.127)
		)
		(pad "D2" thru_hole circle
			(at 3.199892 5.750052 180)
			(size 1.2192 1.2192)
			(drill 0.739902)
			(layers "*.Cu" "*.Mask")
			(remove_unused_layers no)
			(net "P12V_IN")
			(clearance 0.127)
			(thermal_gap 0.127)
		)
		(pad "D3" thru_hole circle
			(at 7.200138 5.750052 180)
			(size 1.2192 1.2192)
			(drill 0.739902)
			(layers "*.Cu" "*.Mask")
			(remove_unused_layers no)
			(net "P12V_IN")
			(clearance 0.127)
			(thermal_gap 0.127)
		)
		(pad "D4" thru_hole circle
			(at 10.40003 5.750052 180)
			(size 1.2192 1.2192)
			(drill 0.739902)
			(layers "*.Cu" "*.Mask")
			(remove_unused_layers no)
			(net "P12V_IN")
			(clearance 0.127)
			(thermal_gap 0.127)
		)
		(pad "D5" thru_hole circle
			(at 14.400022 5.750052 180)
			(size 1.2192 1.2192)
			(drill 0.739902)
			(layers "*.Cu" "*.Mask")
			(remove_unused_layers no)
			(net "GND")
			(clearance 0.127)
			(thermal_gap 0.127)
		)
		(pad "D6" thru_hole circle
			(at 17.600168 5.750052 180)
			(size 1.2192 1.2192)
			(drill 0.739902)
			(layers "*.Cu" "*.Mask")
			(remove_unused_layers no)
			(net "GND")
			(clearance 0.127)
			(thermal_gap 0.127)
		)
		(pad "E1" thru_hole oval
			(at 0 7.249922 180)
			(size 1.2192 4.2164)
			(drill 0.739902)
			(layers "*.Cu" "*.Mask")
			(remove_unused_layers no)
			(net "P12V_IN")
			(clearance 0.127)
			(thermal_gap 0.127)
			(padstack
				(mode front_inner_back)
				(layer "Inner"
					(shape circle)
					(size 1.2192 1.2192)
					(clearance 0.127)
				)
				(layer "B.Cu"
					(shape circle)
					(size 1.2192 1.2192)
					(clearance 0.127)
				)
			)
		)
		(pad "E2" thru_hole oval
			(at 3.199892 7.249922 180)
			(size 1.2192 4.2164)
			(drill 0.739902)
			(layers "*.Cu" "*.Mask")
			(remove_unused_layers no)
			(net "P12V_IN")
			(clearance 0.127)
			(thermal_gap 0.127)
			(padstack
				(mode front_inner_back)
				(layer "Inner"
					(shape circle)
					(size 1.2192 1.2192)
					(clearance 0.127)
				)
				(layer "B.Cu"
					(shape circle)
					(size 1.2192 1.2192)
					(clearance 0.127)
				)
			)
		)
		(pad "E3" thru_hole oval
			(at 7.200138 7.249922 180)
			(size 1.2192 4.2164)
			(drill 0.739902)
			(layers "*.Cu" "*.Mask")
			(remove_unused_layers no)
			(net "P12V_IN")
			(clearance 0.127)
			(thermal_gap 0.127)
			(padstack
				(mode front_inner_back)
				(layer "Inner"
					(shape circle)
					(size 1.2192 1.2192)
					(clearance 0.127)
				)
				(layer "B.Cu"
					(shape circle)
					(size 1.2192 1.2192)
					(clearance 0.127)
				)
			)
		)
		(pad "E4" thru_hole oval
			(at 10.40003 7.249922 180)
			(size 1.2192 4.2164)
			(drill 0.739902)
			(layers "*.Cu" "*.Mask")
			(remove_unused_layers no)
			(net "P12V_IN")
			(clearance 0.127)
			(thermal_gap 0.127)
			(padstack
				(mode front_inner_back)
				(layer "Inner"
					(shape circle)
					(size 1.2192 1.2192)
					(clearance 0.127)
				)
				(layer "B.Cu"
					(shape circle)
					(size 1.2192 1.2192)
					(clearance 0.127)
				)
			)
		)
		(pad "E5" thru_hole oval
			(at 14.400022 7.249922 180)
			(size 1.2192 4.2164)
			(drill 0.739902)
			(layers "*.Cu" "*.Mask")
			(remove_unused_layers no)
			(net "GND")
			(clearance 0.127)
			(thermal_gap 0.127)
			(padstack
				(mode front_inner_back)
				(layer "Inner"
					(shape circle)
					(size 1.2192 1.2192)
					(clearance 0.127)
				)
				(layer "B.Cu"
					(shape circle)
					(size 1.2192 1.2192)
					(clearance 0.127)
				)
			)
		)
		(pad "E6" thru_hole oval
			(at 17.600168 7.249922 180)
			(size 1.2192 4.2164)
			(drill 0.739902)
			(layers "*.Cu" "*.Mask")
			(remove_unused_layers no)
			(net "GND")
			(clearance 0.127)
			(thermal_gap 0.127)
			(padstack
				(mode front_inner_back)
				(layer "Inner"
					(shape circle)
					(size 1.2192 1.2192)
					(clearance 0.127)
				)
				(layer "B.Cu"
					(shape circle)
					(size 1.2192 1.2192)
					(clearance 0.127)
				)
			)
		)
		(pad "F1" thru_hole circle
			(at 0 8.750046 180)
			(size 1.2192 1.2192)
			(drill 0.739902)
			(layers "*.Cu" "*.Mask")
			(remove_unused_layers no)
			(net "P12V_IN")
			(clearance 0.127)
			(thermal_gap 0.127)
		)
		(pad "F2" thru_hole circle
			(at 3.199892 8.750046 180)
			(size 1.2192 1.2192)
			(drill 0.739902)
			(layers "*.Cu" "*.Mask")
			(remove_unused_layers no)
			(net "P12V_IN")
			(clearance 0.127)
			(thermal_gap 0.127)
		)
		(pad "F3" thru_hole circle
			(at 7.200138 8.750046 180)
			(size 1.2192 1.2192)
			(drill 0.739902)
			(layers "*.Cu" "*.Mask")
			(remove_unused_layers no)
			(net "P12V_IN")
			(clearance 0.127)
			(thermal_gap 0.127)
		)
		(pad "F4" thru_hole circle
			(at 10.40003 8.750046 180)
			(size 1.2192 1.2192)
			(drill 0.739902)
			(layers "*.Cu" "*.Mask")
			(remove_unused_layers no)
			(net "P12V_IN")
			(clearance 0.127)
			(thermal_gap 0.127)
		)
		(pad "F5" thru_hole circle
			(at 14.400022 8.750046 180)
			(size 1.2192 1.2192)
			(drill 0.739902)
			(layers "*.Cu" "*.Mask")
			(remove_unused_layers no)
			(net "GND")
			(clearance 0.127)
			(thermal_gap 0.127)
		)
		(pad "F6" thru_hole circle
			(at 17.600168 8.750046 180)
			(size 1.2192 1.2192)
			(drill 0.739902)
			(layers "*.Cu" "*.Mask")
			(remove_unused_layers no)
			(net "GND")
			(clearance 0.127)
			(thermal_gap 0.127)
		)
		(pad "G1" thru_hole circle
			(at 0 11.500104 180)
			(size 1.2192 1.2192)
			(drill 0.739902)
			(layers "*.Cu" "*.Mask")
			(remove_unused_layers no)
			(net "GND")
			(clearance 0.127)
			(thermal_gap 0.127)
		)
		(pad "G2" thru_hole circle
			(at 3.199892 11.500104 180)
			(size 1.2192 1.2192)
			(drill 0.739902)
			(layers "*.Cu" "*.Mask")
			(remove_unused_layers no)
			(net "GND")
			(clearance 0.127)
			(thermal_gap 0.127)
		)
		(pad "G3" thru_hole circle
			(at 7.200138 11.500104 180)
			(size 1.2192 1.2192)
			(drill 0.739902)
			(layers "*.Cu" "*.Mask")
			(remove_unused_layers no)
			(net "GND")
			(clearance 0.127)
			(thermal_gap 0.127)
		)
		(pad "G4" thru_hole circle
			(at 10.40003 11.500104 180)
			(size 1.2192 1.2192)
			(drill 0.739902)
			(layers "*.Cu" "*.Mask")
			(remove_unused_layers no)
			(net "GND")
			(clearance 0.127)
			(thermal_gap 0.127)
		)
		(pad "G5" thru_hole circle
			(at 14.400022 11.500104 180)
			(size 1.2192 1.2192)
			(drill 0.739902)
			(layers "*.Cu" "*.Mask")
			(remove_unused_layers no)
			(net "GND")
			(clearance 0.127)
			(thermal_gap 0.127)
		)
		(pad "G6" thru_hole circle
			(at 17.600168 11.500104 180)
			(size 1.2192 1.2192)
			(drill 0.739902)
			(layers "*.Cu" "*.Mask")
			(remove_unused_layers no)
			(net "GND")
			(clearance 0.127)
			(thermal_gap 0.127)
		)
		(pad "H1" thru_hole oval
			(at 0 12.999974 180)
			(size 1.2192 4.2164)
			(drill 0.739902)
			(layers "*.Cu" "*.Mask")
			(remove_unused_layers no)
			(net "GND")
			(clearance 0.127)
			(thermal_gap 0.127)
			(padstack
				(mode front_inner_back)
				(layer "Inner"
					(shape circle)
					(size 1.2192 1.2192)
					(clearance 0.127)
				)
				(layer "B.Cu"
					(shape circle)
					(size 1.2192 1.2192)
					(clearance 0.127)
				)
			)
		)
		(pad "H2" thru_hole oval
			(at 3.199892 12.999974 180)
			(size 1.2192 4.2164)
			(drill 0.739902)
			(layers "*.Cu" "*.Mask")
			(remove_unused_layers no)
			(net "GND")
			(clearance 0.127)
			(thermal_gap 0.127)
			(padstack
				(mode front_inner_back)
				(layer "Inner"
					(shape circle)
					(size 1.2192 1.2192)
					(clearance 0.127)
				)
				(layer "B.Cu"
					(shape circle)
					(size 1.2192 1.2192)
					(clearance 0.127)
				)
			)
		)
		(pad "H3" thru_hole oval
			(at 7.200138 12.999974 180)
			(size 1.2192 4.2164)
			(drill 0.739902)
			(layers "*.Cu" "*.Mask")
			(remove_unused_layers no)
			(net "GND")
			(clearance 0.127)
			(thermal_gap 0.127)
			(padstack
				(mode front_inner_back)
				(layer "Inner"
					(shape circle)
					(size 1.2192 1.2192)
					(clearance 0.127)
				)
				(layer "B.Cu"
					(shape circle)
					(size 1.2192 1.2192)
					(clearance 0.127)
				)
			)
		)
		(pad "H4" thru_hole oval
			(at 10.40003 12.999974 180)
			(size 1.2192 4.2164)
			(drill 0.739902)
			(layers "*.Cu" "*.Mask")
			(remove_unused_layers no)
			(net "GND")
			(clearance 0.127)
			(thermal_gap 0.127)
			(padstack
				(mode front_inner_back)
				(layer "Inner"
					(shape circle)
					(size 1.2192 1.2192)
					(clearance 0.127)
				)
				(layer "B.Cu"
					(shape circle)
					(size 1.2192 1.2192)
					(clearance 0.127)
				)
			)
		)
		(pad "H5" thru_hole oval
			(at 14.400022 12.999974 180)
			(size 1.2192 4.2164)
			(drill 0.739902)
			(layers "*.Cu" "*.Mask")
			(remove_unused_layers no)
			(net "GND")
			(clearance 0.127)
			(thermal_gap 0.127)
			(padstack
				(mode front_inner_back)
				(layer "Inner"
					(shape circle)
					(size 1.2192 1.2192)
					(clearance 0.127)
				)
				(layer "B.Cu"
					(shape circle)
					(size 1.2192 1.2192)
					(clearance 0.127)
				)
			)
		)
		(pad "H6" thru_hole oval
			(at 17.600168 12.999974 180)
			(size 1.2192 4.2164)
			(drill 0.739902)
			(layers "*.Cu" "*.Mask")
			(remove_unused_layers no)
			(net "GND")
			(clearance 0.127)
			(thermal_gap 0.127)
			(padstack
				(mode front_inner_back)
				(layer "Inner"
					(shape circle)
					(size 1.2192 1.2192)
					(clearance 0.127)
				)
				(layer "B.Cu"
					(shape circle)
					(size 1.2192 1.2192)
					(clearance 0.127)
				)
			)
		)
		(pad "J1" thru_hole circle
			(at 0 14.500098 180)
			(size 1.2192 1.2192)
			(drill 0.739902)
			(layers "*.Cu" "*.Mask")
			(remove_unused_layers no)
			(net "GND")
			(clearance 0.127)
			(thermal_gap 0.127)
		)
		(pad "J2" thru_hole circle
			(at 3.199892 14.500098 180)
			(size 1.2192 1.2192)
			(drill 0.739902)
			(layers "*.Cu" "*.Mask")
			(remove_unused_layers no)
			(net "GND")
			(clearance 0.127)
			(thermal_gap 0.127)
		)
		(pad "J3" thru_hole circle
			(at 7.200138 14.500098 180)
			(size 1.2192 1.2192)
			(drill 0.739902)
			(layers "*.Cu" "*.Mask")
			(remove_unused_layers no)
			(net "GND")
			(clearance 0.127)
			(thermal_gap 0.127)
		)
		(pad "J4" thru_hole circle
			(at 10.40003 14.500098 180)
			(size 1.2192 1.2192)
			(drill 0.739902)
			(layers "*.Cu" "*.Mask")
			(remove_unused_layers no)
			(net "GND")
			(clearance 0.127)
			(thermal_gap 0.127)
		)
		(pad "J5" thru_hole circle
			(at 14.400022 14.500098 180)
			(size 1.2192 1.2192)
			(drill 0.739902)
			(layers "*.Cu" "*.Mask")
			(remove_unused_layers no)
			(net "GND")
			(clearance 0.127)
			(thermal_gap 0.127)
		)
		(pad "J6" thru_hole circle
			(at 17.600168 14.500098 180)
			(size 1.2192 1.2192)
			(drill 0.739902)
			(layers "*.Cu" "*.Mask")
			(remove_unused_layers no)
			(net "GND")
			(clearance 0.127)
			(thermal_gap 0.127)
		)
		(zone
			(layer "F.Cu")
			(hatch none 0.5)
			(connect_pads
				(clearance 0)
			)
			(min_thickness 0.25)
			(keepout
				(tracks allowed)
				(vias not_allowed)
				(pads allowed)
				(copperpour not_allowed)
				(footprints allowed)
			)
			(placement
				(enabled no)
				(sheetname "")
			)
			(fill
				(thermal_gap 0.5)
				(thermal_bridge_width 0.5)
				(island_removal_mode 0)
			)
			(polygon
				(pts
					(arc
						(start 248.009664 -73.74382)
						(mid 247.835532 -74.176912)
						(end 247.40616 -74.360024)
					)
					(arc
						(start 247.40616 -75.890374)
						(mid 247.835532 -76.073486)
						(end 248.009664 -76.506578)
					)
					(xy 248.009664 -77.993748) (xy 248.009664 -78.006448)
					(arc
						(start 248.009664 -79.495142)
						(mid 247.39981 -80.110097)
						(end 246.789956 -79.495142)
					)
					(xy 246.789956 -78.006448) (xy 246.789956 -77.993748)
					(arc
						(start 246.789956 -76.506578)
						(mid 246.964088 -76.073486)
						(end 247.39346 -75.890374)
					)
					(arc
						(start 247.39346 -74.360024)
						(mid 246.964088 -74.176912)
						(end 246.789956 -73.74382)
					)
					(xy 246.789956 -72.256396) (xy 246.789956 -72.243696)
					(arc
						(start 246.789956 -70.756526)
						(mid 246.964088 -70.323434)
						(end 247.39346 -70.140322)
					)
					(arc
						(start 247.39346 -68.609972)
						(mid 246.964088 -68.42686)
						(end 246.789956 -67.993768)
					)
					(xy 246.789956 -66.506598) (xy 246.789956 -66.493898)
					(arc
						(start 246.789956 -65.006474)
						(mid 246.964088 -64.573382)
						(end 247.39346 -64.39027)
					)
					(xy 247.39346 -64.15024) (xy 246.549926 -64.15024) (xy 246.549926 -80.350106) (xy 251.450094 -80.350106)
					(xy 251.450094 -64.15024) (xy 250.606306 -64.15024)
					(arc
						(start 250.606306 -64.39027)
						(mid 251.035678 -64.573382)
						(end 251.20981 -65.006474)
					)
					(xy 251.20981 -66.493898) (xy 251.20981 -66.506598)
					(arc
						(start 251.20981 -67.993768)
						(mid 251.035678 -68.42686)
						(end 250.606306 -68.609972)
					)
					(arc
						(start 250.606306 -70.140322)
						(mid 251.035678 -70.323434)
						(end 251.20981 -70.756526)
					)
					(xy 251.20981 -72.243696) (xy 251.20981 -72.256396)
					(arc
						(start 251.20981 -73.74382)
						(mid 251.035678 -74.176912)
						(end 250.606306 -74.360024)
					)
					(arc
						(start 250.606306 -75.890374)
						(mid 251.035678 -76.073486)
						(end 251.20981 -76.506578)
					)
					(xy 251.20981 -77.993748) (xy 251.20981 -78.006448)
					(arc
						(start 251.20981 -79.495142)
						(mid 250.599956 -80.110097)
						(end 249.990102 -79.495142)
					)
					(xy 249.990102 -78.006448) (xy 249.990102 -77.993748)
					(arc
						(start 249.990102 -76.506578)
						(mid 250.164234 -76.073486)
						(end 250.593606 -75.890374)
					)
					(arc
						(start 250.593606 -74.360024)
						(mid 250.164234 -74.176912)
						(end 249.990102 -73.74382)
					)
					(xy 249.990102 -72.256396) (xy 249.990102 -72.243696)
					(arc
						(start 249.990102 -70.756526)
						(mid 250.164234 -70.323434)
						(end 250.593606 -70.140322)
					)
					(arc
						(start 250.593606 -68.609972)
						(mid 250.164234 -68.42686)
						(end 249.990102 -67.993768)
					)
					(xy 249.990102 -66.506598) (xy 249.990102 -66.493898)
					(arc
						(start 249.990102 -65.006474)
						(mid 250.164234 -64.573382)
						(end 250.593606 -64.39027)
					)
					(xy 250.593606 -64.15024) (xy 247.40616 -64.15024)
					(arc
						(start 247.40616 -64.39027)
						(mid 247.835532 -64.573382)
						(end 248.009664 -65.006474)
					)
					(xy 248.009664 -66.493898) (xy 248.009664 -66.506598)
					(arc
						(start 248.009664 -67.993768)
						(mid 247.835532 -68.42686)
						(end 247.40616 -68.609972)
					)
					(arc
						(start 247.40616 -70.140322)
						(mid 247.835532 -70.323434)
						(end 248.009664 -70.756526)
					)
					(xy 248.009664 -72.243696) (xy 248.009664 -72.256396)
				)
			)
		)
		(zone
			(layer "F.Cu")
			(hatch none 0.5)
			(connect_pads
				(clearance 0)
			)
			(min_thickness 0.25)
			(keepout
				(tracks not_allowed)
				(vias allowed)
				(pads allowed)
				(copperpour not_allowed)
				(footprints allowed)
			)
			(placement
				(enabled no)
				(sheetname "")
			)
			(fill
				(thermal_gap 0.5)
				(thermal_bridge_width 0.5)
				(island_removal_mode 0)
			)
			(polygon
				(pts
					(arc
						(start 248.009664 -73.74382)
						(mid 247.835532 -74.176912)
						(end 247.40616 -74.360024)
					)
					(arc
						(start 247.40616 -75.890374)
						(mid 247.835532 -76.073486)
						(end 248.009664 -76.506578)
					)
					(xy 248.009664 -77.993748) (xy 248.009664 -78.006448)
					(arc
						(start 248.009664 -79.495142)
						(mid 247.39981 -80.110097)
						(end 246.789956 -79.495142)
					)
					(xy 246.789956 -78.006448) (xy 246.789956 -77.993748)
					(arc
						(start 246.789956 -76.506578)
						(mid 246.964088 -76.073486)
						(end 247.39346 -75.890374)
					)
					(arc
						(start 247.39346 -74.360024)
						(mid 246.964088 -74.176912)
						(end 246.789956 -73.74382)
					)
					(xy 246.789956 -72.256396) (xy 246.789956 -72.243696)
					(arc
						(start 246.789956 -70.756526)
						(mid 246.964088 -70.323434)
						(end 247.39346 -70.140322)
					)
					(arc
						(start 247.39346 -68.609972)
						(mid 246.964088 -68.42686)
						(end 246.789956 -67.993768)
					)
					(xy 246.789956 -66.506598) (xy 246.789956 -66.493898)
					(arc
						(start 246.789956 -65.006474)
						(mid 246.964088 -64.573382)
						(end 247.39346 -64.39027)
					)
					(xy 247.39346 -64.15024) (xy 246.549926 -64.15024) (xy 246.549926 -80.350106) (xy 251.450094 -80.350106)
					(xy 251.450094 -64.15024) (xy 250.606306 -64.15024)
					(arc
						(start 250.606306 -64.39027)
						(mid 251.035678 -64.573382)
						(end 251.20981 -65.006474)
					)
					(xy 251.20981 -66.493898) (xy 251.20981 -66.506598)
					(arc
						(start 251.20981 -67.993768)
						(mid 251.035678 -68.42686)
						(end 250.606306 -68.609972)
					)
					(arc
						(start 250.606306 -70.140322)
						(mid 251.035678 -70.323434)
						(end 251.20981 -70.756526)
					)
					(xy 251.20981 -72.243696) (xy 251.20981 -72.256396)
					(arc
						(start 251.20981 -73.74382)
						(mid 251.035678 -74.176912)
						(end 250.606306 -74.360024)
					)
					(arc
						(start 250.606306 -75.890374)
						(mid 251.035678 -76.073486)
						(end 251.20981 -76.506578)
					)
					(xy 251.20981 -77.993748) (xy 251.20981 -78.006448)
					(arc
						(start 251.20981 -79.495142)
						(mid 250.599956 -80.110097)
						(end 249.990102 -79.495142)
					)
					(xy 249.990102 -78.006448) (xy 249.990102 -77.993748)
					(arc
						(start 249.990102 -76.506578)
						(mid 250.164234 -76.073486)
						(end 250.593606 -75.890374)
					)
					(arc
						(start 250.593606 -74.360024)
						(mid 250.164234 -74.176912)
						(end 249.990102 -73.74382)
					)
					(xy 249.990102 -72.256396) (xy 249.990102 -72.243696)
					(arc
						(start 249.990102 -70.756526)
						(mid 250.164234 -70.323434)
						(end 250.593606 -70.140322)
					)
					(arc
						(start 250.593606 -68.609972)
						(mid 250.164234 -68.42686)
						(end 249.990102 -67.993768)
					)
					(xy 249.990102 -66.506598) (xy 249.990102 -66.493898)
					(arc
						(start 249.990102 -65.006474)
						(mid 250.164234 -64.573382)
						(end 250.593606 -64.39027)
					)
					(xy 250.593606 -64.15024) (xy 247.40616 -64.15024)
					(arc
						(start 247.40616 -64.39027)
						(mid 247.835532 -64.573382)
						(end 248.009664 -65.006474)
					)
					(xy 248.009664 -66.493898) (xy 248.009664 -66.506598)
					(arc
						(start 248.009664 -67.993768)
						(mid 247.835532 -68.42686)
						(end 247.40616 -68.609972)
					)
					(arc
						(start 247.40616 -70.140322)
						(mid 247.835532 -70.323434)
						(end 248.009664 -70.756526)
					)
					(xy 248.009664 -72.243696) (xy 248.009664 -72.256396)
				)
			)
		)
		(zone
			(layer "F.Cu")
			(hatch none 0.5)
			(connect_pads
				(clearance 0)
			)
			(min_thickness 0.25)
			(keepout
				(tracks not_allowed)
				(vias allowed)
				(pads allowed)
				(copperpour not_allowed)
				(footprints allowed)
			)
			(placement
				(enabled no)
				(sheetname "")
			)
			(fill
				(thermal_gap 0.5)
				(thermal_bridge_width 0.5)
				(island_removal_mode 0)
			)
			(polygon
				(pts
					(xy 258.649978 -80.350106) (xy 258.649978 -64.15024) (xy 257.80619 -64.15024)
					(arc
						(start 257.80619 -64.39027)
						(mid 258.235562 -64.573382)
						(end 258.409694 -65.006474)
					)
					(xy 258.409694 -66.493898) (xy 258.409694 -66.506598)
					(arc
						(start 258.409694 -67.993768)
						(mid 258.235562 -68.42686)
						(end 257.80619 -68.609972)
					)
					(arc
						(start 257.80619 -70.140322)
						(mid 258.235562 -70.323434)
						(end 258.409694 -70.756526)
					)
					(xy 258.409694 -72.243696) (xy 258.409694 -72.256396)
					(arc
						(start 258.409694 -73.74382)
						(mid 258.235562 -74.176912)
						(end 257.80619 -74.360024)
					)
					(arc
						(start 257.80619 -75.890374)
						(mid 258.235562 -76.073486)
						(end 258.409694 -76.506578)
					)
					(xy 258.409694 -77.993748) (xy 258.409694 -78.006448)
					(arc
						(start 258.409694 -79.495142)
						(mid 257.79984 -80.110097)
						(end 257.189986 -79.495142)
					)
					(xy 257.189986 -78.006448) (xy 257.189986 -77.993748)
					(arc
						(start 257.189986 -76.506578)
						(mid 257.364118 -76.073486)
						(end 257.79349 -75.890374)
					)
					(arc
						(start 257.79349 -74.360024)
						(mid 257.364118 -74.176912)
						(end 257.189986 -73.74382)
					)
					(xy 257.189986 -72.256396) (xy 257.189986 -72.243696)
					(arc
						(start 257.189986 -70.756526)
						(mid 257.364118 -70.323434)
						(end 257.79349 -70.140322)
					)
					(arc
						(start 257.79349 -68.609972)
						(mid 257.364118 -68.42686)
						(end 257.189986 -67.993768)
					)
					(xy 257.189986 -66.506598) (xy 257.189986 -66.493898)
					(arc
						(start 257.189986 -65.006474)
						(mid 257.364118 -64.573382)
						(end 257.79349 -64.39027)
					)
					(xy 257.79349 -64.15024) (xy 254.606298 -64.15024)
					(arc
						(start 254.606298 -64.39027)
						(mid 255.03567 -64.573382)
						(end 255.209802 -65.006474)
					)
					(xy 255.209802 -66.493898) (xy 255.209802 -66.506598)
					(arc
						(start 255.209802 -67.993768)
						(mid 255.03567 -68.42686)
						(end 254.606298 -68.609972)
					)
					(arc
						(start 254.606298 -70.140322)
						(mid 255.03567 -70.323434)
						(end 255.209802 -70.756526)
					)
					(xy 255.209802 -72.243696) (xy 255.209802 -72.256396)
					(arc
						(start 255.209802 -73.74382)
						(mid 255.03567 -74.176912)
						(end 254.606298 -74.360024)
					)
					(arc
						(start 254.606298 -75.890374)
						(mid 255.03567 -76.073486)
						(end 255.209802 -76.506578)
					)
					(xy 255.209802 -77.993748) (xy 255.209802 -78.006448)
					(arc
						(start 255.209802 -79.495142)
						(mid 254.599948 -80.110097)
						(end 253.990094 -79.495142)
					)
					(xy 253.990094 -78.006448) (xy 253.990094 -77.993748)
					(arc
						(start 253.990094 -76.506578)
						(mid 254.164226 -76.073486)
						(end 254.593598 -75.890374)
					)
					(arc
						(start 254.593598 -74.360024)
						(mid 254.164226 -74.176912)
						(end 253.990094 -73.74382)
					)
					(xy 253.990094 -72.256396) (xy 253.990094 -72.243696)
					(arc
						(start 253.990094 -70.756526)
						(mid 254.164226 -70.323434)
						(end 254.593598 -70.140322)
					)
					(arc
						(start 254.593598 -68.609972)
						(mid 254.164226 -68.42686)
						(end 253.990094 -67.993768)
					)
					(xy 253.990094 -66.506598) (xy 253.990094 -66.493898)
					(arc
						(start 253.990094 -65.006474)
						(mid 254.164226 -64.573382)
						(end 254.593598 -64.39027)
					)
					(xy 254.593598 -64.15024) (xy 253.750064 -64.15024) (xy 253.750064 -80.350106)
				)
			)
		)
		(zone
			(layer "F.Cu")
			(hatch none 0.5)
			(connect_pads
				(clearance 0)
			)
			(min_thickness 0.25)
			(keepout
				(tracks allowed)
				(vias not_allowed)
				(pads allowed)
				(copperpour not_allowed)
				(footprints allowed)
			)
			(placement
				(enabled no)
				(sheetname "")
			)
			(fill
				(thermal_gap 0.5)
				(thermal_bridge_width 0.5)
				(island_removal_mode 0)
			)
			(polygon
				(pts
					(xy 258.649978 -80.350106) (xy 258.649978 -64.15024) (xy 257.80619 -64.15024)
					(arc
						(start 257.80619 -64.39027)
						(mid 258.235562 -64.573382)
						(end 258.409694 -65.006474)
					)
					(xy 258.409694 -66.493898) (xy 258.409694 -66.506598)
					(arc
						(start 258.409694 -67.993768)
						(mid 258.235562 -68.42686)
						(end 257.80619 -68.609972)
					)
					(arc
						(start 257.80619 -70.140322)
						(mid 258.235562 -70.323434)
						(end 258.409694 -70.756526)
					)
					(xy 258.409694 -72.243696) (xy 258.409694 -72.256396)
					(arc
						(start 258.409694 -73.74382)
						(mid 258.235562 -74.176912)
						(end 257.80619 -74.360024)
					)
					(arc
						(start 257.80619 -75.890374)
						(mid 258.235562 -76.073486)
						(end 258.409694 -76.506578)
					)
					(xy 258.409694 -77.993748) (xy 258.409694 -78.006448)
					(arc
						(start 258.409694 -79.495142)
						(mid 257.79984 -80.110097)
						(end 257.189986 -79.495142)
					)
					(xy 257.189986 -78.006448) (xy 257.189986 -77.993748)
					(arc
						(start 257.189986 -76.506578)
						(mid 257.364118 -76.073486)
						(end 257.79349 -75.890374)
					)
					(arc
						(start 257.79349 -74.360024)
						(mid 257.364118 -74.176912)
						(end 257.189986 -73.74382)
					)
					(xy 257.189986 -72.256396) (xy 257.189986 -72.243696)
					(arc
						(start 257.189986 -70.756526)
						(mid 257.364118 -70.323434)
						(end 257.79349 -70.140322)
					)
					(arc
						(start 257.79349 -68.609972)
						(mid 257.364118 -68.42686)
						(end 257.189986 -67.993768)
					)
					(xy 257.189986 -66.506598) (xy 257.189986 -66.493898)
					(arc
						(start 257.189986 -65.006474)
						(mid 257.364118 -64.573382)
						(end 257.79349 -64.39027)
					)
					(xy 257.79349 -64.15024) (xy 254.606298 -64.15024)
					(arc
						(start 254.606298 -64.39027)
						(mid 255.03567 -64.573382)
						(end 255.209802 -65.006474)
					)
					(xy 255.209802 -66.493898) (xy 255.209802 -66.506598)
					(arc
						(start 255.209802 -67.993768)
						(mid 255.03567 -68.42686)
						(end 254.606298 -68.609972)
					)
					(arc
						(start 254.606298 -70.140322)
						(mid 255.03567 -70.323434)
						(end 255.209802 -70.756526)
					)
					(xy 255.209802 -72.243696) (xy 255.209802 -72.256396)
					(arc
						(start 255.209802 -73.74382)
						(mid 255.03567 -74.176912)
						(end 254.606298 -74.360024)
					)
					(arc
						(start 254.606298 -75.890374)
						(mid 255.03567 -76.073486)
						(end 255.209802 -76.506578)
					)
					(xy 255.209802 -77.993748) (xy 255.209802 -78.006448)
					(arc
						(start 255.209802 -79.495142)
						(mid 254.599948 -80.110097)
						(end 253.990094 -79.495142)
					)
					(xy 253.990094 -78.006448) (xy 253.990094 -77.993748)
					(arc
						(start 253.990094 -76.506578)
						(mid 254.164226 -76.073486)
						(end 254.593598 -75.890374)
					)
					(arc
						(start 254.593598 -74.360024)
						(mid 254.164226 -74.176912)
						(end 253.990094 -73.74382)
					)
					(xy 253.990094 -72.256396) (xy 253.990094 -72.243696)
					(arc
						(start 253.990094 -70.756526)
						(mid 254.164226 -70.323434)
						(end 254.593598 -70.140322)
					)
					(arc
						(start 254.593598 -68.609972)
						(mid 254.164226 -68.42686)
						(end 253.990094 -67.993768)
					)
					(xy 253.990094 -66.506598) (xy 253.990094 -66.493898)
					(arc
						(start 253.990094 -65.006474)
						(mid 254.164226 -64.573382)
						(end 254.593598 -64.39027)
					)
					(xy 254.593598 -64.15024) (xy 253.750064 -64.15024) (xy 253.750064 -80.350106)
				)
			)
		)
		(zone
			(layer "F.Cu")
			(hatch none 0.5)
			(connect_pads
				(clearance 0)
			)
			(min_thickness 0.25)
			(keepout
				(tracks allowed)
				(vias not_allowed)
				(pads allowed)
				(copperpour not_allowed)
				(footprints allowed)
			)
			(placement
				(enabled no)
				(sheetname "")
			)
			(fill
				(thermal_gap 0.5)
				(thermal_bridge_width 0.5)
				(island_removal_mode 0)
			)
			(polygon
				(pts
					(xy 265.849862 -80.350106) (xy 265.849862 -64.15024) (xy 265.006328 -64.15024)
					(arc
						(start 265.006328 -64.39027)
						(mid 265.4357 -64.573382)
						(end 265.609832 -65.006474)
					)
					(xy 265.609832 -66.493898) (xy 265.609832 -66.506598)
					(arc
						(start 265.609832 -67.993768)
						(mid 265.4357 -68.42686)
						(end 265.006328 -68.609972)
					)
					(arc
						(start 265.006328 -70.140322)
						(mid 265.4357 -70.323434)
						(end 265.609832 -70.756526)
					)
					(xy 265.609832 -72.243696) (xy 265.609832 -72.256396)
					(arc
						(start 265.609832 -73.74382)
						(mid 265.4357 -74.176912)
						(end 265.006328 -74.360024)
					)
					(arc
						(start 265.006328 -75.890374)
						(mid 265.4357 -76.073486)
						(end 265.609832 -76.506578)
					)
					(xy 265.609832 -77.993748) (xy 265.609832 -78.006448)
					(arc
						(start 265.609832 -79.495142)
						(mid 264.999978 -80.110097)
						(end 264.390124 -79.495142)
					)
					(xy 264.390124 -78.006448) (xy 264.390124 -77.993748)
					(arc
						(start 264.390124 -76.506578)
						(mid 264.564256 -76.073486)
						(end 264.993628 -75.890374)
					)
					(arc
						(start 264.993628 -74.360024)
						(mid 264.564256 -74.176912)
						(end 264.390124 -73.74382)
					)
					(xy 264.390124 -72.256396) (xy 264.390124 -72.243696)
					(arc
						(start 264.390124 -70.756526)
						(mid 264.564256 -70.323434)
						(end 264.993628 -70.140322)
					)
					(arc
						(start 264.993628 -68.609972)
						(mid 264.564256 -68.42686)
						(end 264.390124 -67.993768)
					)
					(xy 264.390124 -66.506598) (xy 264.390124 -66.493898)
					(arc
						(start 264.390124 -65.006474)
						(mid 264.564256 -64.573382)
						(end 264.993628 -64.39027)
					)
					(xy 264.993628 -64.15024) (xy 261.806436 -64.15024)
					(arc
						(start 261.806436 -64.39027)
						(mid 262.235808 -64.573382)
						(end 262.40994 -65.006474)
					)
					(xy 262.40994 -66.493898) (xy 262.40994 -66.506598)
					(arc
						(start 262.40994 -67.993768)
						(mid 262.235808 -68.42686)
						(end 261.806436 -68.609972)
					)
					(arc
						(start 261.806436 -70.140322)
						(mid 262.235808 -70.323434)
						(end 262.40994 -70.756526)
					)
					(xy 262.40994 -72.243696) (xy 262.40994 -72.256396)
					(arc
						(start 262.40994 -73.74382)
						(mid 262.235808 -74.176912)
						(end 261.806436 -74.360024)
					)
					(arc
						(start 261.806436 -75.890374)
						(mid 262.235808 -76.073486)
						(end 262.40994 -76.506578)
					)
					(xy 262.40994 -77.993748) (xy 262.40994 -78.006448)
					(arc
						(start 262.40994 -79.495142)
						(mid 261.800086 -80.110097)
						(end 261.190232 -79.495142)
					)
					(xy 261.190232 -78.006448) (xy 261.190232 -77.993748)
					(arc
						(start 261.190232 -76.506578)
						(mid 261.364364 -76.073486)
						(end 261.793736 -75.890374)
					)
					(arc
						(start 261.793736 -74.360024)
						(mid 261.364364 -74.176912)
						(end 261.190232 -73.74382)
					)
					(xy 261.190232 -72.256396) (xy 261.190232 -72.243696)
					(arc
						(start 261.190232 -70.756526)
						(mid 261.364364 -70.323434)
						(end 261.793736 -70.140322)
					)
					(arc
						(start 261.793736 -68.609972)
						(mid 261.364364 -68.42686)
						(end 261.190232 -67.993768)
					)
					(xy 261.190232 -66.506598) (xy 261.190232 -66.493898)
					(arc
						(start 261.190232 -65.006474)
						(mid 261.364364 -64.573382)
						(end 261.793736 -64.39027)
					)
					(xy 261.793736 -64.15024) (xy 260.949948 -64.15024) (xy 260.949948 -80.350106)
				)
			)
		)
		(zone
			(layer "F.Cu")
			(hatch none 0.5)
			(connect_pads
				(clearance 0)
			)
			(min_thickness 0.25)
			(keepout
				(tracks not_allowed)
				(vias allowed)
				(pads allowed)
				(copperpour not_allowed)
				(footprints allowed)
			)
			(placement
				(enabled no)
				(sheetname "")
			)
			(fill
				(thermal_gap 0.5)
				(thermal_bridge_width 0.5)
				(island_removal_mode 0)
			)
			(polygon
				(pts
					(xy 265.849862 -80.350106) (xy 265.849862 -64.15024) (xy 265.006328 -64.15024)
					(arc
						(start 265.006328 -64.39027)
						(mid 265.4357 -64.573382)
						(end 265.609832 -65.006474)
					)
					(xy 265.609832 -66.493898) (xy 265.609832 -66.506598)
					(arc
						(start 265.609832 -67.993768)
						(mid 265.4357 -68.42686)
						(end 265.006328 -68.609972)
					)
					(arc
						(start 265.006328 -70.140322)
						(mid 265.4357 -70.323434)
						(end 265.609832 -70.756526)
					)
					(xy 265.609832 -72.243696) (xy 265.609832 -72.256396)
					(arc
						(start 265.609832 -73.74382)
						(mid 265.4357 -74.176912)
						(end 265.006328 -74.360024)
					)
					(arc
						(start 265.006328 -75.890374)
						(mid 265.4357 -76.073486)
						(end 265.609832 -76.506578)
					)
					(xy 265.609832 -77.993748) (xy 265.609832 -78.006448)
					(arc
						(start 265.609832 -79.495142)
						(mid 264.999978 -80.110097)
						(end 264.390124 -79.495142)
					)
					(xy 264.390124 -78.006448) (xy 264.390124 -77.993748)
					(arc
						(start 264.390124 -76.506578)
						(mid 264.564256 -76.073486)
						(end 264.993628 -75.890374)
					)
					(arc
						(start 264.993628 -74.360024)
						(mid 264.564256 -74.176912)
						(end 264.390124 -73.74382)
					)
					(xy 264.390124 -72.256396) (xy 264.390124 -72.243696)
					(arc
						(start 264.390124 -70.756526)
						(mid 264.564256 -70.323434)
						(end 264.993628 -70.140322)
					)
					(arc
						(start 264.993628 -68.609972)
						(mid 264.564256 -68.42686)
						(end 264.390124 -67.993768)
					)
					(xy 264.390124 -66.506598) (xy 264.390124 -66.493898)
					(arc
						(start 264.390124 -65.006474)
						(mid 264.564256 -64.573382)
						(end 264.993628 -64.39027)
					)
					(xy 264.993628 -64.15024) (xy 261.806436 -64.15024)
					(arc
						(start 261.806436 -64.39027)
						(mid 262.235808 -64.573382)
						(end 262.40994 -65.006474)
					)
					(xy 262.40994 -66.493898) (xy 262.40994 -66.506598)
					(arc
						(start 262.40994 -67.993768)
						(mid 262.235808 -68.42686)
						(end 261.806436 -68.609972)
					)
					(arc
						(start 261.806436 -70.140322)
						(mid 262.235808 -70.323434)
						(end 262.40994 -70.756526)
					)
					(xy 262.40994 -72.243696) (xy 262.40994 -72.256396)
					(arc
						(start 262.40994 -73.74382)
						(mid 262.235808 -74.176912)
						(end 261.806436 -74.360024)
					)
					(arc
						(start 261.806436 -75.890374)
						(mid 262.235808 -76.073486)
						(end 262.40994 -76.506578)
					)
					(xy 262.40994 -77.993748) (xy 262.40994 -78.006448)
					(arc
						(start 262.40994 -79.495142)
						(mid 261.800086 -80.110097)
						(end 261.190232 -79.495142)
					)
					(xy 261.190232 -78.006448) (xy 261.190232 -77.993748)
					(arc
						(start 261.190232 -76.506578)
						(mid 261.364364 -76.073486)
						(end 261.793736 -75.890374)
					)
					(arc
						(start 261.793736 -74.360024)
						(mid 261.364364 -74.176912)
						(end 261.190232 -73.74382)
					)
					(xy 261.190232 -72.256396) (xy 261.190232 -72.243696)
					(arc
						(start 261.190232 -70.756526)
						(mid 261.364364 -70.323434)
						(end 261.793736 -70.140322)
					)
					(arc
						(start 261.793736 -68.609972)
						(mid 261.364364 -68.42686)
						(end 261.190232 -67.993768)
					)
					(xy 261.190232 -66.506598) (xy 261.190232 -66.493898)
					(arc
						(start 261.190232 -65.006474)
						(mid 261.364364 -64.573382)
						(end 261.793736 -64.39027)
					)
					(xy 261.793736 -64.15024) (xy 260.949948 -64.15024) (xy 260.949948 -80.350106)
				)
			)
		)
	)
	(footprint ""
		(layer "F.Cu")
		(at 174.371 -374.904 90)
		(property "Reference" "R1001"
			(at 0 0 90)
			(layer "F.SilkS")
			(hide yes)
			(effects
				(font
					(size 1.27 1.27)
				)
			)
		)
		(property "Value" "11KR2F-L-GP"
			(at 0.064008 -3.993896 90)
			(unlocked yes)
			(layer "F.Fab")
			(hide yes)
			(effects
				(font
					(size 1.016 1.016)
					(thickness 0.1524)
				)
			)
		)
		(property "Device Type" "R402H16"
			(at 0.064008 -5.517896 90)
			(unlocked yes)
			(layer "F.Fab")
			(hide yes)
			(effects
				(font
					(size 1.016 1.016)
					(thickness 0.1524)
				)
			)
		)
		(duplicate_pad_numbers_are_jumpers no)
		(fp_line
			(start 0.508 -0.9398)
			(end -0.508 -0.9398)
			(stroke
				(width 0.1524)
				(type default)
			)
			(layer "F.SilkS")
		)
		(fp_line
			(start -0.508 -0.9398)
			(end -0.508 0.9398)
			(stroke
				(width 0.1524)
				(type default)
			)
			(layer "F.SilkS")
		)
		(fp_rect
			(start -0.508 0.9398)
			(end 0.508 -0.9398)
			(stroke
				(width 0)
				(type default)
			)
			(fill no)
			(layer "F.CrtYd")
		)
		(fp_rect
			(start -0.508 0.9398)
			(end 0.508 -0.9398)
			(stroke
				(width 0)
				(type default)
			)
			(fill no)
			(layer "F.Fab")
		)
		(pad "1" smd custom
			(at 0 -0.4445 90)
			(size 0.1397 0.1397)
			(layers "F.Cu" "F.Mask" "F.Paste")
			(net "MB0_P12V_PWGIN_R")
			(options
				(clearance outline)
				(anchor circle)
			)
			(primitives
				(gr_poly
					(pts
						(arc
							(start -0.1778 -0.2794)
							(mid -0.249642 -0.249642)
							(end -0.2794 -0.1778)
						)
						(arc
							(start -0.2794 0.1778)
							(mid -0.249642 0.249642)
							(end -0.1778 0.2794)
						)
						(arc
							(start 0.1778 0.2794)
							(mid 0.249642 0.249642)
							(end 0.2794 0.1778)
						)
						(arc
							(start 0.2794 -0.1778)
							(mid 0.249642 -0.249642)
							(end 0.1778 -0.2794)
						)
					)
					(width 0)
					(fill yes)
				)
			)
		)
		(pad "2" smd custom
			(at 0 0.4445 90)
			(size 0.1397 0.1397)
			(layers "F.Cu" "F.Mask" "F.Paste")
			(net "AGND_CURRENT_MON")
			(options
				(clearance outline)
				(anchor circle)
			)
			(primitives
				(gr_poly
					(pts
						(arc
							(start -0.1778 -0.2794)
							(mid -0.249642 -0.249642)
							(end -0.2794 -0.1778)
						)
						(arc
							(start -0.2794 0.1778)
							(mid -0.249642 0.249642)
							(end -0.1778 0.2794)
						)
						(arc
							(start 0.1778 0.2794)
							(mid 0.249642 0.249642)
							(end 0.2794 0.1778)
						)
						(arc
							(start 0.2794 -0.1778)
							(mid 0.249642 -0.249642)
							(end 0.1778 -0.2794)
						)
					)
					(width 0)
					(fill yes)
				)
			)
		)
	)
	(footprint ""
		(layer "F.Cu")
		(at 459.359 -15.9258)
		(property "Reference" "R864"
			(at 0 0 0)
			(layer "F.SilkS")
			(hide yes)
			(effects
				(font
					(size 1.27 1.27)
				)
			)
		)
		(property "Value" "4K7R2F-GP"
			(at 0.064008 -3.993896 0)
			(unlocked yes)
			(layer "F.Fab")
			(hide yes)
			(effects
				(font
					(size 1.016 1.016)
					(thickness 0.1524)
				)
			)
		)
		(property "Device Type" "R402H16"
			(at 0.064008 -5.517896 0)
			(unlocked yes)
			(layer "F.Fab")
			(hide yes)
			(effects
				(font
					(size 1.016 1.016)
					(thickness 0.1524)
				)
			)
		)
		(duplicate_pad_numbers_are_jumpers no)
		(fp_line
			(start -0.508 -0.9398)
			(end -0.508 0.9398)
			(stroke
				(width 0.1524)
				(type default)
			)
			(layer "F.SilkS")
		)
		(fp_line
			(start 0.508 -0.9398)
			(end -0.508 -0.9398)
			(stroke
				(width 0.1524)
				(type default)
			)
			(layer "F.SilkS")
		)
		(fp_rect
			(start -0.508 0.9398)
			(end 0.508 -0.9398)
			(stroke
				(width 0)
				(type default)
			)
			(fill no)
			(layer "F.CrtYd")
		)
		(fp_rect
			(start -0.508 0.9398)
			(end 0.508 -0.9398)
			(stroke
				(width 0)
				(type default)
			)
			(fill no)
			(layer "F.Fab")
		)
		(pad "1" smd custom
			(at 0 -0.4445)
			(size 0.1397 0.1397)
			(layers "F.Cu" "F.Mask" "F.Paste")
			(net "SW_PWR_R_HDD34")
			(options
				(clearance outline)
				(anchor circle)
			)
			(primitives
				(gr_poly
					(pts
						(arc
							(start -0.1778 -0.2794)
							(mid -0.249642 -0.249642)
							(end -0.2794 -0.1778)
						)
						(arc
							(start -0.2794 0.1778)
							(mid -0.249642 0.249642)
							(end -0.1778 0.2794)
						)
						(arc
							(start 0.1778 0.2794)
							(mid 0.249642 0.249642)
							(end 0.2794 0.1778)
						)
						(arc
							(start 0.2794 -0.1778)
							(mid 0.249642 -0.249642)
							(end 0.1778 -0.2794)
						)
					)
					(width 0)
					(fill yes)
				)
			)
		)
		(pad "2" smd custom
			(at 0 0.4445)
			(size 0.1397 0.1397)
			(layers "F.Cu" "F.Mask" "F.Paste")
			(net "GND")
			(options
				(clearance outline)
				(anchor circle)
			)
			(primitives
				(gr_poly
					(pts
						(arc
							(start -0.1778 -0.2794)
							(mid -0.249642 -0.249642)
							(end -0.2794 -0.1778)
						)
						(arc
							(start -0.2794 0.1778)
							(mid -0.249642 0.249642)
							(end -0.1778 0.2794)
						)
						(arc
							(start 0.1778 0.2794)
							(mid 0.249642 0.249642)
							(end 0.2794 0.1778)
						)
						(arc
							(start 0.2794 -0.1778)
							(mid 0.249642 -0.249642)
							(end 0.1778 -0.2794)
						)
					)
					(width 0)
					(fill yes)
				)
			)
		)
	)
	(footprint ""
		(layer "F.Cu")
		(at 447.04 -151.13 -90)
		(property "Reference" "R580"
			(at 0 0 270)
			(layer "F.SilkS")
			(hide yes)
			(effects
				(font
					(size 1.27 1.27)
				)
			)
		)
		(property "Value" "220R3F-1-GP"
			(at -0.0254 -2.5146 270)
			(unlocked yes)
			(layer "F.Fab")
			(hide yes)
			(effects
				(font
					(size 1.016 1.016)
					(thickness 0.1524)
				)
			)
		)
		(property "Device Type" "R603H22"
			(at -0.0254 -4.0386 270)
			(unlocked yes)
			(layer "F.Fab")
			(hide yes)
			(effects
				(font
					(size 1.016 1.016)
					(thickness 0.1524)
				)
			)
		)
		(duplicate_pad_numbers_are_jumpers no)
		(fp_line
			(start -0.4826 0)
			(end -0.2032 0)
			(stroke
				(width 0.2032)
				(type default)
			)
			(layer "F.SilkS")
		)
		(fp_line
			(start 0.2032 0)
			(end 0.4826 0)
			(stroke
				(width 0.2032)
				(type default)
			)
			(layer "F.SilkS")
		)
		(fp_rect
			(start -0.5842 1.3335)
			(end 0.5842 -1.3335)
			(stroke
				(width 0)
				(type default)
			)
			(fill no)
			(layer "F.CrtYd")
		)
		(fp_rect
			(start -0.5842 1.3335)
			(end 0.5842 -1.3335)
			(stroke
				(width 0)
				(type default)
			)
			(fill no)
			(layer "F.Fab")
		)
		(pad "1" smd custom
			(at 0 -0.762 270)
			(size 0.2159 0.2159)
			(layers "F.Cu" "F.Mask" "F.Paste")
			(net "HDD_PRSNT_22")
			(options
				(clearance outline)
				(anchor circle)
			)
			(primitives
				(gr_poly
					(pts
						(arc
							(start -0.3302 -0.4318)
							(mid -0.402042 -0.402042)
							(end -0.4318 -0.3302)
						)
						(arc
							(start -0.4318 0.3302)
							(mid -0.402042 0.402042)
							(end -0.3302 0.4318)
						)
						(arc
							(start 0.3302 0.4318)
							(mid 0.402042 0.402042)
							(end 0.4318 0.3302)
						)
						(arc
							(start 0.4318 -0.3302)
							(mid 0.402042 -0.402042)
							(end 0.3302 -0.4318)
						)
					)
					(width 0)
					(fill yes)
				)
			)
		)
		(pad "2" smd custom
			(at 0 0.762 270)
			(size 0.2159 0.2159)
			(layers "F.Cu" "F.Mask" "F.Paste")
			(net "DRIVE_B_22_INS")
			(options
				(clearance outline)
				(anchor circle)
			)
			(primitives
				(gr_poly
					(pts
						(arc
							(start -0.3302 -0.4318)
							(mid -0.402042 -0.402042)
							(end -0.4318 -0.3302)
						)
						(arc
							(start -0.4318 0.3302)
							(mid -0.402042 0.402042)
							(end -0.3302 0.4318)
						)
						(arc
							(start 0.3302 0.4318)
							(mid 0.402042 0.402042)
							(end 0.4318 0.3302)
						)
						(arc
							(start 0.4318 -0.3302)
							(mid 0.402042 -0.402042)
							(end 0.3302 -0.4318)
						)
					)
					(width 0)
					(fill yes)
				)
			)
		)
	)
	(footprint ""
		(layer "F.Cu")
		(at 209.423 -205.994 -90)
		(property "Reference" "R49"
			(at 0 0 270)
			(layer "F.SilkS")
			(hide yes)
			(effects
				(font
					(size 1.27 1.27)
				)
			)
		)
		(property "Value" "0R2J-2-GP"
			(at 0.064008 -3.993896 270)
			(unlocked yes)
			(layer "F.Fab")
			(hide yes)
			(effects
				(font
					(size 1.016 1.016)
					(thickness 0.1524)
				)
			)
		)
		(property "Device Type" "R402H16"
			(at 0.064008 -5.517896 270)
			(unlocked yes)
			(layer "F.Fab")
			(hide yes)
			(effects
				(font
					(size 1.016 1.016)
					(thickness 0.1524)
				)
			)
		)
		(duplicate_pad_numbers_are_jumpers no)
		(fp_line
			(start -0.508 -0.9398)
			(end -0.508 0.9398)
			(stroke
				(width 0.1524)
				(type default)
			)
			(layer "F.SilkS")
		)
		(fp_line
			(start 0.508 -0.9398)
			(end -0.508 -0.9398)
			(stroke
				(width 0.1524)
				(type default)
			)
			(layer "F.SilkS")
		)
		(fp_rect
			(start -0.508 0.9398)
			(end 0.508 -0.9398)
			(stroke
				(width 0)
				(type default)
			)
			(fill no)
			(layer "F.CrtYd")
		)
		(fp_rect
			(start -0.508 0.9398)
			(end 0.508 -0.9398)
			(stroke
				(width 0)
				(type default)
			)
			(fill no)
			(layer "F.Fab")
		)
		(pad "1" smd custom
			(at 0 -0.4445 270)
			(size 0.1397 0.1397)
			(layers "F.Cu" "F.Mask" "F.Paste")
			(net "IO_EXP5_SCL")
			(options
				(clearance outline)
				(anchor circle)
			)
			(primitives
				(gr_poly
					(pts
						(arc
							(start -0.1778 -0.2794)
							(mid -0.249642 -0.249642)
							(end -0.2794 -0.1778)
						)
						(arc
							(start -0.2794 0.1778)
							(mid -0.249642 0.249642)
							(end -0.1778 0.2794)
						)
						(arc
							(start 0.1778 0.2794)
							(mid 0.249642 0.249642)
							(end 0.2794 0.1778)
						)
						(arc
							(start 0.2794 -0.1778)
							(mid 0.249642 -0.249642)
							(end 0.1778 -0.2794)
						)
					)
					(width 0)
					(fill yes)
				)
			)
		)
		(pad "2" smd custom
			(at 0 0.4445 270)
			(size 0.1397 0.1397)
			(layers "F.Cu" "F.Mask" "F.Paste")
			(net "I2C_DRIVE_B_INS_SCL")
			(options
				(clearance outline)
				(anchor circle)
			)
			(primitives
				(gr_poly
					(pts
						(arc
							(start -0.1778 -0.2794)
							(mid -0.249642 -0.249642)
							(end -0.2794 -0.1778)
						)
						(arc
							(start -0.2794 0.1778)
							(mid -0.249642 0.249642)
							(end -0.1778 0.2794)
						)
						(arc
							(start 0.1778 0.2794)
							(mid 0.249642 0.249642)
							(end 0.2794 0.1778)
						)
						(arc
							(start 0.2794 -0.1778)
							(mid 0.249642 -0.249642)
							(end 0.1778 -0.2794)
						)
					)
					(width 0)
					(fill yes)
				)
			)
		)
	)
	(footprint ""
		(layer "F.Cu")
		(at 307.300884 -358.470962 180)
		(property "Reference" "Q267"
			(at 0 0 180)
			(layer "F.SilkS")
			(hide yes)
			(effects
				(font
					(size 1.27 1.27)
				)
			)
		)
		(property "Value" "2N7002K-2-GP"
			(at 0.127 -8.9662 180)
			(unlocked yes)
			(layer "F.Fab")
			(hide yes)
			(effects
				(font
					(size 1.016 1.016)
					(thickness 0.1524)
				)
			)
		)
		(property "Device Type" "SOT23DGS2D4H44"
			(at 0.127 -10.4902 180)
			(unlocked yes)
			(layer "F.Fab")
			(hide yes)
			(effects
				(font
					(size 1.016 1.016)
					(thickness 0.1524)
				)
			)
		)
		(duplicate_pad_numbers_are_jumpers no)
		(fp_line
			(start 1.651 1.778)
			(end 1.651 -1.778)
			(stroke
				(width 0.1524)
				(type default)
			)
			(layer "F.SilkS")
		)
		(fp_line
			(start 1.651 -1.778)
			(end -1.651 -1.778)
			(stroke
				(width 0.1524)
				(type default)
			)
			(layer "F.SilkS")
		)
		(fp_line
			(start -1.651 1.778)
			(end 1.651 1.778)
			(stroke
				(width 0.1524)
				(type default)
			)
			(layer "F.SilkS")
		)
		(fp_line
			(start -1.651 -1.778)
			(end -1.651 1.778)
			(stroke
				(width 0.1524)
				(type default)
			)
			(layer "F.SilkS")
		)
		(fp_poly
			(pts
				(xy -1.778 1.8796) (xy -1.778 -1.8796) (xy 1.778 -1.8796) (xy 1.778 1.8796)
			)
			(stroke
				(width 0)
				(type default)
			)
			(fill no)
			(layer "F.CrtYd")
		)
		(fp_poly
			(pts
				(xy -1.778 1.8796) (xy -1.778 -1.8796) (xy 1.778 -1.8796) (xy 1.778 1.8796)
			)
			(stroke
				(width 0)
				(type default)
			)
			(fill no)
			(layer "F.Fab")
		)
		(pad "D" smd custom
			(at 0 -0.9525 180)
			(size 0.1905 0.1905)
			(layers "F.Cu" "F.Mask" "F.Paste")
			(net "FANTACH_B_OE_N")
			(options
				(clearance outline)
				(anchor circle)
			)
			(primitives
				(gr_poly
					(pts
						(arc
							(start -0.1778 0.5715)
							(mid -0.321484 0.511984)
							(end -0.381 0.3683)
						)
						(arc
							(start -0.381 -0.3683)
							(mid -0.321484 -0.511984)
							(end -0.1778 -0.5715)
						)
						(arc
							(start 0.1778 -0.5715)
							(mid 0.321484 -0.511984)
							(end 0.381 -0.3683)
						)
						(arc
							(start 0.381 0.3683)
							(mid 0.321484 0.511984)
							(end 0.1778 0.5715)
						)
					)
					(width 0)
					(fill yes)
				)
			)
		)
		(pad "G" smd custom
			(at -0.98425 0.9525 180)
			(size 0.1905 0.1905)
			(layers "F.Cu" "F.Mask" "F.Paste")
			(net "FANTACH_B_OE")
			(options
				(clearance outline)
				(anchor circle)
			)
			(primitives
				(gr_poly
					(pts
						(arc
							(start -0.1778 0.5715)
							(mid -0.321484 0.511984)
							(end -0.381 0.3683)
						)
						(arc
							(start -0.381 -0.3683)
							(mid -0.321484 -0.511984)
							(end -0.1778 -0.5715)
						)
						(arc
							(start 0.1778 -0.5715)
							(mid 0.321484 -0.511984)
							(end 0.381 -0.3683)
						)
						(arc
							(start 0.381 0.3683)
							(mid 0.321484 0.511984)
							(end 0.1778 0.5715)
						)
					)
					(width 0)
					(fill yes)
				)
			)
		)
		(pad "S" smd custom
			(at 0.98425 0.9525 180)
			(size 0.1905 0.1905)
			(layers "F.Cu" "F.Mask" "F.Paste")
			(net "GND")
			(options
				(clearance outline)
				(anchor circle)
			)
			(primitives
				(gr_poly
					(pts
						(arc
							(start -0.1778 0.5715)
							(mid -0.321484 0.511984)
							(end -0.381 0.3683)
						)
						(arc
							(start -0.381 -0.3683)
							(mid -0.321484 -0.511984)
							(end -0.1778 -0.5715)
						)
						(arc
							(start 0.1778 -0.5715)
							(mid 0.321484 -0.511984)
							(end 0.381 -0.3683)
						)
						(arc
							(start 0.381 0.3683)
							(mid 0.321484 0.511984)
							(end 0.1778 0.5715)
						)
					)
					(width 0)
					(fill yes)
				)
			)
		)
	)
	(footprint ""
		(layer "F.Cu")
		(at 215.773 -221.234 -90)
		(property "Reference" "U3"
			(at 0 0 270)
			(layer "F.SilkS")
			(hide yes)
			(effects
				(font
					(size 1.27 1.27)
				)
			)
		)
		(property "Value" "TCA9555PWR-GP"
			(at 0 -6.9342 270)
			(unlocked yes)
			(layer "F.Fab")
			(hide yes)
			(effects
				(font
					(size 1.016 1.016)
					(thickness 0.1524)
				)
			)
		)
		(property "Device Type" "TSOIC24H48"
			(at 0 -8.5852 270)
			(unlocked yes)
			(layer "F.Fab")
			(hide yes)
			(effects
				(font
					(size 1.016 1.016)
					(thickness 0.1524)
				)
			)
		)
		(duplicate_pad_numbers_are_jumpers no)
		(fp_line
			(start -4.2291 3.937)
			(end -4.2291 -1.397)
			(stroke
				(width 0.1524)
				(type default)
			)
			(layer "F.SilkS")
		)
		(fp_line
			(start -4.22656 3.81)
			(end -4.2291 1.397)
			(stroke
				(width 0.508)
				(type default)
			)
			(layer "F.SilkS")
		)
		(fp_line
			(start 3.81 1.397)
			(end -4.2291 1.397)
			(stroke
				(width 0.1524)
				(type default)
			)
			(layer "F.SilkS")
		)
		(fp_line
			(start -3.429 0)
			(end -4.2291 0.8001)
			(stroke
				(width 0.1524)
				(type default)
			)
			(layer "F.SilkS")
		)
		(fp_line
			(start -4.2291 -0.8001)
			(end -3.429 0)
			(stroke
				(width 0.1524)
				(type default)
			)
			(layer "F.SilkS")
		)
		(fp_line
			(start -4.2291 -1.397)
			(end 3.81 -1.397)
			(stroke
				(width 0.1524)
				(type default)
			)
			(layer "F.SilkS")
		)
		(fp_line
			(start 3.81 -1.397)
			(end 3.81 1.397)
			(stroke
				(width 0.1524)
				(type default)
			)
			(layer "F.SilkS")
		)
		(fp_poly
			(pts
				(xy -3.90652 -1.8542) (xy 3.90652 -1.8542) (xy 3.90652 1.8542) (xy -3.90652 1.8542)
			)
			(stroke
				(width 0)
				(type default)
			)
			(fill yes)
			(layer "F.SilkS")
		)
		(fp_poly
			(pts
				(xy -4.2164 3.81) (xy 4.2164 3.81) (xy 4.22656 -3.81) (xy -4.2164 -3.81)
			)
			(stroke
				(width 0)
				(type default)
			)
			(fill no)
			(layer "F.CrtYd")
		)
		(fp_poly
			(pts
				(xy -4.22656 -3.81) (xy 4.22656 -3.81) (xy 4.22656 3.81) (xy -4.22656 3.81)
			)
			(stroke
				(width 0)
				(type default)
			)
			(fill no)
			(layer "F.Fab")
		)
		(pad "1" smd rect
			(at -3.57632 2.8194 270)
			(size 0.3556 1.524)
			(layers "F.Cu" "F.Mask" "F.Paste")
			(net "IO_EXP1_HDD_FAULT_INT_N")
		)
		(pad "2" smd rect
			(at -2.92608 2.8194 270)
			(size 0.3556 1.524)
			(layers "F.Cu" "F.Mask" "F.Paste")
			(net "IO_EXP1_HDD_FAULT_A1")
		)
		(pad "3" smd rect
			(at -2.27584 2.8194 270)
			(size 0.3556 1.524)
			(layers "F.Cu" "F.Mask" "F.Paste")
			(net "IO_EXP1_HDD_FAULT_A2")
		)
		(pad "4" smd rect
			(at -1.6256 2.8194 270)
			(size 0.3556 1.524)
			(layers "F.Cu" "F.Mask" "F.Paste")
			(net "DRIVE_B_0_FLT_LED")
		)
		(pad "5" smd rect
			(at -0.97536 2.8194 270)
			(size 0.3556 1.524)
			(layers "F.Cu" "F.Mask" "F.Paste")
			(net "DRIVE_B_1_FLT_LED")
		)
		(pad "6" smd rect
			(at -0.32512 2.8194 270)
			(size 0.3556 1.524)
			(layers "F.Cu" "F.Mask" "F.Paste")
			(net "DRIVE_B_2_FLT_LED")
		)
		(pad "7" smd rect
			(at 0.32512 2.8194 270)
			(size 0.3556 1.524)
			(layers "F.Cu" "F.Mask" "F.Paste")
			(net "DRIVE_B_3_FLT_LED")
		)
		(pad "8" smd rect
			(at 0.97536 2.8194 270)
			(size 0.3556 1.524)
			(layers "F.Cu" "F.Mask" "F.Paste")
			(net "DRIVE_B_4_FLT_LED")
		)
		(pad "9" smd rect
			(at 1.6256 2.8194 270)
			(size 0.3556 1.524)
			(layers "F.Cu" "F.Mask" "F.Paste")
			(net "DRIVE_B_5_FLT_LED")
		)
		(pad "10" smd rect
			(at 2.27584 2.8194 270)
			(size 0.3556 1.524)
			(layers "F.Cu" "F.Mask" "F.Paste")
			(net "DRIVE_B_6_FLT_LED")
		)
		(pad "11" smd rect
			(at 2.92608 2.8194 270)
			(size 0.3556 1.524)
			(layers "F.Cu" "F.Mask" "F.Paste")
			(net "DRIVE_B_7_FLT_LED")
		)
		(pad "12" smd rect
			(at 3.57632 2.8194 270)
			(size 0.3556 1.524)
			(layers "F.Cu" "F.Mask" "F.Paste")
			(net "GND")
		)
		(pad "13" smd rect
			(at 3.57632 -2.8194 270)
			(size 0.3556 1.524)
			(layers "F.Cu" "F.Mask" "F.Paste")
			(net "DRIVE_B_8_FLT_LED")
		)
		(pad "14" smd rect
			(at 2.92608 -2.8194 270)
			(size 0.3556 1.524)
			(layers "F.Cu" "F.Mask" "F.Paste")
			(net "DRIVE_B_9_FLT_LED")
		)
		(pad "15" smd rect
			(at 2.27584 -2.8194 270)
			(size 0.3556 1.524)
			(layers "F.Cu" "F.Mask" "F.Paste")
			(net "DRIVE_B_10_FLT_LED")
		)
		(pad "16" smd rect
			(at 1.6256 -2.8194 270)
			(size 0.3556 1.524)
			(layers "F.Cu" "F.Mask" "F.Paste")
			(net "DRIVE_B_11_FLT_LED")
		)
		(pad "17" smd rect
			(at 0.97536 -2.8194 270)
			(size 0.3556 1.524)
			(layers "F.Cu" "F.Mask" "F.Paste")
			(net "DRIVE_B_12_FLT_LED")
		)
		(pad "18" smd rect
			(at 0.32512 -2.8194 270)
			(size 0.3556 1.524)
			(layers "F.Cu" "F.Mask" "F.Paste")
			(net "DRIVE_B_13_FLT_LED")
		)
		(pad "19" smd rect
			(at -0.32512 -2.8194 270)
			(size 0.3556 1.524)
			(layers "F.Cu" "F.Mask" "F.Paste")
			(net "DRIVE_B_14_FLT_LED")
		)
		(pad "20" smd rect
			(at -0.97536 -2.8194 270)
			(size 0.3556 1.524)
			(layers "F.Cu" "F.Mask" "F.Paste")
			(net "DRIVE_B_15_FLT_LED")
		)
		(pad "21" smd rect
			(at -1.6256 -2.8194 270)
			(size 0.3556 1.524)
			(layers "F.Cu" "F.Mask" "F.Paste")
			(net "IO_EXP1_HDD_FAULT_A0")
		)
		(pad "22" smd rect
			(at -2.27584 -2.8194 270)
			(size 0.3556 1.524)
			(layers "F.Cu" "F.Mask" "F.Paste")
			(net "IO_EXP1_LED_SCL")
		)
		(pad "23" smd rect
			(at -2.92608 -2.8194 270)
			(size 0.3556 1.524)
			(layers "F.Cu" "F.Mask" "F.Paste")
			(net "IO_EXP1_LED_SDA")
		)
		(pad "24" smd rect
			(at -3.57632 -2.8194 270)
			(size 0.3556 1.524)
			(layers "F.Cu" "F.Mask" "F.Paste")
			(net "P3V3_STBY_B")
		)
	)
	(footprint ""
		(layer "F.Cu")
		(at 161.925 -151.003 90)
		(property "Reference" "R442"
			(at 0 0 90)
			(layer "F.SilkS")
			(hide yes)
			(effects
				(font
					(size 1.27 1.27)
				)
			)
		)
		(property "Value" "220R3F-1-GP"
			(at -0.0254 -2.5146 90)
			(unlocked yes)
			(layer "F.Fab")
			(hide yes)
			(effects
				(font
					(size 1.016 1.016)
					(thickness 0.1524)
				)
			)
		)
		(property "Device Type" "R603H22"
			(at -0.0254 -4.0386 90)
			(unlocked yes)
			(layer "F.Fab")
			(hide yes)
			(effects
				(font
					(size 1.016 1.016)
					(thickness 0.1524)
				)
			)
		)
		(duplicate_pad_numbers_are_jumpers no)
		(fp_line
			(start 0.2032 0)
			(end 0.4826 0)
			(stroke
				(width 0.2032)
				(type default)
			)
			(layer "F.SilkS")
		)
		(fp_line
			(start -0.4826 0)
			(end -0.2032 0)
			(stroke
				(width 0.2032)
				(type default)
			)
			(layer "F.SilkS")
		)
		(fp_rect
			(start -0.5842 1.3335)
			(end 0.5842 -1.3335)
			(stroke
				(width 0)
				(type default)
			)
			(fill no)
			(layer "F.CrtYd")
		)
		(fp_rect
			(start -0.5842 1.3335)
			(end 0.5842 -1.3335)
			(stroke
				(width 0)
				(type default)
			)
			(fill no)
			(layer "F.Fab")
		)
		(pad "1" smd custom
			(at 0 -0.762 90)
			(size 0.2159 0.2159)
			(layers "F.Cu" "F.Mask" "F.Paste")
			(net "HDD_PRSNT_16")
			(options
				(clearance outline)
				(anchor circle)
			)
			(primitives
				(gr_poly
					(pts
						(arc
							(start -0.3302 -0.4318)
							(mid -0.402042 -0.402042)
							(end -0.4318 -0.3302)
						)
						(arc
							(start -0.4318 0.3302)
							(mid -0.402042 0.402042)
							(end -0.3302 0.4318)
						)
						(arc
							(start 0.3302 0.4318)
							(mid 0.402042 0.402042)
							(end 0.4318 0.3302)
						)
						(arc
							(start 0.4318 -0.3302)
							(mid 0.402042 -0.402042)
							(end 0.3302 -0.4318)
						)
					)
					(width 0)
					(fill yes)
				)
			)
		)
		(pad "2" smd custom
			(at 0 0.762 90)
			(size 0.2159 0.2159)
			(layers "F.Cu" "F.Mask" "F.Paste")
			(net "DRIVE_B_16_INS")
			(options
				(clearance outline)
				(anchor circle)
			)
			(primitives
				(gr_poly
					(pts
						(arc
							(start -0.3302 -0.4318)
							(mid -0.402042 -0.402042)
							(end -0.4318 -0.3302)
						)
						(arc
							(start -0.4318 0.3302)
							(mid -0.402042 0.402042)
							(end -0.3302 0.4318)
						)
						(arc
							(start 0.3302 0.4318)
							(mid 0.402042 0.402042)
							(end 0.4318 0.3302)
						)
						(arc
							(start 0.4318 -0.3302)
							(mid 0.402042 -0.402042)
							(end 0.3302 -0.4318)
						)
					)
					(width 0)
					(fill yes)
				)
			)
		)
	)
	(footprint ""
		(layer "F.Cu")
		(at 172.974 -248.158 180)
		(property "Reference" "R250"
			(at 0 0 180)
			(layer "F.SilkS")
			(hide yes)
			(effects
				(font
					(size 1.27 1.27)
				)
			)
		)
		(property "Value" "200KR2F-L-GP"
			(at 0.064008 -3.993896 180)
			(unlocked yes)
			(layer "F.Fab")
			(hide yes)
			(effects
				(font
					(size 1.016 1.016)
					(thickness 0.1524)
				)
			)
		)
		(property "Device Type" "R402H16"
			(at 0.064008 -5.517896 180)
			(unlocked yes)
			(layer "F.Fab")
			(hide yes)
			(effects
				(font
					(size 1.016 1.016)
					(thickness 0.1524)
				)
			)
		)
		(duplicate_pad_numbers_are_jumpers no)
		(fp_line
			(start 0.508 -0.9398)
			(end -0.508 -0.9398)
			(stroke
				(width 0.1524)
				(type default)
			)
			(layer "F.SilkS")
		)
		(fp_line
			(start -0.508 -0.9398)
			(end -0.508 0.9398)
			(stroke
				(width 0.1524)
				(type default)
			)
			(layer "F.SilkS")
		)
		(fp_rect
			(start -0.508 0.9398)
			(end 0.508 -0.9398)
			(stroke
				(width 0)
				(type default)
			)
			(fill no)
			(layer "F.CrtYd")
		)
		(fp_rect
			(start -0.508 0.9398)
			(end 0.508 -0.9398)
			(stroke
				(width 0)
				(type default)
			)
			(fill no)
			(layer "F.Fab")
		)
		(pad "1" smd custom
			(at 0 -0.4445 180)
			(size 0.1397 0.1397)
			(layers "F.Cu" "F.Mask" "F.Paste")
			(net "SW_HDD_R5")
			(options
				(clearance outline)
				(anchor circle)
			)
			(primitives
				(gr_poly
					(pts
						(arc
							(start -0.1778 -0.2794)
							(mid -0.249642 -0.249642)
							(end -0.2794 -0.1778)
						)
						(arc
							(start -0.2794 0.1778)
							(mid -0.249642 0.249642)
							(end -0.1778 0.2794)
						)
						(arc
							(start 0.1778 0.2794)
							(mid 0.249642 0.249642)
							(end 0.2794 0.1778)
						)
						(arc
							(start 0.2794 -0.1778)
							(mid 0.249642 -0.249642)
							(end 0.1778 -0.2794)
						)
					)
					(width 0)
					(fill yes)
				)
			)
		)
		(pad "2" smd custom
			(at 0 0.4445 180)
			(size 0.1397 0.1397)
			(layers "F.Cu" "F.Mask" "F.Paste")
			(net "SW_HDD_N5")
			(options
				(clearance outline)
				(anchor circle)
			)
			(primitives
				(gr_poly
					(pts
						(arc
							(start -0.1778 -0.2794)
							(mid -0.249642 -0.249642)
							(end -0.2794 -0.1778)
						)
						(arc
							(start -0.2794 0.1778)
							(mid -0.249642 0.249642)
							(end -0.1778 0.2794)
						)
						(arc
							(start 0.1778 0.2794)
							(mid 0.249642 0.249642)
							(end 0.2794 0.1778)
						)
						(arc
							(start 0.2794 -0.1778)
							(mid 0.249642 -0.249642)
							(end 0.1778 -0.2794)
						)
					)
					(width 0)
					(fill yes)
				)
			)
		)
	)
	(footprint ""
		(layer "F.Cu")
		(at 338.709 -257.81 -90)
		(property "Reference" "R265"
			(at 0 0 270)
			(layer "F.SilkS")
			(hide yes)
			(effects
				(font
					(size 1.27 1.27)
				)
			)
		)
		(property "Value" "300KR2F-GP"
			(at 0.064008 -3.993896 270)
			(unlocked yes)
			(layer "F.Fab")
			(hide yes)
			(effects
				(font
					(size 1.016 1.016)
					(thickness 0.1524)
				)
			)
		)
		(property "Device Type" "R402H16"
			(at 0.064008 -5.517896 270)
			(unlocked yes)
			(layer "F.Fab")
			(hide yes)
			(effects
				(font
					(size 1.016 1.016)
					(thickness 0.1524)
				)
			)
		)
		(duplicate_pad_numbers_are_jumpers no)
		(fp_line
			(start -0.508 -0.9398)
			(end -0.508 0.9398)
			(stroke
				(width 0.1524)
				(type default)
			)
			(layer "F.SilkS")
		)
		(fp_line
			(start 0.508 -0.9398)
			(end -0.508 -0.9398)
			(stroke
				(width 0.1524)
				(type default)
			)
			(layer "F.SilkS")
		)
		(fp_rect
			(start -0.508 0.9398)
			(end 0.508 -0.9398)
			(stroke
				(width 0)
				(type default)
			)
			(fill no)
			(layer "F.CrtYd")
		)
		(fp_rect
			(start -0.508 0.9398)
			(end 0.508 -0.9398)
			(stroke
				(width 0)
				(type default)
			)
			(fill no)
			(layer "F.Fab")
		)
		(pad "1" smd custom
			(at 0 -0.4445 270)
			(size 0.1397 0.1397)
			(layers "F.Cu" "F.Mask" "F.Paste")
			(net "SW_HDD_N6")
			(options
				(clearance outline)
				(anchor circle)
			)
			(primitives
				(gr_poly
					(pts
						(arc
							(start -0.1778 -0.2794)
							(mid -0.249642 -0.249642)
							(end -0.2794 -0.1778)
						)
						(arc
							(start -0.2794 0.1778)
							(mid -0.249642 0.249642)
							(end -0.1778 0.2794)
						)
						(arc
							(start 0.1778 0.2794)
							(mid 0.249642 0.249642)
							(end 0.2794 0.1778)
						)
						(arc
							(start 0.2794 -0.1778)
							(mid 0.249642 -0.249642)
							(end 0.1778 -0.2794)
						)
					)
					(width 0)
					(fill yes)
				)
			)
		)
		(pad "2" smd custom
			(at 0 0.4445 270)
			(size 0.1397 0.1397)
			(layers "F.Cu" "F.Mask" "F.Paste")
			(net "P12V_B")
			(options
				(clearance outline)
				(anchor circle)
			)
			(primitives
				(gr_poly
					(pts
						(arc
							(start -0.1778 -0.2794)
							(mid -0.249642 -0.249642)
							(end -0.2794 -0.1778)
						)
						(arc
							(start -0.2794 0.1778)
							(mid -0.249642 0.249642)
							(end -0.1778 0.2794)
						)
						(arc
							(start 0.1778 0.2794)
							(mid 0.249642 0.249642)
							(end 0.2794 0.1778)
						)
						(arc
							(start 0.2794 -0.1778)
							(mid 0.249642 -0.249642)
							(end 0.1778 -0.2794)
						)
					)
					(width 0)
					(fill yes)
				)
			)
		)
	)
	(footprint ""
		(layer "F.Cu")
		(at 439.82386 -111.266478 -90)
		(property "Reference" "R1162"
			(at 0 0 270)
			(layer "F.SilkS")
			(hide yes)
			(effects
				(font
					(size 1.27 1.27)
				)
			)
		)
		(property "Value" "3D01R5F-GP"
			(at 0 -8.9535 270)
			(unlocked yes)
			(layer "F.Fab")
			(hide yes)
			(effects
				(font
					(size 1.27 1.016)
					(thickness 0.1524)
				)
			)
		)
		(property "Device Type" "R805H24"
			(at 0 -10.6299 270)
			(unlocked yes)
			(layer "F.Fab")
			(hide yes)
			(effects
				(font
					(size 1.27 1.016)
					(thickness 0.1524)
				)
			)
		)
		(duplicate_pad_numbers_are_jumpers no)
		(fp_line
			(start -0.889 1.7018)
			(end 0.889 1.7018)
			(stroke
				(width 0.1524)
				(type default)
			)
			(layer "F.SilkS")
		)
		(fp_line
			(start 0.889 1.7018)
			(end 0.889 -0.508)
			(stroke
				(width 0.1524)
				(type default)
			)
			(layer "F.SilkS")
		)
		(fp_line
			(start -0.889 0.0762)
			(end -0.889 1.7018)
			(stroke
				(width 0.1524)
				(type default)
			)
			(layer "F.SilkS")
		)
		(fp_line
			(start -0.889 -1.7018)
			(end -0.889 0.2794)
			(stroke
				(width 0.1524)
				(type default)
			)
			(layer "F.SilkS")
		)
		(fp_line
			(start 0.889 -1.7018)
			(end 0.889 -0.381)
			(stroke
				(width 0.1524)
				(type default)
			)
			(layer "F.SilkS")
		)
		(fp_line
			(start 0.889 -1.7018)
			(end -0.889 -1.7018)
			(stroke
				(width 0.1524)
				(type default)
			)
			(layer "F.SilkS")
		)
		(fp_poly
			(pts
				(xy 0.9652 -1.778) (xy 0.9652 1.778) (xy -0.9652 1.778) (xy -0.9652 -1.778)
			)
			(stroke
				(width 0)
				(type default)
			)
			(fill no)
			(layer "F.CrtYd")
		)
		(fp_rect
			(start -0.9652 1.778)
			(end 0.9652 -1.778)
			(stroke
				(width 0)
				(type default)
			)
			(fill no)
			(layer "F.Fab")
		)
		(pad "1" smd rect
			(at 0 -0.9652 270)
			(size 1.397 1.143)
			(layers "F.Cu" "F.Mask" "F.Paste")
			(net "P5V_B_4_SNB")
		)
		(pad "2" smd rect
			(at 0 0.9652 270)
			(size 1.397 1.143)
			(layers "F.Cu" "F.Mask" "F.Paste")
			(net "GND")
		)
	)
	(footprint ""
		(layer "F.Cu")
		(at 46.957996 -360.2355 180)
		(property "Reference" "C365"
			(at 0 0 180)
			(layer "F.SilkS")
			(hide yes)
			(effects
				(font
					(size 1.27 1.27)
				)
			)
		)
		(property "Value" "SCD033U25V2KX-GP"
			(at 1.1811 -2.7051 180)
			(unlocked yes)
			(layer "F.Fab")
			(hide yes)
			(effects
				(font
					(size 1.016 1.016)
					(thickness 0.1524)
				)
			)
		)
		(property "Device Type" "C402H22"
			(at 1.1811 -4.2291 180)
			(unlocked yes)
			(layer "F.Fab")
			(hide yes)
			(effects
				(font
					(size 1.016 1.016)
					(thickness 0.1524)
				)
			)
		)
		(duplicate_pad_numbers_are_jumpers no)
		(fp_rect
			(start -0.4318 0.9525)
			(end 0.4318 -0.9525)
			(stroke
				(width 0)
				(type default)
			)
			(fill no)
			(layer "F.CrtYd")
		)
		(fp_rect
			(start -0.4318 0.9525)
			(end 0.4318 -0.9525)
			(stroke
				(width 0)
				(type default)
			)
			(fill no)
			(layer "F.Fab")
		)
		(pad "1" smd custom
			(at 0 -0.4445 180)
			(size 0.1524 0.1524)
			(layers "F.Cu" "F.Mask" "F.Paste")
			(net "GATE_FAN0_R")
			(options
				(clearance outline)
				(anchor circle)
			)
			(primitives
				(gr_poly
					(pts
						(arc
							(start 0.3048 -0.2032)
							(mid 0.275042 -0.275042)
							(end 0.2032 -0.3048)
						)
						(arc
							(start -0.2032 -0.3048)
							(mid -0.275042 -0.275042)
							(end -0.3048 -0.2032)
						)
						(arc
							(start -0.3048 0.2032)
							(mid -0.275042 0.275042)
							(end -0.2032 0.3048)
						)
						(arc
							(start 0.2032 0.3048)
							(mid 0.275042 0.275042)
							(end 0.3048 0.2032)
						)
					)
					(width 0)
					(fill yes)
				)
			)
		)
		(pad "2" smd custom
			(at 0 0.4445 180)
			(size 0.1524 0.1524)
			(layers "F.Cu" "F.Mask" "F.Paste")
			(net "P12V_IN")
			(options
				(clearance outline)
				(anchor circle)
			)
			(primitives
				(gr_poly
					(pts
						(arc
							(start 0.3048 -0.2032)
							(mid 0.275042 -0.275042)
							(end 0.2032 -0.3048)
						)
						(arc
							(start -0.2032 -0.3048)
							(mid -0.275042 -0.275042)
							(end -0.3048 -0.2032)
						)
						(arc
							(start -0.3048 0.2032)
							(mid -0.275042 0.275042)
							(end -0.2032 0.3048)
						)
						(arc
							(start 0.2032 0.3048)
							(mid 0.275042 0.275042)
							(end 0.3048 0.2032)
						)
					)
					(width 0)
					(fill yes)
				)
			)
		)
	)
	(footprint ""
		(layer "F.Cu")
		(at 160.963864 -269.705074)
		(property "Reference" "TP41"
			(at 0 0 0)
			(layer "F.SilkS")
			(hide yes)
			(effects
				(font
					(size 1.27 1.27)
				)
			)
		)
		(property "Value" "*"
			(at -0.0508 -1.6764 0)
			(unlocked yes)
			(layer "F.Fab")
			(hide yes)
			(effects
				(font
					(size 1.016 1.016)
					(thickness 0.1524)
				)
			)
		)
		(property "Device Type" "TPAD32"
			(at -0.0508 -3.2004 0)
			(unlocked yes)
			(layer "F.Fab")
			(hide yes)
			(effects
				(font
					(size 1.016 1.016)
					(thickness 0.1524)
				)
			)
		)
		(duplicate_pad_numbers_are_jumpers no)
		(fp_poly
			(pts
				(arc
					(start 0.4064 0)
					(mid -0.4064 0)
					(end 0.4064 0)
				)
			)
			(stroke
				(width 0)
				(type default)
			)
			(fill no)
			(layer "F.CrtYd")
		)
		(fp_poly
			(pts
				(arc
					(start 0.7112 0)
					(mid -0.7112 0)
					(end 0.7112 0)
				)
			)
			(stroke
				(width 0)
				(type default)
			)
			(fill no)
			(layer "F.Fab")
		)
		(pad "1" smd circle
			(at 0 0)
			(size 0.8128 0.8128)
			(layers "F.Cu" "F.Mask" "F.Paste")
			(net "ACT_HDD_4")
		)
	)
	(footprint ""
		(layer "F.Cu")
		(at 118.618 -272.288)
		(property "Reference" "C74"
			(at 0 0 0)
			(layer "F.SilkS")
			(hide yes)
			(effects
				(font
					(size 1.27 1.27)
				)
			)
		)
		(property "Value" "SC4D7U25V5KX-1-GP"
			(at -0.0762 -6.1214 0)
			(unlocked yes)
			(layer "F.Fab")
			(hide yes)
			(effects
				(font
					(size 1.016 1.016)
					(thickness 0.1524)
				)
			)
		)
		(property "Device Type" "C805H58"
			(at -0.0762 -8.1534 0)
			(unlocked yes)
			(layer "F.Fab")
			(hide yes)
			(effects
				(font
					(size 1.016 1.016)
					(thickness 0.1524)
				)
			)
		)
		(duplicate_pad_numbers_are_jumpers no)
		(fp_line
			(start 0.635 0)
			(end -0.635 0)
			(stroke
				(width 0.508)
				(type default)
			)
			(layer "F.SilkS")
		)
		(fp_rect
			(start -0.9652 1.778)
			(end 0.9652 -1.778)
			(stroke
				(width 0)
				(type default)
			)
			(fill no)
			(layer "F.CrtYd")
		)
		(fp_poly
			(pts
				(xy -0.9652 -1.778) (xy 0.9652 -1.778) (xy 0.9652 1.778) (xy -0.9652 1.778)
			)
			(stroke
				(width 0)
				(type default)
			)
			(fill no)
			(layer "F.Fab")
		)
		(pad "1" smd rect
			(at 0 -0.9652)
			(size 1.397 1.143)
			(layers "F.Cu" "F.Mask" "F.Paste")
			(net "P12V_HDD3")
		)
		(pad "2" smd rect
			(at 0 0.9652)
			(size 1.397 1.143)
			(layers "F.Cu" "F.Mask" "F.Paste")
			(net "GND")
		)
	)
	(footprint ""
		(layer "F.Cu")
		(at 396.7226 -40.5892 -90)
		(property "Reference" "R807"
			(at 0 0 270)
			(layer "F.SilkS")
			(hide yes)
			(effects
				(font
					(size 1.27 1.27)
				)
			)
		)
		(property "Value" "2R6F-GP"
			(at -0.0508 -4.8514 270)
			(unlocked yes)
			(layer "F.Fab")
			(hide yes)
			(effects
				(font
					(size 1.016 1.016)
					(thickness 0.1524)
				)
			)
		)
		(property "Device Type" "R1206H26"
			(at 0 -6.3754 270)
			(unlocked yes)
			(layer "F.Fab")
			(hide yes)
			(effects
				(font
					(size 1.016 1.016)
					(thickness 0.1524)
				)
			)
		)
		(duplicate_pad_numbers_are_jumpers no)
		(fp_line
			(start -1.016 2.2352)
			(end -1.016 -2.2352)
			(stroke
				(width 0.1524)
				(type default)
			)
			(layer "F.SilkS")
		)
		(fp_line
			(start 1.016 2.2352)
			(end -1.016 2.2352)
			(stroke
				(width 0.1524)
				(type default)
			)
			(layer "F.SilkS")
		)
		(fp_line
			(start -1.016 -2.2352)
			(end 1.016 -2.2352)
			(stroke
				(width 0.1524)
				(type default)
			)
			(layer "F.SilkS")
		)
		(fp_line
			(start 1.016 -2.2352)
			(end 1.016 2.2352)
			(stroke
				(width 0.1524)
				(type default)
			)
			(layer "F.SilkS")
		)
		(fp_rect
			(start -1.0922 2.3114)
			(end 1.0922 -2.3114)
			(stroke
				(width 0)
				(type default)
			)
			(fill no)
			(layer "F.CrtYd")
		)
		(fp_poly
			(pts
				(xy -1.0922 -2.3114) (xy 1.0922 -2.3114) (xy 1.0922 2.3114) (xy -1.0922 2.3114)
			)
			(stroke
				(width 0)
				(type default)
			)
			(fill no)
			(layer "F.Fab")
		)
		(pad "1" smd rect
			(at 0 -1.397 270)
			(size 1.651 1.27)
			(layers "F.Cu" "F.Mask" "F.Paste")
			(net "P12V_HDD32")
		)
		(pad "2" smd rect
			(at 0 1.397 270)
			(size 1.651 1.27)
			(layers "F.Cu" "F.Mask" "F.Paste")
			(net "12V_PRE_32")
		)
	)
	(footprint ""
		(layer "F.Cu")
		(at 158.663386 -14.660626 90)
		(property "Reference" "C393"
			(at 0 0 90)
			(layer "F.SilkS")
			(hide yes)
			(effects
				(font
					(size 1.27 1.27)
				)
			)
		)
		(property "Value" "SCD01U16V1KX-GP"
			(at -2.8321 -1.7399 90)
			(unlocked yes)
			(layer "F.Fab")
			(hide yes)
			(effects
				(font
					(size 1.016 1.016)
					(thickness 0.1524)
				)
			)
		)
		(property "Device Type" "C0201H13"
			(at -2.8321 -3.2639 90)
			(unlocked yes)
			(layer "F.Fab")
			(hide yes)
			(effects
				(font
					(size 1.016 1.016)
					(thickness 0.1524)
				)
			)
		)
		(duplicate_pad_numbers_are_jumpers no)
		(fp_rect
			(start -0.2794 0.6477)
			(end 0.2794 -0.6477)
			(stroke
				(width 0)
				(type default)
			)
			(fill no)
			(layer "F.CrtYd")
		)
		(fp_rect
			(start -0.2794 0.6477)
			(end 0.2794 -0.6477)
			(stroke
				(width 0)
				(type default)
			)
			(fill no)
			(layer "F.Fab")
		)
		(pad "1" smd custom
			(at 0 -0.2794 90)
			(size 0.0762 0.0762)
			(layers "F.Cu" "F.Mask" "F.Paste")
			(net "SAS_HDD_RX_P28")
			(options
				(clearance outline)
				(anchor circle)
			)
			(primitives
				(gr_poly
					(pts
						(arc
							(start 0.1524 -0.127)
							(mid 0.137521 -0.162921)
							(end 0.1016 -0.1778)
						)
						(arc
							(start -0.1016 -0.1778)
							(mid -0.137521 -0.162921)
							(end -0.1524 -0.127)
						)
						(arc
							(start -0.1524 0.127)
							(mid -0.137521 0.162921)
							(end -0.1016 0.1778)
						)
						(arc
							(start 0.1016 0.1778)
							(mid 0.137521 0.162921)
							(end 0.1524 0.127)
						)
					)
					(width 0)
					(fill yes)
				)
			)
		)
		(pad "2" smd custom
			(at 0 0.2794 90)
			(size 0.0762 0.0762)
			(layers "F.Cu" "F.Mask" "F.Paste")
			(net "PHY_SCC_B_TO_DRV_B_28_DP")
			(options
				(clearance outline)
				(anchor circle)
			)
			(primitives
				(gr_poly
					(pts
						(arc
							(start 0.1524 -0.127)
							(mid 0.137521 -0.162921)
							(end 0.1016 -0.1778)
						)
						(arc
							(start -0.1016 -0.1778)
							(mid -0.137521 -0.162921)
							(end -0.1524 -0.127)
						)
						(arc
							(start -0.1524 0.127)
							(mid -0.137521 0.162921)
							(end -0.1016 0.1778)
						)
						(arc
							(start 0.1016 0.1778)
							(mid 0.137521 0.162921)
							(end 0.1524 0.127)
						)
					)
					(width 0)
					(fill yes)
				)
			)
		)
	)
	(footprint ""
		(layer "F.Cu")
		(at 64.013334 -130.21945 90)
		(property "Reference" "C197"
			(at 0 0 90)
			(layer "F.SilkS")
			(hide yes)
			(effects
				(font
					(size 1.27 1.27)
				)
			)
		)
		(property "Value" "SCD01U16V1KX-GP"
			(at -2.8321 -1.7399 90)
			(unlocked yes)
			(layer "F.Fab")
			(hide yes)
			(effects
				(font
					(size 1.016 1.016)
					(thickness 0.1524)
				)
			)
		)
		(property "Device Type" "C0201H13"
			(at -2.8321 -3.2639 90)
			(unlocked yes)
			(layer "F.Fab")
			(hide yes)
			(effects
				(font
					(size 1.016 1.016)
					(thickness 0.1524)
				)
			)
		)
		(duplicate_pad_numbers_are_jumpers no)
		(fp_rect
			(start -0.2794 0.6477)
			(end 0.2794 -0.6477)
			(stroke
				(width 0)
				(type default)
			)
			(fill no)
			(layer "F.CrtYd")
		)
		(fp_rect
			(start -0.2794 0.6477)
			(end 0.2794 -0.6477)
			(stroke
				(width 0)
				(type default)
			)
			(fill no)
			(layer "F.Fab")
		)
		(pad "1" smd custom
			(at 0 -0.2794 90)
			(size 0.0762 0.0762)
			(layers "F.Cu" "F.Mask" "F.Paste")
			(net "SAS_HDD_RX_N13")
			(options
				(clearance outline)
				(anchor circle)
			)
			(primitives
				(gr_poly
					(pts
						(arc
							(start 0.1524 -0.127)
							(mid 0.137521 -0.162921)
							(end 0.1016 -0.1778)
						)
						(arc
							(start -0.1016 -0.1778)
							(mid -0.137521 -0.162921)
							(end -0.1524 -0.127)
						)
						(arc
							(start -0.1524 0.127)
							(mid -0.137521 0.162921)
							(end -0.1016 0.1778)
						)
						(arc
							(start 0.1016 0.1778)
							(mid 0.137521 0.162921)
							(end 0.1524 0.127)
						)
					)
					(width 0)
					(fill yes)
				)
			)
		)
		(pad "2" smd custom
			(at 0 0.2794 90)
			(size 0.0762 0.0762)
			(layers "F.Cu" "F.Mask" "F.Paste")
			(net "PHY_SCC_B_TO_DRV_B_13_DN")
			(options
				(clearance outline)
				(anchor circle)
			)
			(primitives
				(gr_poly
					(pts
						(arc
							(start 0.1524 -0.127)
							(mid 0.137521 -0.162921)
							(end 0.1016 -0.1778)
						)
						(arc
							(start -0.1016 -0.1778)
							(mid -0.137521 -0.162921)
							(end -0.1524 -0.127)
						)
						(arc
							(start -0.1524 0.127)
							(mid -0.137521 0.162921)
							(end -0.1016 0.1778)
						)
						(arc
							(start 0.1016 0.1778)
							(mid 0.137521 0.162921)
							(end 0.1524 0.127)
						)
					)
					(width 0)
					(fill yes)
				)
			)
		)
	)
	(footprint ""
		(layer "F.Cu")
		(at 20.701 -256.286 180)
		(property "Reference" "Q189"
			(at 0 0 180)
			(layer "F.SilkS")
			(hide yes)
			(effects
				(font
					(size 1.27 1.27)
				)
			)
		)
		(property "Value" "AO4406AL-GP"
			(at -3.707384 -1.5367 180)
			(unlocked yes)
			(layer "F.Fab")
			(hide yes)
			(effects
				(font
					(size 1.016 1.016)
					(thickness 0.1524)
				)
			)
		)
		(property "Device Type" "SOIC8H69"
			(at -3.707384 -3.0607 180)
			(unlocked yes)
			(layer "F.Fab")
			(hide yes)
			(effects
				(font
					(size 1.016 1.016)
					(thickness 0.1524)
				)
			)
		)
		(duplicate_pad_numbers_are_jumpers no)
		(fp_line
			(start 2.1336 1.4224)
			(end 2.1336 -1.4224)
			(stroke
				(width 0.1524)
				(type default)
			)
			(layer "F.SilkS")
		)
		(fp_line
			(start 2.1336 -1.4224)
			(end -2.7432 -1.4224)
			(stroke
				(width 0.1524)
				(type default)
			)
			(layer "F.SilkS")
		)
		(fp_line
			(start -2.1844 -0.0508)
			(end -2.7178 0.508)
			(stroke
				(width 0.1524)
				(type default)
			)
			(layer "F.SilkS")
		)
		(fp_line
			(start -2.6289 3.4417)
			(end -2.6289 1.4732)
			(stroke
				(width 0.381)
				(type default)
			)
			(layer "F.SilkS")
		)
		(fp_line
			(start -2.7178 -0.508)
			(end -2.1844 -0.0508)
			(stroke
				(width 0.1524)
				(type default)
			)
			(layer "F.SilkS")
		)
		(fp_line
			(start -2.7432 1.4224)
			(end 2.1336 1.4224)
			(stroke
				(width 0.1524)
				(type default)
			)
			(layer "F.SilkS")
		)
		(fp_line
			(start -2.7432 1.4224)
			(end -2.6416 1.4224)
			(stroke
				(width 0.1524)
				(type default)
			)
			(layer "F.SilkS")
		)
		(fp_line
			(start -2.7432 -1.4224)
			(end -2.7432 1.4224)
			(stroke
				(width 0.1524)
				(type default)
			)
			(layer "F.SilkS")
		)
		(fp_poly
			(pts
				(xy -2.2098 -1.4224) (xy -2.2098 1.4224) (xy 2.2098 1.4224) (xy 2.2098 -1.4224)
			)
			(stroke
				(width 0)
				(type default)
			)
			(fill yes)
			(layer "F.SilkS")
		)
		(fp_rect
			(start -2.450084 2.999994)
			(end 2.450084 -2.999994)
			(stroke
				(width 0)
				(type default)
			)
			(fill no)
			(layer "F.CrtYd")
		)
		(fp_poly
			(pts
				(xy -2.8194 3.6322) (xy -2.8194 -3.6322) (xy 2.8194 -3.6322) (xy 2.8194 1.18364) (xy 2.450084 1.18364)
				(xy 2.450084 -2.999994) (xy -2.450084 -2.999994) (xy -2.450084 2.999994) (xy 2.450084 2.999994)
				(xy 2.450084 1.18618) (xy 2.8194 1.18618) (xy 2.8194 3.6322)
			)
			(stroke
				(width 0)
				(type default)
			)
			(fill no)
			(layer "F.CrtYd")
		)
		(fp_rect
			(start -2.8194 3.6322)
			(end 2.8194 -3.6322)
			(stroke
				(width 0)
				(type default)
			)
			(fill no)
			(layer "F.Fab")
		)
		(pad "1" smd rect
			(at -1.905 2.54 180)
			(size 0.635 1.651)
			(layers "F.Cu" "F.Mask" "F.Paste")
			(net "P5V_HDD0")
		)
		(pad "2" smd rect
			(at -0.635 2.54 180)
			(size 0.635 1.651)
			(layers "F.Cu" "F.Mask" "F.Paste")
			(net "P5V_HDD0")
		)
		(pad "3" smd rect
			(at 0.635 2.54 180)
			(size 0.635 1.651)
			(layers "F.Cu" "F.Mask" "F.Paste")
			(net "P5V_HDD0")
		)
		(pad "4" smd rect
			(at 1.905 2.54 180)
			(size 0.635 1.651)
			(layers "F.Cu" "F.Mask" "F.Paste")
			(net "SW_HDD_P0")
		)
		(pad "5" smd rect
			(at 1.905 -2.54 180)
			(size 0.635 1.651)
			(layers "F.Cu" "F.Mask" "F.Paste")
			(net "P5V_B_1")
		)
		(pad "6" smd rect
			(at 0.635 -2.54 180)
			(size 0.635 1.651)
			(layers "F.Cu" "F.Mask" "F.Paste")
			(net "P5V_B_1")
		)
		(pad "7" smd rect
			(at -0.635 -2.54 180)
			(size 0.635 1.651)
			(layers "F.Cu" "F.Mask" "F.Paste")
			(net "P5V_B_1")
		)
		(pad "8" smd rect
			(at -1.905 -2.54 180)
			(size 0.635 1.651)
			(layers "F.Cu" "F.Mask" "F.Paste")
			(net "P5V_B_1")
		)
	)
	(footprint ""
		(layer "F.Cu")
		(at 424.434 -160.401 180)
		(property "Reference" "C309"
			(at 0 0 180)
			(layer "F.SilkS")
			(hide yes)
			(effects
				(font
					(size 1.27 1.27)
				)
			)
		)
		(property "Value" "SC1U25V3KX-GP"
			(at 0 -2.8194 180)
			(unlocked yes)
			(layer "F.Fab")
			(hide yes)
			(effects
				(font
					(size 1.016 1.016)
					(thickness 0.1524)
				)
			)
		)
		(property "Device Type" "C603H36"
			(at 0 -4.3434 180)
			(unlocked yes)
			(layer "F.Fab")
			(hide yes)
			(effects
				(font
					(size 1.016 1.016)
					(thickness 0.1524)
				)
			)
		)
		(duplicate_pad_numbers_are_jumpers no)
		(fp_line
			(start 0.508 0)
			(end -0.508 0)
			(stroke
				(width 0.2032)
				(type default)
			)
			(layer "F.SilkS")
		)
		(fp_rect
			(start -0.5842 1.3335)
			(end 0.5842 -1.3335)
			(stroke
				(width 0)
				(type default)
			)
			(fill no)
			(layer "F.CrtYd")
		)
		(fp_rect
			(start -0.5842 1.3335)
			(end 0.5842 -1.3335)
			(stroke
				(width 0)
				(type default)
			)
			(fill no)
			(layer "F.Fab")
		)
		(pad "1" smd custom
			(at 0 -0.762 180)
			(size 0.2159 0.2159)
			(layers "F.Cu" "F.Mask" "F.Paste")
			(net "P12V_HDD21")
			(options
				(clearance outline)
				(anchor circle)
			)
			(primitives
				(gr_poly
					(pts
						(arc
							(start -0.3302 -0.4318)
							(mid -0.402042 -0.402042)
							(end -0.4318 -0.3302)
						)
						(arc
							(start -0.4318 0.3302)
							(mid -0.402042 0.402042)
							(end -0.3302 0.4318)
						)
						(arc
							(start 0.3302 0.4318)
							(mid 0.402042 0.402042)
							(end 0.4318 0.3302)
						)
						(arc
							(start 0.4318 -0.3302)
							(mid 0.402042 -0.402042)
							(end 0.3302 -0.4318)
						)
					)
					(width 0)
					(fill yes)
				)
			)
		)
		(pad "2" smd custom
			(at 0 0.762 180)
			(size 0.2159 0.2159)
			(layers "F.Cu" "F.Mask" "F.Paste")
			(net "GND")
			(options
				(clearance outline)
				(anchor circle)
			)
			(primitives
				(gr_poly
					(pts
						(arc
							(start -0.3302 -0.4318)
							(mid -0.402042 -0.402042)
							(end -0.4318 -0.3302)
						)
						(arc
							(start -0.4318 0.3302)
							(mid -0.402042 0.402042)
							(end -0.3302 0.4318)
						)
						(arc
							(start 0.3302 0.4318)
							(mid 0.402042 0.402042)
							(end 0.4318 0.3302)
						)
						(arc
							(start 0.4318 -0.3302)
							(mid 0.402042 -0.402042)
							(end 0.3302 -0.4318)
						)
					)
					(width 0)
					(fill yes)
				)
			)
		)
	)
	(footprint ""
		(layer "F.Cu")
		(at 301.371 -226.7204 -90)
		(property "Reference" "R7"
			(at 0 0 270)
			(layer "F.SilkS")
			(hide yes)
			(effects
				(font
					(size 1.27 1.27)
				)
			)
		)
		(property "Value" "10KR2F-2-GP"
			(at 0.064008 -3.993896 270)
			(unlocked yes)
			(layer "F.Fab")
			(hide yes)
			(effects
				(font
					(size 1.016 1.016)
					(thickness 0.1524)
				)
			)
		)
		(property "Device Type" "R402H16"
			(at 0.064008 -5.517896 270)
			(unlocked yes)
			(layer "F.Fab")
			(hide yes)
			(effects
				(font
					(size 1.016 1.016)
					(thickness 0.1524)
				)
			)
		)
		(duplicate_pad_numbers_are_jumpers no)
		(fp_line
			(start -0.508 -0.9398)
			(end -0.508 0.9398)
			(stroke
				(width 0.1524)
				(type default)
			)
			(layer "F.SilkS")
		)
		(fp_line
			(start 0.508 -0.9398)
			(end -0.508 -0.9398)
			(stroke
				(width 0.1524)
				(type default)
			)
			(layer "F.SilkS")
		)
		(fp_rect
			(start -0.508 0.9398)
			(end 0.508 -0.9398)
			(stroke
				(width 0)
				(type default)
			)
			(fill no)
			(layer "F.CrtYd")
		)
		(fp_rect
			(start -0.508 0.9398)
			(end 0.508 -0.9398)
			(stroke
				(width 0)
				(type default)
			)
			(fill no)
			(layer "F.Fab")
		)
		(pad "1" smd custom
			(at 0 -0.4445 270)
			(size 0.1397 0.1397)
			(layers "F.Cu" "F.Mask" "F.Paste")
			(net "P3V3_STBY_B")
			(options
				(clearance outline)
				(anchor circle)
			)
			(primitives
				(gr_poly
					(pts
						(arc
							(start -0.1778 -0.2794)
							(mid -0.249642 -0.249642)
							(end -0.2794 -0.1778)
						)
						(arc
							(start -0.2794 0.1778)
							(mid -0.249642 0.249642)
							(end -0.1778 0.2794)
						)
						(arc
							(start 0.1778 0.2794)
							(mid 0.249642 0.249642)
							(end 0.2794 0.1778)
						)
						(arc
							(start 0.2794 -0.1778)
							(mid 0.249642 -0.249642)
							(end 0.1778 -0.2794)
						)
					)
					(width 0)
					(fill yes)
				)
			)
		)
		(pad "2" smd custom
			(at 0 0.4445 270)
			(size 0.1397 0.1397)
			(layers "F.Cu" "F.Mask" "F.Paste")
			(net "SCC_B_TYPE_3")
			(options
				(clearance outline)
				(anchor circle)
			)
			(primitives
				(gr_poly
					(pts
						(arc
							(start -0.1778 -0.2794)
							(mid -0.249642 -0.249642)
							(end -0.2794 -0.1778)
						)
						(arc
							(start -0.2794 0.1778)
							(mid -0.249642 0.249642)
							(end -0.1778 0.2794)
						)
						(arc
							(start 0.1778 0.2794)
							(mid 0.249642 0.249642)
							(end 0.2794 0.1778)
						)
						(arc
							(start 0.2794 -0.1778)
							(mid 0.249642 -0.249642)
							(end 0.1778 -0.2794)
						)
					)
					(width 0)
					(fill yes)
				)
			)
		)
	)
	(footprint ""
		(layer "F.Cu")
		(at 248.285 -311.15 -90)
		(property "Reference" "R1086"
			(at 0 0 270)
			(layer "F.SilkS")
			(hide yes)
			(effects
				(font
					(size 1.27 1.27)
				)
			)
		)
		(property "Value" "4K7R2F-GP"
			(at 0.064008 -3.993896 270)
			(unlocked yes)
			(layer "F.Fab")
			(hide yes)
			(effects
				(font
					(size 1.016 1.016)
					(thickness 0.1524)
				)
			)
		)
		(property "Device Type" "R402H16"
			(at 0.064008 -5.517896 270)
			(unlocked yes)
			(layer "F.Fab")
			(hide yes)
			(effects
				(font
					(size 1.016 1.016)
					(thickness 0.1524)
				)
			)
		)
		(duplicate_pad_numbers_are_jumpers no)
		(fp_line
			(start -0.508 -0.9398)
			(end -0.508 0.9398)
			(stroke
				(width 0.1524)
				(type default)
			)
			(layer "F.SilkS")
		)
		(fp_line
			(start 0.508 -0.9398)
			(end -0.508 -0.9398)
			(stroke
				(width 0.1524)
				(type default)
			)
			(layer "F.SilkS")
		)
		(fp_rect
			(start -0.508 0.9398)
			(end 0.508 -0.9398)
			(stroke
				(width 0)
				(type default)
			)
			(fill no)
			(layer "F.CrtYd")
		)
		(fp_rect
			(start -0.508 0.9398)
			(end 0.508 -0.9398)
			(stroke
				(width 0)
				(type default)
			)
			(fill no)
			(layer "F.Fab")
		)
		(pad "1" smd custom
			(at 0 -0.4445 270)
			(size 0.1397 0.1397)
			(layers "F.Cu" "F.Mask" "F.Paste")
			(net "P3V3_STBY_A")
			(options
				(clearance outline)
				(anchor circle)
			)
			(primitives
				(gr_poly
					(pts
						(arc
							(start -0.1778 -0.2794)
							(mid -0.249642 -0.249642)
							(end -0.2794 -0.1778)
						)
						(arc
							(start -0.2794 0.1778)
							(mid -0.249642 0.249642)
							(end -0.1778 0.2794)
						)
						(arc
							(start 0.1778 0.2794)
							(mid 0.249642 0.249642)
							(end 0.2794 0.1778)
						)
						(arc
							(start 0.2794 -0.1778)
							(mid 0.249642 -0.249642)
							(end 0.1778 -0.2794)
						)
					)
					(width 0)
					(fill yes)
				)
			)
		)
		(pad "2" smd custom
			(at 0 0.4445 270)
			(size 0.1397 0.1397)
			(layers "F.Cu" "F.Mask" "F.Paste")
			(net "MAX31790_A_FULL_SPEED")
			(options
				(clearance outline)
				(anchor circle)
			)
			(primitives
				(gr_poly
					(pts
						(arc
							(start -0.1778 -0.2794)
							(mid -0.249642 -0.249642)
							(end -0.2794 -0.1778)
						)
						(arc
							(start -0.2794 0.1778)
							(mid -0.249642 0.249642)
							(end -0.1778 0.2794)
						)
						(arc
							(start 0.1778 0.2794)
							(mid 0.249642 0.249642)
							(end 0.2794 0.1778)
						)
						(arc
							(start 0.2794 -0.1778)
							(mid 0.249642 -0.249642)
							(end 0.1778 -0.2794)
						)
					)
					(width 0)
					(fill yes)
				)
			)
		)
	)
	(footprint ""
		(layer "F.Cu")
		(at 143.129 -17.653 180)
		(property "Reference" "D28"
			(at 0 0 180)
			(layer "F.SilkS")
			(hide yes)
			(effects
				(font
					(size 1.27 1.27)
				)
			)
		)
		(property "Value" "RB551V30-GP"
			(at 0 -6.7818 180)
			(unlocked yes)
			(layer "F.Fab")
			(hide yes)
			(effects
				(font
					(size 1.016 1.016)
					(thickness 0.1524)
				)
			)
		)
		(property "Device Type" "SOD323AKH38"
			(at 0 -8.6868 180)
			(unlocked yes)
			(layer "F.Fab")
			(hide yes)
			(effects
				(font
					(size 1.016 1.016)
					(thickness 0.1524)
				)
			)
		)
		(duplicate_pad_numbers_are_jumpers no)
		(fp_line
			(start 0.889 2.159)
			(end -0.889 2.159)
			(stroke
				(width 0.1524)
				(type default)
			)
			(layer "F.SilkS")
		)
		(fp_line
			(start 0.889 -1.9304)
			(end 0.889 2.159)
			(stroke
				(width 0.1524)
				(type default)
			)
			(layer "F.SilkS")
		)
		(fp_line
			(start 0.762 2.0574)
			(end -0.762 2.0574)
			(stroke
				(width 0.508)
				(type default)
			)
			(layer "F.SilkS")
		)
		(fp_line
			(start -0.889 2.159)
			(end -0.889 -1.9304)
			(stroke
				(width 0.1524)
				(type default)
			)
			(layer "F.SilkS")
		)
		(fp_line
			(start -0.889 -1.9304)
			(end 0.889 -1.9304)
			(stroke
				(width 0.1524)
				(type default)
			)
			(layer "F.SilkS")
		)
		(fp_rect
			(start -1.016 2.3114)
			(end 1.016 -2.0066)
			(stroke
				(width 0)
				(type default)
			)
			(fill no)
			(layer "F.CrtYd")
		)
		(fp_poly
			(pts
				(xy -1.016 -2.0066) (xy 1.016 -2.0066) (xy 1.016 2.3114) (xy -1.016 2.3114)
			)
			(stroke
				(width 0)
				(type default)
			)
			(fill no)
			(layer "F.Fab")
		)
		(pad "A" smd rect
			(at 0 -1.143 180)
			(size 0.5588 1.016)
			(layers "F.Cu" "F.Mask" "F.Paste")
			(net "SW_HDD_R28")
		)
		(pad "K" smd rect
			(at 0 1.143 180)
			(size 0.5588 1.016)
			(layers "F.Cu" "F.Mask" "F.Paste")
			(net "SW_HDD_N28")
		)
	)
	(footprint ""
		(layer "F.Cu")
		(at 264.2997 -375.999756 90)
		(property "Reference" "R1062"
			(at 0 0 90)
			(layer "F.SilkS")
			(hide yes)
			(effects
				(font
					(size 1.27 1.27)
				)
			)
		)
		(property "Value" "4K7R3J-2-GP"
			(at -0.0254 -2.5146 90)
			(unlocked yes)
			(layer "F.Fab")
			(hide yes)
			(effects
				(font
					(size 1.016 1.016)
					(thickness 0.1524)
				)
			)
		)
		(property "Device Type" "R603H22"
			(at -0.0254 -4.0386 90)
			(unlocked yes)
			(layer "F.Fab")
			(hide yes)
			(effects
				(font
					(size 1.016 1.016)
					(thickness 0.1524)
				)
			)
		)
		(duplicate_pad_numbers_are_jumpers no)
		(fp_line
			(start 0.2032 0)
			(end 0.4826 0)
			(stroke
				(width 0.2032)
				(type default)
			)
			(layer "F.SilkS")
		)
		(fp_line
			(start -0.4826 0)
			(end -0.2032 0)
			(stroke
				(width 0.2032)
				(type default)
			)
			(layer "F.SilkS")
		)
		(fp_rect
			(start -0.5842 1.3335)
			(end 0.5842 -1.3335)
			(stroke
				(width 0)
				(type default)
			)
			(fill no)
			(layer "F.CrtYd")
		)
		(fp_rect
			(start -0.5842 1.3335)
			(end 0.5842 -1.3335)
			(stroke
				(width 0)
				(type default)
			)
			(fill no)
			(layer "F.Fab")
		)
		(pad "1" smd custom
			(at 0 -0.762 90)
			(size 0.2159 0.2159)
			(layers "F.Cu" "F.Mask" "F.Paste")
			(net "P3V3_IN")
			(options
				(clearance outline)
				(anchor circle)
			)
			(primitives
				(gr_poly
					(pts
						(arc
							(start -0.3302 -0.4318)
							(mid -0.402042 -0.402042)
							(end -0.4318 -0.3302)
						)
						(arc
							(start -0.4318 0.3302)
							(mid -0.402042 0.402042)
							(end -0.3302 0.4318)
						)
						(arc
							(start 0.3302 0.4318)
							(mid 0.402042 0.402042)
							(end 0.4318 0.3302)
						)
						(arc
							(start 0.4318 -0.3302)
							(mid 0.402042 -0.402042)
							(end 0.3302 -0.4318)
						)
					)
					(width 0)
					(fill yes)
				)
			)
		)
		(pad "2" smd custom
			(at 0 0.762 90)
			(size 0.2159 0.2159)
			(layers "F.Cu" "F.Mask" "F.Paste")
			(net "IR_SWITCH_C")
			(options
				(clearance outline)
				(anchor circle)
			)
			(primitives
				(gr_poly
					(pts
						(arc
							(start -0.3302 -0.4318)
							(mid -0.402042 -0.402042)
							(end -0.4318 -0.3302)
						)
						(arc
							(start -0.4318 0.3302)
							(mid -0.402042 0.402042)
							(end -0.3302 0.4318)
						)
						(arc
							(start 0.3302 0.4318)
							(mid 0.402042 0.402042)
							(end 0.4318 0.3302)
						)
						(arc
							(start 0.4318 -0.3302)
							(mid 0.402042 -0.402042)
							(end 0.3302 -0.4318)
						)
					)
					(width 0)
					(fill yes)
				)
			)
		)
	)
	(footprint ""
		(layer "F.Cu")
		(at 49.349914 -65.39992)
		(property "Reference" "LED14"
			(at 0 0 0)
			(layer "F.SilkS")
			(hide yes)
			(effects
				(font
					(size 1.27 1.27)
				)
			)
		)
		(property "Value" "LED-BY-19-GP"
			(at -2.132076 1.414018 0)
			(unlocked yes)
			(layer "F.Fab")
			(hide yes)
			(effects
				(font
					(size 1.016 1.016)
					(thickness 0.1524)
				)
			)
		)
		(property "Device Type" "LED-1615-4PH26"
			(at -2.132076 -0.109982 0)
			(unlocked yes)
			(layer "F.Fab")
			(hide yes)
			(effects
				(font
					(size 1.016 1.016)
					(thickness 0.1524)
				)
			)
		)
		(duplicate_pad_numbers_are_jumpers no)
		(fp_line
			(start -1.2954 0.254)
			(end -1.2954 1.6002)
			(stroke
				(width 0.508)
				(type default)
			)
			(layer "F.SilkS")
		)
		(fp_line
			(start -1.2954 1.6002)
			(end 1.2954 1.6002)
			(stroke
				(width 0.508)
				(type default)
			)
			(layer "F.SilkS")
		)
		(fp_line
			(start -1.1176 -1.4224)
			(end 1.1176 -1.4224)
			(stroke
				(width 0.1524)
				(type default)
			)
			(layer "F.SilkS")
		)
		(fp_line
			(start -1.1176 1.4224)
			(end -1.1176 -1.4224)
			(stroke
				(width 0.1524)
				(type default)
			)
			(layer "F.SilkS")
		)
		(fp_line
			(start 1.1176 -1.4224)
			(end 1.1176 1.4224)
			(stroke
				(width 0.1524)
				(type default)
			)
			(layer "F.SilkS")
		)
		(fp_line
			(start 1.1176 1.4224)
			(end -1.1176 1.4224)
			(stroke
				(width 0.1524)
				(type default)
			)
			(layer "F.SilkS")
		)
		(fp_line
			(start 1.2954 1.6002)
			(end 1.2954 0.254)
			(stroke
				(width 0.508)
				(type default)
			)
			(layer "F.SilkS")
		)
		(fp_rect
			(start -0.7493 0.8001)
			(end 0.7493 -0.8001)
			(stroke
				(width 0)
				(type default)
			)
			(fill no)
			(layer "F.CrtYd")
		)
		(fp_poly
			(pts
				(xy -1.3716 1.6764) (xy -1.3716 -1.6764) (xy 1.3716 -1.6764) (xy 1.3716 0.0635) (xy 0.7493 0.0635)
				(xy 0.7493 -0.8001) (xy -0.7493 -0.8001) (xy -0.7493 0.8001) (xy 0.7493 0.8001) (xy 0.7493 0.0762)
				(xy 1.3716 0.0762) (xy 1.3716 1.6764)
			)
			(stroke
				(width 0)
				(type default)
			)
			(fill no)
			(layer "F.CrtYd")
		)
		(fp_rect
			(start -1.3716 1.6764)
			(end 1.3716 -1.6764)
			(stroke
				(width 0)
				(type default)
			)
			(fill no)
			(layer "F.Fab")
		)
		(pad "1" smd rect
			(at 0.50038 -0.73025)
			(size 0.7112 0.8636)
			(layers "F.Cu" "F.Mask" "F.Paste")
			(net "DRV_ACT_13")
		)
		(pad "2" smd rect
			(at -0.50038 -0.73025)
			(size 0.7112 0.8636)
			(layers "F.Cu" "F.Mask" "F.Paste")
			(net "FLT_HDD13")
		)
		(pad "3" smd rect
			(at 0.50038 0.73025)
			(size 0.7112 0.8636)
			(layers "F.Cu" "F.Mask" "F.Paste")
			(net "DRV_ACT_13_N")
		)
		(pad "4" smd rect
			(at -0.50038 0.73025)
			(size 0.7112 0.8636)
			(layers "F.Cu" "F.Mask" "F.Paste")
			(net "FLT_HDD13_N")
		)
	)
	(footprint ""
		(layer "F.Cu")
		(at 240.687098 -132.685028)
		(property "Reference" "R420"
			(at 0 0 0)
			(layer "F.SilkS")
			(hide yes)
			(effects
				(font
					(size 1.27 1.27)
				)
			)
		)
		(property "Value" "0R2J-2-GP"
			(at 0.064008 -3.993896 0)
			(unlocked yes)
			(layer "F.Fab")
			(hide yes)
			(effects
				(font
					(size 1.016 1.016)
					(thickness 0.1524)
				)
			)
		)
		(property "Device Type" "R402H16"
			(at 0.064008 -5.517896 0)
			(unlocked yes)
			(layer "F.Fab")
			(hide yes)
			(effects
				(font
					(size 1.016 1.016)
					(thickness 0.1524)
				)
			)
		)
		(duplicate_pad_numbers_are_jumpers no)
		(fp_line
			(start -0.508 -0.9398)
			(end -0.508 0.9398)
			(stroke
				(width 0.1524)
				(type default)
			)
			(layer "F.SilkS")
		)
		(fp_line
			(start 0.508 -0.9398)
			(end -0.508 -0.9398)
			(stroke
				(width 0.1524)
				(type default)
			)
			(layer "F.SilkS")
		)
		(fp_rect
			(start -0.508 0.9398)
			(end 0.508 -0.9398)
			(stroke
				(width 0)
				(type default)
			)
			(fill no)
			(layer "F.CrtYd")
		)
		(fp_rect
			(start -0.508 0.9398)
			(end 0.508 -0.9398)
			(stroke
				(width 0)
				(type default)
			)
			(fill no)
			(layer "F.Fab")
		)
		(pad "1" smd custom
			(at 0 -0.4445)
			(size 0.1397 0.1397)
			(layers "F.Cu" "F.Mask" "F.Paste")
			(net "I2C_DPB_B_SCL_BUF")
			(options
				(clearance outline)
				(anchor circle)
			)
			(primitives
				(gr_poly
					(pts
						(arc
							(start -0.1778 -0.2794)
							(mid -0.249642 -0.249642)
							(end -0.2794 -0.1778)
						)
						(arc
							(start -0.2794 0.1778)
							(mid -0.249642 0.249642)
							(end -0.1778 0.2794)
						)
						(arc
							(start 0.1778 0.2794)
							(mid 0.249642 0.249642)
							(end 0.2794 0.1778)
						)
						(arc
							(start 0.2794 -0.1778)
							(mid 0.249642 -0.249642)
							(end 0.1778 -0.2794)
						)
					)
					(width 0)
					(fill yes)
				)
			)
		)
		(pad "2" smd custom
			(at 0 0.4445)
			(size 0.1397 0.1397)
			(layers "F.Cu" "F.Mask" "F.Paste")
			(net "I2C_DPB_B_SCL")
			(options
				(clearance outline)
				(anchor circle)
			)
			(primitives
				(gr_poly
					(pts
						(arc
							(start -0.1778 -0.2794)
							(mid -0.249642 -0.249642)
							(end -0.2794 -0.1778)
						)
						(arc
							(start -0.2794 0.1778)
							(mid -0.249642 0.249642)
							(end -0.1778 0.2794)
						)
						(arc
							(start 0.1778 0.2794)
							(mid 0.249642 0.249642)
							(end 0.2794 0.1778)
						)
						(arc
							(start 0.2794 -0.1778)
							(mid 0.249642 -0.249642)
							(end 0.1778 -0.2794)
						)
					)
					(width 0)
					(fill yes)
				)
			)
		)
	)
	(footprint ""
		(layer "F.Cu")
		(at 479.384614 -130.21945 -90)
		(property "Reference" "C327"
			(at 0 0 270)
			(layer "F.SilkS")
			(hide yes)
			(effects
				(font
					(size 1.27 1.27)
				)
			)
		)
		(property "Value" "SCD01U16V1KX-GP"
			(at -2.8321 -1.7399 270)
			(unlocked yes)
			(layer "F.Fab")
			(hide yes)
			(effects
				(font
					(size 1.016 1.016)
					(thickness 0.1524)
				)
			)
		)
		(property "Device Type" "C0201H13"
			(at -2.8321 -3.2639 270)
			(unlocked yes)
			(layer "F.Fab")
			(hide yes)
			(effects
				(font
					(size 1.016 1.016)
					(thickness 0.1524)
				)
			)
		)
		(duplicate_pad_numbers_are_jumpers no)
		(fp_rect
			(start -0.2794 0.6477)
			(end 0.2794 -0.6477)
			(stroke
				(width 0)
				(type default)
			)
			(fill no)
			(layer "F.CrtYd")
		)
		(fp_rect
			(start -0.2794 0.6477)
			(end 0.2794 -0.6477)
			(stroke
				(width 0)
				(type default)
			)
			(fill no)
			(layer "F.Fab")
		)
		(pad "1" smd custom
			(at 0 -0.2794 270)
			(size 0.0762 0.0762)
			(layers "F.Cu" "F.Mask" "F.Paste")
			(net "SAS_HDD_RX_N23")
			(options
				(clearance outline)
				(anchor circle)
			)
			(primitives
				(gr_poly
					(pts
						(arc
							(start 0.1524 -0.127)
							(mid 0.137521 -0.162921)
							(end 0.1016 -0.1778)
						)
						(arc
							(start -0.1016 -0.1778)
							(mid -0.137521 -0.162921)
							(end -0.1524 -0.127)
						)
						(arc
							(start -0.1524 0.127)
							(mid -0.137521 0.162921)
							(end -0.1016 0.1778)
						)
						(arc
							(start 0.1016 0.1778)
							(mid 0.137521 0.162921)
							(end 0.1524 0.127)
						)
					)
					(width 0)
					(fill yes)
				)
			)
		)
		(pad "2" smd custom
			(at 0 0.2794 270)
			(size 0.0762 0.0762)
			(layers "F.Cu" "F.Mask" "F.Paste")
			(net "PHY_SCC_B_TO_DRV_B_23_DN")
			(options
				(clearance outline)
				(anchor circle)
			)
			(primitives
				(gr_poly
					(pts
						(arc
							(start 0.1524 -0.127)
							(mid 0.137521 -0.162921)
							(end 0.1016 -0.1778)
						)
						(arc
							(start -0.1016 -0.1778)
							(mid -0.137521 -0.162921)
							(end -0.1524 -0.127)
						)
						(arc
							(start -0.1524 0.127)
							(mid -0.137521 0.162921)
							(end -0.1016 0.1778)
						)
						(arc
							(start 0.1016 0.1778)
							(mid 0.137521 0.162921)
							(end 0.1524 0.127)
						)
					)
					(width 0)
					(fill yes)
				)
			)
		)
	)
	(footprint ""
		(layer "F.Cu")
		(at 334.899 -253.873 -90)
		(property "Reference" "Q22"
			(at 0 0 270)
			(layer "F.SilkS")
			(hide yes)
			(effects
				(font
					(size 1.27 1.27)
				)
			)
		)
		(property "Value" "AO4406AL-GP"
			(at -3.707384 -1.5367 270)
			(unlocked yes)
			(layer "F.Fab")
			(hide yes)
			(effects
				(font
					(size 1.016 1.016)
					(thickness 0.1524)
				)
			)
		)
		(property "Device Type" "SOIC8H69"
			(at -3.707384 -3.0607 270)
			(unlocked yes)
			(layer "F.Fab")
			(hide yes)
			(effects
				(font
					(size 1.016 1.016)
					(thickness 0.1524)
				)
			)
		)
		(duplicate_pad_numbers_are_jumpers no)
		(fp_line
			(start -2.6289 3.4417)
			(end -2.6289 1.4732)
			(stroke
				(width 0.381)
				(type default)
			)
			(layer "F.SilkS")
		)
		(fp_line
			(start -2.7432 1.4224)
			(end -2.6416 1.4224)
			(stroke
				(width 0.1524)
				(type default)
			)
			(layer "F.SilkS")
		)
		(fp_line
			(start -2.7432 1.4224)
			(end 2.1336 1.4224)
			(stroke
				(width 0.1524)
				(type default)
			)
			(layer "F.SilkS")
		)
		(fp_line
			(start 2.1336 1.4224)
			(end 2.1336 -1.4224)
			(stroke
				(width 0.1524)
				(type default)
			)
			(layer "F.SilkS")
		)
		(fp_line
			(start -2.1844 -0.0508)
			(end -2.7178 0.508)
			(stroke
				(width 0.1524)
				(type default)
			)
			(layer "F.SilkS")
		)
		(fp_line
			(start -2.7178 -0.508)
			(end -2.1844 -0.0508)
			(stroke
				(width 0.1524)
				(type default)
			)
			(layer "F.SilkS")
		)
		(fp_line
			(start -2.7432 -1.4224)
			(end -2.7432 1.4224)
			(stroke
				(width 0.1524)
				(type default)
			)
			(layer "F.SilkS")
		)
		(fp_line
			(start 2.1336 -1.4224)
			(end -2.7432 -1.4224)
			(stroke
				(width 0.1524)
				(type default)
			)
			(layer "F.SilkS")
		)
		(fp_poly
			(pts
				(xy -2.2098 -1.4224) (xy -2.2098 1.4224) (xy 2.2098 1.4224) (xy 2.2098 -1.4224)
			)
			(stroke
				(width 0)
				(type default)
			)
			(fill yes)
			(layer "F.SilkS")
		)
		(fp_rect
			(start -2.450084 2.999994)
			(end 2.450084 -2.999994)
			(stroke
				(width 0)
				(type default)
			)
			(fill no)
			(layer "F.CrtYd")
		)
		(fp_poly
			(pts
				(xy -2.8194 3.6322) (xy -2.8194 -3.6322) (xy 2.8194 -3.6322) (xy 2.8194 1.18364) (xy 2.450084 1.18364)
				(xy 2.450084 -2.999994) (xy -2.450084 -2.999994) (xy -2.450084 2.999994) (xy 2.450084 2.999994)
				(xy 2.450084 1.18618) (xy 2.8194 1.18618) (xy 2.8194 3.6322)
			)
			(stroke
				(width 0)
				(type default)
			)
			(fill no)
			(layer "F.CrtYd")
		)
		(fp_rect
			(start -2.8194 3.6322)
			(end 2.8194 -3.6322)
			(stroke
				(width 0)
				(type default)
			)
			(fill no)
			(layer "F.Fab")
		)
		(pad "1" smd rect
			(at -1.905 2.54 270)
			(size 0.635 1.651)
			(layers "F.Cu" "F.Mask" "F.Paste")
			(net "P5V_HDD6")
		)
		(pad "2" smd rect
			(at -0.635 2.54 270)
			(size 0.635 1.651)
			(layers "F.Cu" "F.Mask" "F.Paste")
			(net "P5V_HDD6")
		)
		(pad "3" smd rect
			(at 0.635 2.54 270)
			(size 0.635 1.651)
			(layers "F.Cu" "F.Mask" "F.Paste")
			(net "P5V_HDD6")
		)
		(pad "4" smd rect
			(at 1.905 2.54 270)
			(size 0.635 1.651)
			(layers "F.Cu" "F.Mask" "F.Paste")
			(net "SW_HDD_P6")
		)
		(pad "5" smd rect
			(at 1.905 -2.54 270)
			(size 0.635 1.651)
			(layers "F.Cu" "F.Mask" "F.Paste")
			(net "P5V_B_3")
		)
		(pad "6" smd rect
			(at 0.635 -2.54 270)
			(size 0.635 1.651)
			(layers "F.Cu" "F.Mask" "F.Paste")
			(net "P5V_B_3")
		)
		(pad "7" smd rect
			(at -0.635 -2.54 270)
			(size 0.635 1.651)
			(layers "F.Cu" "F.Mask" "F.Paste")
			(net "P5V_B_3")
		)
		(pad "8" smd rect
			(at -1.905 -2.54 270)
			(size 0.635 1.651)
			(layers "F.Cu" "F.Mask" "F.Paste")
			(net "P5V_B_3")
		)
	)
	(footprint ""
		(layer "F.Cu")
		(at 190.5 -32.131 90)
		(property "Reference" "C414"
			(at 0 0 90)
			(layer "F.SilkS")
			(hide yes)
			(effects
				(font
					(size 1.27 1.27)
				)
			)
		)
		(property "Value" "SCD01U50V2KX-1GP"
			(at 1.1811 -2.7051 90)
			(unlocked yes)
			(layer "F.Fab")
			(hide yes)
			(effects
				(font
					(size 1.016 1.016)
					(thickness 0.1524)
				)
			)
		)
		(property "Device Type" "C402H22"
			(at 1.1811 -4.2291 90)
			(unlocked yes)
			(layer "F.Fab")
			(hide yes)
			(effects
				(font
					(size 1.016 1.016)
					(thickness 0.1524)
				)
			)
		)
		(duplicate_pad_numbers_are_jumpers no)
		(fp_rect
			(start -0.4318 0.9525)
			(end 0.4318 -0.9525)
			(stroke
				(width 0)
				(type default)
			)
			(fill no)
			(layer "F.CrtYd")
		)
		(fp_rect
			(start -0.4318 0.9525)
			(end 0.4318 -0.9525)
			(stroke
				(width 0)
				(type default)
			)
			(fill no)
			(layer "F.Fab")
		)
		(pad "1" smd custom
			(at 0 -0.4445 90)
			(size 0.1524 0.1524)
			(layers "F.Cu" "F.Mask" "F.Paste")
			(net "HDD_PRSNT_29")
			(options
				(clearance outline)
				(anchor circle)
			)
			(primitives
				(gr_poly
					(pts
						(arc
							(start 0.3048 -0.2032)
							(mid 0.275042 -0.275042)
							(end 0.2032 -0.3048)
						)
						(arc
							(start -0.2032 -0.3048)
							(mid -0.275042 -0.275042)
							(end -0.3048 -0.2032)
						)
						(arc
							(start -0.3048 0.2032)
							(mid -0.275042 0.275042)
							(end -0.2032 0.3048)
						)
						(arc
							(start 0.2032 0.3048)
							(mid 0.275042 0.275042)
							(end 0.3048 0.2032)
						)
					)
					(width 0)
					(fill yes)
				)
			)
		)
		(pad "2" smd custom
			(at 0 0.4445 90)
			(size 0.1524 0.1524)
			(layers "F.Cu" "F.Mask" "F.Paste")
			(net "GND")
			(options
				(clearance outline)
				(anchor circle)
			)
			(primitives
				(gr_poly
					(pts
						(arc
							(start 0.3048 -0.2032)
							(mid 0.275042 -0.275042)
							(end 0.2032 -0.3048)
						)
						(arc
							(start -0.2032 -0.3048)
							(mid -0.275042 -0.275042)
							(end -0.3048 -0.2032)
						)
						(arc
							(start -0.3048 0.2032)
							(mid -0.275042 0.275042)
							(end -0.2032 0.3048)
						)
						(arc
							(start 0.2032 0.3048)
							(mid 0.275042 0.275042)
							(end 0.3048 0.2032)
						)
					)
					(width 0)
					(fill yes)
				)
			)
		)
	)
	(footprint ""
		(layer "F.Cu")
		(at 207.3402 -197.231 -90)
		(property "Reference" "R28"
			(at 0 0 270)
			(layer "F.SilkS")
			(hide yes)
			(effects
				(font
					(size 1.27 1.27)
				)
			)
		)
		(property "Value" "4K7R2F-GP"
			(at 0.064008 -3.993896 270)
			(unlocked yes)
			(layer "F.Fab")
			(hide yes)
			(effects
				(font
					(size 1.016 1.016)
					(thickness 0.1524)
				)
			)
		)
		(property "Device Type" "R402H16"
			(at 0.064008 -5.517896 270)
			(unlocked yes)
			(layer "F.Fab")
			(hide yes)
			(effects
				(font
					(size 1.016 1.016)
					(thickness 0.1524)
				)
			)
		)
		(duplicate_pad_numbers_are_jumpers no)
		(fp_line
			(start -0.508 -0.9398)
			(end -0.508 0.9398)
			(stroke
				(width 0.1524)
				(type default)
			)
			(layer "F.SilkS")
		)
		(fp_line
			(start 0.508 -0.9398)
			(end -0.508 -0.9398)
			(stroke
				(width 0.1524)
				(type default)
			)
			(layer "F.SilkS")
		)
		(fp_rect
			(start -0.508 0.9398)
			(end 0.508 -0.9398)
			(stroke
				(width 0)
				(type default)
			)
			(fill no)
			(layer "F.CrtYd")
		)
		(fp_rect
			(start -0.508 0.9398)
			(end 0.508 -0.9398)
			(stroke
				(width 0)
				(type default)
			)
			(fill no)
			(layer "F.Fab")
		)
		(pad "1" smd custom
			(at 0 -0.4445 270)
			(size 0.1397 0.1397)
			(layers "F.Cu" "F.Mask" "F.Paste")
			(net "IO_EXP2_HDD_FAULT_A1")
			(options
				(clearance outline)
				(anchor circle)
			)
			(primitives
				(gr_poly
					(pts
						(arc
							(start -0.1778 -0.2794)
							(mid -0.249642 -0.249642)
							(end -0.2794 -0.1778)
						)
						(arc
							(start -0.2794 0.1778)
							(mid -0.249642 0.249642)
							(end -0.1778 0.2794)
						)
						(arc
							(start 0.1778 0.2794)
							(mid 0.249642 0.249642)
							(end 0.2794 0.1778)
						)
						(arc
							(start 0.2794 -0.1778)
							(mid 0.249642 -0.249642)
							(end 0.1778 -0.2794)
						)
					)
					(width 0)
					(fill yes)
				)
			)
		)
		(pad "2" smd custom
			(at 0 0.4445 270)
			(size 0.1397 0.1397)
			(layers "F.Cu" "F.Mask" "F.Paste")
			(net "GND")
			(options
				(clearance outline)
				(anchor circle)
			)
			(primitives
				(gr_poly
					(pts
						(arc
							(start -0.1778 -0.2794)
							(mid -0.249642 -0.249642)
							(end -0.2794 -0.1778)
						)
						(arc
							(start -0.2794 0.1778)
							(mid -0.249642 0.249642)
							(end -0.1778 0.2794)
						)
						(arc
							(start 0.1778 0.2794)
							(mid 0.249642 0.249642)
							(end 0.2794 0.1778)
						)
						(arc
							(start 0.2794 -0.1778)
							(mid 0.249642 -0.249642)
							(end 0.1778 -0.2794)
						)
					)
					(width 0)
					(fill yes)
				)
			)
		)
	)
	(footprint ""
		(layer "F.Cu")
		(at 83.82 -141.224 180)
		(property "Reference" "Q57"
			(at 0 0 180)
			(layer "F.SilkS")
			(hide yes)
			(effects
				(font
					(size 1.27 1.27)
				)
			)
		)
		(property "Value" "AO4406AL-GP"
			(at -3.707384 -1.5367 180)
			(unlocked yes)
			(layer "F.Fab")
			(hide yes)
			(effects
				(font
					(size 1.016 1.016)
					(thickness 0.1524)
				)
			)
		)
		(property "Device Type" "SOIC8H69"
			(at -3.707384 -3.0607 180)
			(unlocked yes)
			(layer "F.Fab")
			(hide yes)
			(effects
				(font
					(size 1.016 1.016)
					(thickness 0.1524)
				)
			)
		)
		(duplicate_pad_numbers_are_jumpers no)
		(fp_line
			(start 2.1336 1.4224)
			(end 2.1336 -1.4224)
			(stroke
				(width 0.1524)
				(type default)
			)
			(layer "F.SilkS")
		)
		(fp_line
			(start 2.1336 -1.4224)
			(end -2.7432 -1.4224)
			(stroke
				(width 0.1524)
				(type default)
			)
			(layer "F.SilkS")
		)
		(fp_line
			(start -2.1844 -0.0508)
			(end -2.7178 0.508)
			(stroke
				(width 0.1524)
				(type default)
			)
			(layer "F.SilkS")
		)
		(fp_line
			(start -2.6289 3.4417)
			(end -2.6289 1.4732)
			(stroke
				(width 0.381)
				(type default)
			)
			(layer "F.SilkS")
		)
		(fp_line
			(start -2.7178 -0.508)
			(end -2.1844 -0.0508)
			(stroke
				(width 0.1524)
				(type default)
			)
			(layer "F.SilkS")
		)
		(fp_line
			(start -2.7432 1.4224)
			(end 2.1336 1.4224)
			(stroke
				(width 0.1524)
				(type default)
			)
			(layer "F.SilkS")
		)
		(fp_line
			(start -2.7432 1.4224)
			(end -2.6416 1.4224)
			(stroke
				(width 0.1524)
				(type default)
			)
			(layer "F.SilkS")
		)
		(fp_line
			(start -2.7432 -1.4224)
			(end -2.7432 1.4224)
			(stroke
				(width 0.1524)
				(type default)
			)
			(layer "F.SilkS")
		)
		(fp_poly
			(pts
				(xy -2.2098 -1.4224) (xy -2.2098 1.4224) (xy 2.2098 1.4224) (xy 2.2098 -1.4224)
			)
			(stroke
				(width 0)
				(type default)
			)
			(fill yes)
			(layer "F.SilkS")
		)
		(fp_rect
			(start -2.450084 2.999994)
			(end 2.450084 -2.999994)
			(stroke
				(width 0)
				(type default)
			)
			(fill no)
			(layer "F.CrtYd")
		)
		(fp_poly
			(pts
				(xy -2.8194 3.6322) (xy -2.8194 -3.6322) (xy 2.8194 -3.6322) (xy 2.8194 1.18364) (xy 2.450084 1.18364)
				(xy 2.450084 -2.999994) (xy -2.450084 -2.999994) (xy -2.450084 2.999994) (xy 2.450084 2.999994)
				(xy 2.450084 1.18618) (xy 2.8194 1.18618) (xy 2.8194 3.6322)
			)
			(stroke
				(width 0)
				(type default)
			)
			(fill no)
			(layer "F.CrtYd")
		)
		(fp_rect
			(start -2.8194 3.6322)
			(end 2.8194 -3.6322)
			(stroke
				(width 0)
				(type default)
			)
			(fill no)
			(layer "F.Fab")
		)
		(pad "1" smd rect
			(at -1.905 2.54 180)
			(size 0.635 1.651)
			(layers "F.Cu" "F.Mask" "F.Paste")
			(net "P5V_HDD14")
		)
		(pad "2" smd rect
			(at -0.635 2.54 180)
			(size 0.635 1.651)
			(layers "F.Cu" "F.Mask" "F.Paste")
			(net "P5V_HDD14")
		)
		(pad "3" smd rect
			(at 0.635 2.54 180)
			(size 0.635 1.651)
			(layers "F.Cu" "F.Mask" "F.Paste")
			(net "P5V_HDD14")
		)
		(pad "4" smd rect
			(at 1.905 2.54 180)
			(size 0.635 1.651)
			(layers "F.Cu" "F.Mask" "F.Paste")
			(net "SW_HDD_P14")
		)
		(pad "5" smd rect
			(at 1.905 -2.54 180)
			(size 0.635 1.651)
			(layers "F.Cu" "F.Mask" "F.Paste")
			(net "P5V_B_1")
		)
		(pad "6" smd rect
			(at 0.635 -2.54 180)
			(size 0.635 1.651)
			(layers "F.Cu" "F.Mask" "F.Paste")
			(net "P5V_B_1")
		)
		(pad "7" smd rect
			(at -0.635 -2.54 180)
			(size 0.635 1.651)
			(layers "F.Cu" "F.Mask" "F.Paste")
			(net "P5V_B_1")
		)
		(pad "8" smd rect
			(at -1.905 -2.54 180)
			(size 0.635 1.651)
			(layers "F.Cu" "F.Mask" "F.Paste")
			(net "P5V_B_1")
		)
	)
	(footprint ""
		(layer "F.Cu")
		(at 343.993978 -102.413562 -90)
		(property "Reference" "R470"
			(at 0 0 270)
			(layer "F.SilkS")
			(hide yes)
			(effects
				(font
					(size 1.27 1.27)
				)
			)
		)
		(property "Value" "4K7R2F-GP"
			(at 0.064008 -3.993896 270)
			(unlocked yes)
			(layer "F.Fab")
			(hide yes)
			(effects
				(font
					(size 1.016 1.016)
					(thickness 0.1524)
				)
			)
		)
		(property "Device Type" "R402H16"
			(at 0.064008 -5.517896 270)
			(unlocked yes)
			(layer "F.Fab")
			(hide yes)
			(effects
				(font
					(size 1.016 1.016)
					(thickness 0.1524)
				)
			)
		)
		(duplicate_pad_numbers_are_jumpers no)
		(fp_line
			(start -0.508 -0.9398)
			(end -0.508 0.9398)
			(stroke
				(width 0.1524)
				(type default)
			)
			(layer "F.SilkS")
		)
		(fp_line
			(start 0.508 -0.9398)
			(end -0.508 -0.9398)
			(stroke
				(width 0.1524)
				(type default)
			)
			(layer "F.SilkS")
		)
		(fp_rect
			(start -0.508 0.9398)
			(end 0.508 -0.9398)
			(stroke
				(width 0)
				(type default)
			)
			(fill no)
			(layer "F.CrtYd")
		)
		(fp_rect
			(start -0.508 0.9398)
			(end 0.508 -0.9398)
			(stroke
				(width 0)
				(type default)
			)
			(fill no)
			(layer "F.Fab")
		)
		(pad "1" smd custom
			(at 0 -0.4445 270)
			(size 0.1397 0.1397)
			(layers "F.Cu" "F.Mask" "F.Paste")
			(net "DRIVE_B_19_FLT_LED")
			(options
				(clearance outline)
				(anchor circle)
			)
			(primitives
				(gr_poly
					(pts
						(arc
							(start -0.1778 -0.2794)
							(mid -0.249642 -0.249642)
							(end -0.2794 -0.1778)
						)
						(arc
							(start -0.2794 0.1778)
							(mid -0.249642 0.249642)
							(end -0.1778 0.2794)
						)
						(arc
							(start 0.1778 0.2794)
							(mid 0.249642 0.249642)
							(end 0.2794 0.1778)
						)
						(arc
							(start 0.2794 -0.1778)
							(mid 0.249642 -0.249642)
							(end 0.1778 -0.2794)
						)
					)
					(width 0)
					(fill yes)
				)
			)
		)
		(pad "2" smd custom
			(at 0 0.4445 270)
			(size 0.1397 0.1397)
			(layers "F.Cu" "F.Mask" "F.Paste")
			(net "GND")
			(options
				(clearance outline)
				(anchor circle)
			)
			(primitives
				(gr_poly
					(pts
						(arc
							(start -0.1778 -0.2794)
							(mid -0.249642 -0.249642)
							(end -0.2794 -0.1778)
						)
						(arc
							(start -0.2794 0.1778)
							(mid -0.249642 0.249642)
							(end -0.1778 0.2794)
						)
						(arc
							(start 0.1778 0.2794)
							(mid 0.249642 0.249642)
							(end 0.2794 0.1778)
						)
						(arc
							(start 0.2794 -0.1778)
							(mid 0.249642 -0.249642)
							(end 0.1778 -0.2794)
						)
					)
					(width 0)
					(fill yes)
				)
			)
		)
	)
	(footprint ""
		(layer "F.Cu")
		(at 434.939186 -116.257578 -90)
		(property "Reference" "R1169"
			(at 0 0 270)
			(layer "F.SilkS")
			(hide yes)
			(effects
				(font
					(size 1.27 1.27)
				)
			)
		)
		(property "Value" "309KR2F-GP"
			(at 0.064008 -3.993896 270)
			(unlocked yes)
			(layer "F.Fab")
			(hide yes)
			(effects
				(font
					(size 1.016 1.016)
					(thickness 0.1524)
				)
			)
		)
		(property "Device Type" "R402H16"
			(at 0.064008 -5.517896 270)
			(unlocked yes)
			(layer "F.Fab")
			(hide yes)
			(effects
				(font
					(size 1.016 1.016)
					(thickness 0.1524)
				)
			)
		)
		(duplicate_pad_numbers_are_jumpers no)
		(fp_line
			(start -0.508 -0.9398)
			(end -0.508 0.9398)
			(stroke
				(width 0.1524)
				(type default)
			)
			(layer "F.SilkS")
		)
		(fp_line
			(start 0.508 -0.9398)
			(end -0.508 -0.9398)
			(stroke
				(width 0.1524)
				(type default)
			)
			(layer "F.SilkS")
		)
		(fp_rect
			(start -0.508 0.9398)
			(end 0.508 -0.9398)
			(stroke
				(width 0)
				(type default)
			)
			(fill no)
			(layer "F.CrtYd")
		)
		(fp_rect
			(start -0.508 0.9398)
			(end 0.508 -0.9398)
			(stroke
				(width 0)
				(type default)
			)
			(fill no)
			(layer "F.Fab")
		)
		(pad "1" smd custom
			(at 0 -0.4445 270)
			(size 0.1397 0.1397)
			(layers "F.Cu" "F.Mask" "F.Paste")
			(net "P5V_B_4_RF")
			(options
				(clearance outline)
				(anchor circle)
			)
			(primitives
				(gr_poly
					(pts
						(arc
							(start -0.1778 -0.2794)
							(mid -0.249642 -0.249642)
							(end -0.2794 -0.1778)
						)
						(arc
							(start -0.2794 0.1778)
							(mid -0.249642 0.249642)
							(end -0.1778 0.2794)
						)
						(arc
							(start 0.1778 0.2794)
							(mid 0.249642 0.249642)
							(end 0.2794 0.1778)
						)
						(arc
							(start 0.2794 -0.1778)
							(mid 0.249642 -0.249642)
							(end 0.1778 -0.2794)
						)
					)
					(width 0)
					(fill yes)
				)
			)
		)
		(pad "2" smd custom
			(at 0 0.4445 270)
			(size 0.1397 0.1397)
			(layers "F.Cu" "F.Mask" "F.Paste")
			(net "P5V_B_4_VREG")
			(options
				(clearance outline)
				(anchor circle)
			)
			(primitives
				(gr_poly
					(pts
						(arc
							(start -0.1778 -0.2794)
							(mid -0.249642 -0.249642)
							(end -0.2794 -0.1778)
						)
						(arc
							(start -0.2794 0.1778)
							(mid -0.249642 0.249642)
							(end -0.1778 0.2794)
						)
						(arc
							(start 0.1778 0.2794)
							(mid 0.249642 0.249642)
							(end 0.2794 0.1778)
						)
						(arc
							(start 0.2794 -0.1778)
							(mid 0.249642 -0.249642)
							(end 0.1778 -0.2794)
						)
					)
					(width 0)
					(fill yes)
				)
			)
		)
	)
	(footprint ""
		(layer "F.Cu")
		(at 281.559 -340.18601 180)
		(property "Reference" "U48"
			(at 0 0 180)
			(layer "F.SilkS")
			(hide yes)
			(effects
				(font
					(size 1.27 1.27)
				)
			)
		)
		(property "Value" "RT9077-33GJ5-GP"
			(at 0 -5.1308 180)
			(unlocked yes)
			(layer "F.Fab")
			(hide yes)
			(effects
				(font
					(size 1.016 1.016)
					(thickness 0.1524)
				)
			)
		)
		(property "Device Type" "SOT-23-5H40"
			(at 0 -6.7564 180)
			(unlocked yes)
			(layer "F.Fab")
			(hide yes)
			(effects
				(font
					(size 1.016 1.016)
					(thickness 0.1524)
				)
			)
		)
		(duplicate_pad_numbers_are_jumpers no)
		(fp_line
			(start 1.778 2.286)
			(end 1.778 -2.286)
			(stroke
				(width 0.1524)
				(type default)
			)
			(layer "F.SilkS")
		)
		(fp_line
			(start 1.778 -2.286)
			(end -1.778 -2.286)
			(stroke
				(width 0.1524)
				(type default)
			)
			(layer "F.SilkS")
		)
		(fp_line
			(start -0.254 2.286)
			(end 1.778 2.286)
			(stroke
				(width 0.1524)
				(type default)
			)
			(layer "F.SilkS")
		)
		(fp_line
			(start -0.7112 2.2352)
			(end -1.7272 2.2352)
			(stroke
				(width 0.3302)
				(type default)
			)
			(layer "F.SilkS")
		)
		(fp_line
			(start -1.7272 2.2352)
			(end -1.7272 0.762)
			(stroke
				(width 0.3302)
				(type default)
			)
			(layer "F.SilkS")
		)
		(fp_line
			(start -1.778 2.286)
			(end 1.778 2.286)
			(stroke
				(width 0.1524)
				(type default)
			)
			(layer "F.SilkS")
		)
		(fp_line
			(start -1.778 2.286)
			(end -0.254 2.286)
			(stroke
				(width 0.1524)
				(type default)
			)
			(layer "F.SilkS")
		)
		(fp_line
			(start -1.778 -2.286)
			(end -1.778 2.286)
			(stroke
				(width 0.1524)
				(type default)
			)
			(layer "F.SilkS")
		)
		(fp_poly
			(pts
				(xy -0.9652 2.4384) (xy -1.3208 2.794) (xy -0.6096 2.794)
			)
			(stroke
				(width 0)
				(type default)
			)
			(fill yes)
			(layer "F.SilkS")
		)
		(fp_rect
			(start -1.778 2.286)
			(end 1.778 -2.286)
			(stroke
				(width 0)
				(type default)
			)
			(fill no)
			(layer "F.CrtYd")
		)
		(fp_rect
			(start -1.778 2.286)
			(end 1.778 -2.286)
			(stroke
				(width 0)
				(type default)
			)
			(fill no)
			(layer "F.Fab")
		)
		(pad "1" smd rect
			(at -0.94996 1.143 180)
			(size 0.508 1.524)
			(layers "F.Cu" "F.Mask" "F.Paste")
			(net "P12V_IN")
		)
		(pad "2" smd rect
			(at 0 1.143 180)
			(size 0.508 1.524)
			(layers "F.Cu" "F.Mask" "F.Paste")
			(net "GND")
		)
		(pad "3" smd rect
			(at 0.94996 1.143 180)
			(size 0.508 1.524)
			(layers "F.Cu" "F.Mask" "F.Paste")
			(net "P3V3_IN_EN")
		)
		(pad "4" smd rect
			(at 0.94996 -1.143 180)
			(size 0.508 1.524)
			(layers "F.Cu" "F.Mask" "F.Paste")
			(net "Net_22")
		)
		(pad "5" smd rect
			(at -0.94996 -1.143 180)
			(size 0.508 1.524)
			(layers "F.Cu" "F.Mask" "F.Paste")
			(net "P3V3_IN")
		)
	)
	(footprint ""
		(layer "F.Cu")
		(at 96.324928 -178.799998)
		(property "Reference" ""
			(at 0 0 0)
			(layer "F.SilkS")
			(hide yes)
			(effects
				(font
					(size 1.27 1.27)
				)
			)
		)
		(property "Value" "*"
			(at -8.398764 -8.057642 0)
			(unlocked yes)
			(layer "F.Fab")
			(hide yes)
			(effects
				(font
					(size 1.016 1.016)
					(thickness 0.1524)
				)
			)
		)
		(duplicate_pad_numbers_are_jumpers no)
		(fp_poly
			(pts
				(arc
					(start 7.3152 0)
					(mid 0 7.3152)
					(end -7.3152 0)
				)
				(arc
					(start -7.3152 -5.9944)
					(mid 0 -13.3096)
					(end 7.3152 -5.9944)
				)
			)
			(stroke
				(width 0)
				(type default)
			)
			(fill no)
			(layer "B.CrtYd")
		)
		(fp_poly
			(pts
				(arc
					(start 7.3152 0)
					(mid 0 7.3152)
					(end -7.3152 0)
				)
				(arc
					(start -7.3152 -5.9944)
					(mid 0 -13.3096)
					(end 7.3152 -5.9944)
				)
			)
			(stroke
				(width 0)
				(type default)
			)
			(fill no)
			(layer "F.CrtYd")
		)
		(fp_poly
			(pts
				(arc
					(start 7.3152 0)
					(mid 0 7.3152)
					(end -7.3152 0)
				)
				(arc
					(start -7.3152 -5.9944)
					(mid 0 -13.3096)
					(end 7.3152 -5.9944)
				)
			)
			(stroke
				(width 0)
				(type default)
			)
			(fill no)
			(layer "B.Fab")
		)
		(fp_poly
			(pts
				(arc
					(start 7.3152 0)
					(mid 0 7.3152)
					(end -7.3152 0)
				)
				(arc
					(start -7.3152 -5.9944)
					(mid 0 -13.3096)
					(end 7.3152 -5.9944)
				)
			)
			(stroke
				(width 0)
				(type default)
			)
			(fill no)
			(layer "F.Fab")
		)
		(pad "1" thru_hole oval
			(at 0 0)
			(size 14.0208 20.0152)
			(drill 0.0254
				(offset 0 -2.9972)
			)
			(layers "*.Cu" "*.Mask")
			(remove_unused_layers no)
			(net "Net_46")
			(clearance -1.002284)
			(thermal_gap 0.1524)
			(padstack
				(mode front_inner_back)
				(layer "Inner"
					(shape custom)
					(size 2.928012 2.928012)
					(options
						(anchor circle)
					)
					(primitives
						(gr_poly
							(pts
								(arc
									(start 4.571746 -2.084324)
									(mid 0.000333 7.430372)
									(end -4.571492 -2.084324)
								)
								(arc
									(start -4.571492 -2.084324)
									(mid -3.570296 -3.611977)
									(end -2.875026 -5.30098)
								)
								(arc
									(start -2.875026 -5.30098)
									(mid 0.000217 -7.43089)
									(end 2.87528 -5.30098)
								)
								(arc
									(start 2.87528 -5.30098)
									(mid 3.570511 -3.611956)
									(end 4.571746 -2.084324)
								)
							)
							(width 0)
							(fill yes)
						)
					)
					(clearance 0.1524)
				)
				(layer "B.Cu"
					(shape oval)
					(size 14.0208 20.0152)
					(offset 0 -2.9972)
					(clearance -1.002284)
				)
			)
		)
		(zone
			(layers "F.Cu" "B.Cu" "In1.Cu" "In2.Cu" "In3.Cu" "In4.Cu" "In5.Cu" "In6.Cu")
			(hatch none 0.5)
			(connect_pads
				(clearance 0)
			)
			(min_thickness 0.25)
			(keepout
				(tracks not_allowed)
				(vias allowed)
				(pads allowed)
				(copperpour not_allowed)
				(footprints allowed)
			)
			(placement
				(enabled no)
				(sheetname "")
			)
			(fill
				(thermal_gap 0.5)
				(thermal_bridge_width 0.5)
				(island_removal_mode 0)
			)
			(polygon
				(pts
					(arc
						(start 89.314528 -184.794398)
						(mid 96.324928 -191.804798)
						(end 103.335328 -184.794398)
					)
					(arc
						(start 103.335328 -178.799998)
						(mid 96.324928 -171.789598)
						(end 89.314528 -178.799998)
					)
				)
			)
		)
	)
	(footprint ""
		(layer "F.Cu")
		(at 130.4544 -32.8422 180)
		(property "Reference" "R695"
			(at 0 0 180)
			(layer "F.SilkS")
			(hide yes)
			(effects
				(font
					(size 1.27 1.27)
				)
			)
		)
		(property "Value" "220R3F-1-GP"
			(at -0.0254 -2.5146 180)
			(unlocked yes)
			(layer "F.Fab")
			(hide yes)
			(effects
				(font
					(size 1.016 1.016)
					(thickness 0.1524)
				)
			)
		)
		(property "Device Type" "R603H22"
			(at -0.0254 -4.0386 180)
			(unlocked yes)
			(layer "F.Fab")
			(hide yes)
			(effects
				(font
					(size 1.016 1.016)
					(thickness 0.1524)
				)
			)
		)
		(duplicate_pad_numbers_are_jumpers no)
		(fp_line
			(start 0.2032 0)
			(end 0.4826 0)
			(stroke
				(width 0.2032)
				(type default)
			)
			(layer "F.SilkS")
		)
		(fp_line
			(start -0.4826 0)
			(end -0.2032 0)
			(stroke
				(width 0.2032)
				(type default)
			)
			(layer "F.SilkS")
		)
		(fp_rect
			(start -0.5842 1.3335)
			(end 0.5842 -1.3335)
			(stroke
				(width 0)
				(type default)
			)
			(fill no)
			(layer "F.CrtYd")
		)
		(fp_rect
			(start -0.5842 1.3335)
			(end 0.5842 -1.3335)
			(stroke
				(width 0)
				(type default)
			)
			(fill no)
			(layer "F.Fab")
		)
		(pad "1" smd custom
			(at 0 -0.762 180)
			(size 0.2159 0.2159)
			(layers "F.Cu" "F.Mask" "F.Paste")
			(net "HDD_PRSNT_27")
			(options
				(clearance outline)
				(anchor circle)
			)
			(primitives
				(gr_poly
					(pts
						(arc
							(start -0.3302 -0.4318)
							(mid -0.402042 -0.402042)
							(end -0.4318 -0.3302)
						)
						(arc
							(start -0.4318 0.3302)
							(mid -0.402042 0.402042)
							(end -0.3302 0.4318)
						)
						(arc
							(start 0.3302 0.4318)
							(mid 0.402042 0.402042)
							(end 0.4318 0.3302)
						)
						(arc
							(start 0.4318 -0.3302)
							(mid 0.402042 -0.402042)
							(end 0.3302 -0.4318)
						)
					)
					(width 0)
					(fill yes)
				)
			)
		)
		(pad "2" smd custom
			(at 0 0.762 180)
			(size 0.2159 0.2159)
			(layers "F.Cu" "F.Mask" "F.Paste")
			(net "DRIVE_B_27_INS")
			(options
				(clearance outline)
				(anchor circle)
			)
			(primitives
				(gr_poly
					(pts
						(arc
							(start -0.3302 -0.4318)
							(mid -0.402042 -0.402042)
							(end -0.4318 -0.3302)
						)
						(arc
							(start -0.4318 0.3302)
							(mid -0.402042 0.402042)
							(end -0.3302 0.4318)
						)
						(arc
							(start 0.3302 0.4318)
							(mid 0.402042 0.402042)
							(end 0.4318 0.3302)
						)
						(arc
							(start 0.4318 -0.3302)
							(mid 0.402042 -0.402042)
							(end 0.3302 -0.4318)
						)
					)
					(width 0)
					(fill yes)
				)
			)
		)
	)
	(footprint ""
		(layer "F.Cu")
		(at 113.03 -214.249)
		(property "Reference" "R252"
			(at 0 0 0)
			(layer "F.SilkS")
			(hide yes)
			(effects
				(font
					(size 1.27 1.27)
				)
			)
		)
		(property "Value" "91R3F-1-GP"
			(at -0.0254 -2.5146 0)
			(unlocked yes)
			(layer "F.Fab")
			(hide yes)
			(effects
				(font
					(size 1.016 1.016)
					(thickness 0.1524)
				)
			)
		)
		(property "Device Type" "R603H22"
			(at -0.0254 -4.0386 0)
			(unlocked yes)
			(layer "F.Fab")
			(hide yes)
			(effects
				(font
					(size 1.016 1.016)
					(thickness 0.1524)
				)
			)
		)
		(duplicate_pad_numbers_are_jumpers no)
		(fp_line
			(start -0.4826 0)
			(end -0.2032 0)
			(stroke
				(width 0.2032)
				(type default)
			)
			(layer "F.SilkS")
		)
		(fp_line
			(start 0.2032 0)
			(end 0.4826 0)
			(stroke
				(width 0.2032)
				(type default)
			)
			(layer "F.SilkS")
		)
		(fp_rect
			(start -0.5842 1.3335)
			(end 0.5842 -1.3335)
			(stroke
				(width 0)
				(type default)
			)
			(fill no)
			(layer "F.CrtYd")
		)
		(fp_rect
			(start -0.5842 1.3335)
			(end 0.5842 -1.3335)
			(stroke
				(width 0)
				(type default)
			)
			(fill no)
			(layer "F.Fab")
		)
		(pad "1" smd custom
			(at 0 -0.762)
			(size 0.2159 0.2159)
			(layers "F.Cu" "F.Mask" "F.Paste")
			(net "P5V_B_1")
			(options
				(clearance outline)
				(anchor circle)
			)
			(primitives
				(gr_poly
					(pts
						(arc
							(start -0.3302 -0.4318)
							(mid -0.402042 -0.402042)
							(end -0.4318 -0.3302)
						)
						(arc
							(start -0.4318 0.3302)
							(mid -0.402042 0.402042)
							(end -0.3302 0.4318)
						)
						(arc
							(start 0.3302 0.4318)
							(mid 0.402042 0.402042)
							(end 0.4318 0.3302)
						)
						(arc
							(start 0.4318 -0.3302)
							(mid 0.402042 -0.402042)
							(end 0.3302 -0.4318)
						)
					)
					(width 0)
					(fill yes)
				)
			)
		)
		(pad "2" smd custom
			(at 0 0.762)
			(size 0.2159 0.2159)
			(layers "F.Cu" "F.Mask" "F.Paste")
			(net "DRV_ACT_3")
			(options
				(clearance outline)
				(anchor circle)
			)
			(primitives
				(gr_poly
					(pts
						(arc
							(start -0.3302 -0.4318)
							(mid -0.402042 -0.402042)
							(end -0.4318 -0.3302)
						)
						(arc
							(start -0.4318 0.3302)
							(mid -0.402042 0.402042)
							(end -0.3302 0.4318)
						)
						(arc
							(start 0.3302 0.4318)
							(mid 0.402042 0.402042)
							(end 0.4318 0.3302)
						)
						(arc
							(start 0.4318 -0.3302)
							(mid 0.402042 -0.402042)
							(end 0.3302 -0.4318)
						)
					)
					(width 0)
					(fill yes)
				)
			)
		)
	)
	(footprint ""
		(layer "F.Cu")
		(at 303.586896 -231.732074 90)
		(property "Reference" "R920"
			(at 0 0 90)
			(layer "F.SilkS")
			(hide yes)
			(effects
				(font
					(size 1.27 1.27)
				)
			)
		)
		(property "Value" "4K7R2F-GP"
			(at 0.064008 -3.993896 90)
			(unlocked yes)
			(layer "F.Fab")
			(hide yes)
			(effects
				(font
					(size 1.016 1.016)
					(thickness 0.1524)
				)
			)
		)
		(property "Device Type" "R402H16"
			(at 0.064008 -5.517896 90)
			(unlocked yes)
			(layer "F.Fab")
			(hide yes)
			(effects
				(font
					(size 1.016 1.016)
					(thickness 0.1524)
				)
			)
		)
		(duplicate_pad_numbers_are_jumpers no)
		(fp_line
			(start 0.508 -0.9398)
			(end -0.508 -0.9398)
			(stroke
				(width 0.1524)
				(type default)
			)
			(layer "F.SilkS")
		)
		(fp_line
			(start -0.508 -0.9398)
			(end -0.508 0.9398)
			(stroke
				(width 0.1524)
				(type default)
			)
			(layer "F.SilkS")
		)
		(fp_rect
			(start -0.508 0.9398)
			(end 0.508 -0.9398)
			(stroke
				(width 0)
				(type default)
			)
			(fill no)
			(layer "F.CrtYd")
		)
		(fp_rect
			(start -0.508 0.9398)
			(end 0.508 -0.9398)
			(stroke
				(width 0)
				(type default)
			)
			(fill no)
			(layer "F.Fab")
		)
		(pad "1" smd custom
			(at 0 -0.4445 90)
			(size 0.1397 0.1397)
			(layers "F.Cu" "F.Mask" "F.Paste")
			(net "SCC_B_SLOT_ID_0")
			(options
				(clearance outline)
				(anchor circle)
			)
			(primitives
				(gr_poly
					(pts
						(arc
							(start -0.1778 -0.2794)
							(mid -0.249642 -0.249642)
							(end -0.2794 -0.1778)
						)
						(arc
							(start -0.2794 0.1778)
							(mid -0.249642 0.249642)
							(end -0.1778 0.2794)
						)
						(arc
							(start 0.1778 0.2794)
							(mid 0.249642 0.249642)
							(end 0.2794 0.1778)
						)
						(arc
							(start 0.2794 -0.1778)
							(mid 0.249642 -0.249642)
							(end 0.1778 -0.2794)
						)
					)
					(width 0)
					(fill yes)
				)
			)
		)
		(pad "2" smd custom
			(at 0 0.4445 90)
			(size 0.1397 0.1397)
			(layers "F.Cu" "F.Mask" "F.Paste")
			(net "GND")
			(options
				(clearance outline)
				(anchor circle)
			)
			(primitives
				(gr_poly
					(pts
						(arc
							(start -0.1778 -0.2794)
							(mid -0.249642 -0.249642)
							(end -0.2794 -0.1778)
						)
						(arc
							(start -0.2794 0.1778)
							(mid -0.249642 0.249642)
							(end -0.1778 0.2794)
						)
						(arc
							(start 0.1778 0.2794)
							(mid 0.249642 0.249642)
							(end 0.2794 0.1778)
						)
						(arc
							(start 0.2794 -0.1778)
							(mid 0.249642 -0.249642)
							(end 0.1778 -0.2794)
						)
					)
					(width 0)
					(fill yes)
				)
			)
		)
	)
	(footprint ""
		(layer "F.Cu")
		(at 231.267 -197.612 -90)
		(property "Reference" "R77"
			(at 0 0 270)
			(layer "F.SilkS")
			(hide yes)
			(effects
				(font
					(size 1.27 1.27)
				)
			)
		)
		(property "Value" "4K7R2F-GP"
			(at 0.064008 -3.993896 270)
			(unlocked yes)
			(layer "F.Fab")
			(hide yes)
			(effects
				(font
					(size 1.016 1.016)
					(thickness 0.1524)
				)
			)
		)
		(property "Device Type" "R402H16"
			(at 0.064008 -5.517896 270)
			(unlocked yes)
			(layer "F.Fab")
			(hide yes)
			(effects
				(font
					(size 1.016 1.016)
					(thickness 0.1524)
				)
			)
		)
		(duplicate_pad_numbers_are_jumpers no)
		(fp_line
			(start -0.508 -0.9398)
			(end -0.508 0.9398)
			(stroke
				(width 0.1524)
				(type default)
			)
			(layer "F.SilkS")
		)
		(fp_line
			(start 0.508 -0.9398)
			(end -0.508 -0.9398)
			(stroke
				(width 0.1524)
				(type default)
			)
			(layer "F.SilkS")
		)
		(fp_rect
			(start -0.508 0.9398)
			(end 0.508 -0.9398)
			(stroke
				(width 0)
				(type default)
			)
			(fill no)
			(layer "F.CrtYd")
		)
		(fp_rect
			(start -0.508 0.9398)
			(end 0.508 -0.9398)
			(stroke
				(width 0)
				(type default)
			)
			(fill no)
			(layer "F.Fab")
		)
		(pad "1" smd custom
			(at 0 -0.4445 270)
			(size 0.1397 0.1397)
			(layers "F.Cu" "F.Mask" "F.Paste")
			(net "IO_EXP2_A0")
			(options
				(clearance outline)
				(anchor circle)
			)
			(primitives
				(gr_poly
					(pts
						(arc
							(start -0.1778 -0.2794)
							(mid -0.249642 -0.249642)
							(end -0.2794 -0.1778)
						)
						(arc
							(start -0.2794 0.1778)
							(mid -0.249642 0.249642)
							(end -0.1778 0.2794)
						)
						(arc
							(start 0.1778 0.2794)
							(mid 0.249642 0.249642)
							(end 0.2794 0.1778)
						)
						(arc
							(start 0.2794 -0.1778)
							(mid 0.249642 -0.249642)
							(end 0.1778 -0.2794)
						)
					)
					(width 0)
					(fill yes)
				)
			)
		)
		(pad "2" smd custom
			(at 0 0.4445 270)
			(size 0.1397 0.1397)
			(layers "F.Cu" "F.Mask" "F.Paste")
			(net "GND")
			(options
				(clearance outline)
				(anchor circle)
			)
			(primitives
				(gr_poly
					(pts
						(arc
							(start -0.1778 -0.2794)
							(mid -0.249642 -0.249642)
							(end -0.2794 -0.1778)
						)
						(arc
							(start -0.2794 0.1778)
							(mid -0.249642 0.249642)
							(end -0.1778 0.2794)
						)
						(arc
							(start 0.1778 0.2794)
							(mid 0.249642 0.249642)
							(end 0.2794 0.1778)
						)
						(arc
							(start 0.2794 -0.1778)
							(mid 0.249642 -0.249642)
							(end 0.1778 -0.2794)
						)
					)
					(width 0)
					(fill yes)
				)
			)
		)
	)
	(footprint ""
		(layer "F.Cu")
		(at 150.79472 -215.011 180)
		(property "Reference" "Q223"
			(at 0 0 180)
			(layer "F.SilkS")
			(hide yes)
			(effects
				(font
					(size 1.27 1.27)
				)
			)
		)
		(property "Value" "2N7002K-2-GP"
			(at 0.127 -8.9662 180)
			(unlocked yes)
			(layer "F.Fab")
			(hide yes)
			(effects
				(font
					(size 1.016 1.016)
					(thickness 0.1524)
				)
			)
		)
		(property "Device Type" "SOT23DGS2D4H44"
			(at 0.127 -10.4902 180)
			(unlocked yes)
			(layer "F.Fab")
			(hide yes)
			(effects
				(font
					(size 1.016 1.016)
					(thickness 0.1524)
				)
			)
		)
		(duplicate_pad_numbers_are_jumpers no)
		(fp_line
			(start 1.651 1.778)
			(end 1.651 -1.778)
			(stroke
				(width 0.1524)
				(type default)
			)
			(layer "F.SilkS")
		)
		(fp_line
			(start 1.651 -1.778)
			(end -1.651 -1.778)
			(stroke
				(width 0.1524)
				(type default)
			)
			(layer "F.SilkS")
		)
		(fp_line
			(start -1.651 1.778)
			(end 1.651 1.778)
			(stroke
				(width 0.1524)
				(type default)
			)
			(layer "F.SilkS")
		)
		(fp_line
			(start -1.651 -1.778)
			(end -1.651 1.778)
			(stroke
				(width 0.1524)
				(type default)
			)
			(layer "F.SilkS")
		)
		(fp_poly
			(pts
				(xy -1.778 1.8796) (xy -1.778 -1.8796) (xy 1.778 -1.8796) (xy 1.778 1.8796)
			)
			(stroke
				(width 0)
				(type default)
			)
			(fill no)
			(layer "F.CrtYd")
		)
		(fp_poly
			(pts
				(xy -1.778 1.8796) (xy -1.778 -1.8796) (xy 1.778 -1.8796) (xy 1.778 1.8796)
			)
			(stroke
				(width 0)
				(type default)
			)
			(fill no)
			(layer "F.Fab")
		)
		(pad "D" smd custom
			(at 0 -0.9525 180)
			(size 0.1905 0.1905)
			(layers "F.Cu" "F.Mask" "F.Paste")
			(net "FLT_HDD4_N")
			(options
				(clearance outline)
				(anchor circle)
			)
			(primitives
				(gr_poly
					(pts
						(arc
							(start -0.1778 0.5715)
							(mid -0.321484 0.511984)
							(end -0.381 0.3683)
						)
						(arc
							(start -0.381 -0.3683)
							(mid -0.321484 -0.511984)
							(end -0.1778 -0.5715)
						)
						(arc
							(start 0.1778 -0.5715)
							(mid 0.321484 -0.511984)
							(end 0.381 -0.3683)
						)
						(arc
							(start 0.381 0.3683)
							(mid 0.321484 0.511984)
							(end 0.1778 0.5715)
						)
					)
					(width 0)
					(fill yes)
				)
			)
		)
		(pad "G" smd custom
			(at -0.98425 0.9525 180)
			(size 0.1905 0.1905)
			(layers "F.Cu" "F.Mask" "F.Paste")
			(net "DRIVE_B_4_FLT_LED")
			(options
				(clearance outline)
				(anchor circle)
			)
			(primitives
				(gr_poly
					(pts
						(arc
							(start -0.1778 0.5715)
							(mid -0.321484 0.511984)
							(end -0.381 0.3683)
						)
						(arc
							(start -0.381 -0.3683)
							(mid -0.321484 -0.511984)
							(end -0.1778 -0.5715)
						)
						(arc
							(start 0.1778 -0.5715)
							(mid 0.321484 -0.511984)
							(end 0.381 -0.3683)
						)
						(arc
							(start 0.381 0.3683)
							(mid 0.321484 0.511984)
							(end 0.1778 0.5715)
						)
					)
					(width 0)
					(fill yes)
				)
			)
		)
		(pad "S" smd custom
			(at 0.98425 0.9525 180)
			(size 0.1905 0.1905)
			(layers "F.Cu" "F.Mask" "F.Paste")
			(net "GND")
			(options
				(clearance outline)
				(anchor circle)
			)
			(primitives
				(gr_poly
					(pts
						(arc
							(start -0.1778 0.5715)
							(mid -0.321484 0.511984)
							(end -0.381 0.3683)
						)
						(arc
							(start -0.381 -0.3683)
							(mid -0.321484 -0.511984)
							(end -0.1778 -0.5715)
						)
						(arc
							(start 0.1778 -0.5715)
							(mid 0.321484 -0.511984)
							(end 0.381 -0.3683)
						)
						(arc
							(start 0.381 0.3683)
							(mid 0.321484 0.511984)
							(end 0.1778 0.5715)
						)
					)
					(width 0)
					(fill yes)
				)
			)
		)
	)
	(footprint ""
		(layer "F.Cu")
		(at 467.499954 -13.999972)
		(property "Reference" ""
			(at 0 0 0)
			(layer "F.SilkS")
			(hide yes)
			(effects
				(font
					(size 1.27 1.27)
				)
			)
		)
		(property "Value" "*"
			(at -6.3373 -0.4572 0)
			(unlocked yes)
			(layer "F.Fab")
			(hide yes)
			(effects
				(font
					(size 1.016 1.016)
					(thickness 0.1524)
				)
			)
		)
		(duplicate_pad_numbers_are_jumpers no)
		(fp_poly
			(pts
				(arc
					(start 5.0673 0)
					(mid -5.0673 0)
					(end 5.0673 0)
				)
			)
			(stroke
				(width 0)
				(type default)
			)
			(fill no)
			(layer "B.CrtYd")
		)
		(fp_poly
			(pts
				(arc
					(start 5.0673 0)
					(mid -5.0673 0)
					(end 5.0673 0)
				)
			)
			(stroke
				(width 0)
				(type default)
			)
			(fill no)
			(layer "F.CrtYd")
		)
		(fp_poly
			(pts
				(arc
					(start 5.0673 0)
					(mid -5.0673 0)
					(end 5.0673 0)
				)
			)
			(stroke
				(width 0)
				(type default)
			)
			(fill no)
			(layer "B.Fab")
		)
		(fp_poly
			(pts
				(arc
					(start 5.0673 0)
					(mid -5.0673 0)
					(end 5.0673 0)
				)
			)
			(stroke
				(width 0)
				(type default)
			)
			(fill no)
			(layer "F.Fab")
		)
		(pad "1" thru_hole circle
			(at 0 0)
			(size 9.525 9.525)
			(drill 3.556)
			(layers "*.Cu" "*.Mask")
			(remove_unused_layers no)
			(net "Net_32")
			(clearance -2.4765)
			(thermal_gap 0.3048)
			(padstack
				(mode front_inner_back)
				(layer "Inner"
					(shape circle)
					(size 3.9624 3.9624)
					(clearance 0.3048)
				)
				(layer "B.Cu"
					(shape circle)
					(size 9.525 9.525)
					(clearance -2.4765)
				)
			)
		)
		(zone
			(layers "F.Cu" "B.Cu" "In1.Cu" "In2.Cu" "In3.Cu" "In4.Cu" "In5.Cu" "In6.Cu")
			(hatch none 0.5)
			(connect_pads
				(clearance 0)
			)
			(min_thickness 0.25)
			(keepout
				(tracks not_allowed)
				(vias allowed)
				(pads allowed)
				(copperpour not_allowed)
				(footprints allowed)
			)
			(placement
				(enabled no)
				(sheetname "")
			)
			(fill
				(thermal_gap 0.5)
				(thermal_bridge_width 0.5)
				(island_removal_mode 0)
			)
			(polygon
				(pts
					(arc
						(start 472.262454 -13.999972)
						(mid 462.737454 -13.999972)
						(end 472.262454 -13.999972)
					)
				)
			)
		)
	)
	(footprint ""
		(layer "F.Cu")
		(at 244.37848 -196.72554 90)
		(property "Reference" "R79"
			(at 0 0 90)
			(layer "F.SilkS")
			(hide yes)
			(effects
				(font
					(size 1.27 1.27)
				)
			)
		)
		(property "Value" "4K7R2F-GP"
			(at 0.064008 -3.993896 90)
			(unlocked yes)
			(layer "F.Fab")
			(hide yes)
			(effects
				(font
					(size 1.016 1.016)
					(thickness 0.1524)
				)
			)
		)
		(property "Device Type" "R402H16"
			(at 0.064008 -5.517896 90)
			(unlocked yes)
			(layer "F.Fab")
			(hide yes)
			(effects
				(font
					(size 1.016 1.016)
					(thickness 0.1524)
				)
			)
		)
		(duplicate_pad_numbers_are_jumpers no)
		(fp_line
			(start 0.508 -0.9398)
			(end -0.508 -0.9398)
			(stroke
				(width 0.1524)
				(type default)
			)
			(layer "F.SilkS")
		)
		(fp_line
			(start -0.508 -0.9398)
			(end -0.508 0.9398)
			(stroke
				(width 0.1524)
				(type default)
			)
			(layer "F.SilkS")
		)
		(fp_rect
			(start -0.508 0.9398)
			(end 0.508 -0.9398)
			(stroke
				(width 0)
				(type default)
			)
			(fill no)
			(layer "F.CrtYd")
		)
		(fp_rect
			(start -0.508 0.9398)
			(end 0.508 -0.9398)
			(stroke
				(width 0)
				(type default)
			)
			(fill no)
			(layer "F.Fab")
		)
		(pad "1" smd custom
			(at 0 -0.4445 90)
			(size 0.1397 0.1397)
			(layers "F.Cu" "F.Mask" "F.Paste")
			(net "IO_EXP2_A2")
			(options
				(clearance outline)
				(anchor circle)
			)
			(primitives
				(gr_poly
					(pts
						(arc
							(start -0.1778 -0.2794)
							(mid -0.249642 -0.249642)
							(end -0.2794 -0.1778)
						)
						(arc
							(start -0.2794 0.1778)
							(mid -0.249642 0.249642)
							(end -0.1778 0.2794)
						)
						(arc
							(start 0.1778 0.2794)
							(mid 0.249642 0.249642)
							(end 0.2794 0.1778)
						)
						(arc
							(start 0.2794 -0.1778)
							(mid 0.249642 -0.249642)
							(end 0.1778 -0.2794)
						)
					)
					(width 0)
					(fill yes)
				)
			)
		)
		(pad "2" smd custom
			(at 0 0.4445 90)
			(size 0.1397 0.1397)
			(layers "F.Cu" "F.Mask" "F.Paste")
			(net "GND")
			(options
				(clearance outline)
				(anchor circle)
			)
			(primitives
				(gr_poly
					(pts
						(arc
							(start -0.1778 -0.2794)
							(mid -0.249642 -0.249642)
							(end -0.2794 -0.1778)
						)
						(arc
							(start -0.2794 0.1778)
							(mid -0.249642 0.249642)
							(end -0.1778 0.2794)
						)
						(arc
							(start 0.1778 0.2794)
							(mid 0.249642 0.249642)
							(end 0.2794 0.1778)
						)
						(arc
							(start 0.2794 -0.1778)
							(mid 0.249642 -0.249642)
							(end 0.1778 -0.2794)
						)
					)
					(width 0)
					(fill yes)
				)
			)
		)
	)
	(footprint ""
		(layer "F.Cu")
		(at 457.581 -274.955 180)
		(property "Reference" "C164"
			(at 0 0 180)
			(layer "F.SilkS")
			(hide yes)
			(effects
				(font
					(size 1.27 1.27)
				)
			)
		)
		(property "Value" "SC4D7U25V5KX-1-GP"
			(at -0.0762 -6.1214 180)
			(unlocked yes)
			(layer "F.Fab")
			(hide yes)
			(effects
				(font
					(size 1.016 1.016)
					(thickness 0.1524)
				)
			)
		)
		(property "Device Type" "C805H58"
			(at -0.0762 -8.1534 180)
			(unlocked yes)
			(layer "F.Fab")
			(hide yes)
			(effects
				(font
					(size 1.016 1.016)
					(thickness 0.1524)
				)
			)
		)
		(duplicate_pad_numbers_are_jumpers no)
		(fp_line
			(start 0.635 0)
			(end -0.635 0)
			(stroke
				(width 0.508)
				(type default)
			)
			(layer "F.SilkS")
		)
		(fp_rect
			(start -0.9652 1.778)
			(end 0.9652 -1.778)
			(stroke
				(width 0)
				(type default)
			)
			(fill no)
			(layer "F.CrtYd")
		)
		(fp_poly
			(pts
				(xy -0.9652 -1.778) (xy 0.9652 -1.778) (xy 0.9652 1.778) (xy -0.9652 1.778)
			)
			(stroke
				(width 0)
				(type default)
			)
			(fill no)
			(layer "F.Fab")
		)
		(pad "1" smd rect
			(at 0 -0.9652 180)
			(size 1.397 1.143)
			(layers "F.Cu" "F.Mask" "F.Paste")
			(net "P12V_HDD10")
		)
		(pad "2" smd rect
			(at 0 0.9652 180)
			(size 1.397 1.143)
			(layers "F.Cu" "F.Mask" "F.Paste")
			(net "GND")
		)
	)
	(footprint ""
		(layer "F.Cu")
		(at 241.995452 -363.046772 90)
		(property "Reference" "R1049"
			(at 0 0 90)
			(layer "F.SilkS")
			(hide yes)
			(effects
				(font
					(size 1.27 1.27)
				)
			)
		)
		(property "Value" "49K9R2F-L-GP"
			(at 0.064008 -3.993896 90)
			(unlocked yes)
			(layer "F.Fab")
			(hide yes)
			(effects
				(font
					(size 1.016 1.016)
					(thickness 0.1524)
				)
			)
		)
		(property "Device Type" "R402H16"
			(at 0.064008 -5.517896 90)
			(unlocked yes)
			(layer "F.Fab")
			(hide yes)
			(effects
				(font
					(size 1.016 1.016)
					(thickness 0.1524)
				)
			)
		)
		(duplicate_pad_numbers_are_jumpers no)
		(fp_line
			(start 0.508 -0.9398)
			(end -0.508 -0.9398)
			(stroke
				(width 0.1524)
				(type default)
			)
			(layer "F.SilkS")
		)
		(fp_line
			(start -0.508 -0.9398)
			(end -0.508 0.9398)
			(stroke
				(width 0.1524)
				(type default)
			)
			(layer "F.SilkS")
		)
		(fp_rect
			(start -0.508 0.9398)
			(end 0.508 -0.9398)
			(stroke
				(width 0)
				(type default)
			)
			(fill no)
			(layer "F.CrtYd")
		)
		(fp_rect
			(start -0.508 0.9398)
			(end 0.508 -0.9398)
			(stroke
				(width 0)
				(type default)
			)
			(fill no)
			(layer "F.Fab")
		)
		(pad "1" smd custom
			(at 0 -0.4445 90)
			(size 0.1397 0.1397)
			(layers "F.Cu" "F.Mask" "F.Paste")
			(net "P12V_IN")
			(options
				(clearance outline)
				(anchor circle)
			)
			(primitives
				(gr_poly
					(pts
						(arc
							(start -0.1778 -0.2794)
							(mid -0.249642 -0.249642)
							(end -0.2794 -0.1778)
						)
						(arc
							(start -0.2794 0.1778)
							(mid -0.249642 0.249642)
							(end -0.1778 0.2794)
						)
						(arc
							(start 0.1778 0.2794)
							(mid 0.249642 0.249642)
							(end 0.2794 0.1778)
						)
						(arc
							(start 0.2794 -0.1778)
							(mid 0.249642 -0.249642)
							(end 0.1778 -0.2794)
						)
					)
					(width 0)
					(fill yes)
				)
			)
		)
		(pad "2" smd custom
			(at 0 0.4445 90)
			(size 0.1397 0.1397)
			(layers "F.Cu" "F.Mask" "F.Paste")
			(net "MB3_CM_UV_R")
			(options
				(clearance outline)
				(anchor circle)
			)
			(primitives
				(gr_poly
					(pts
						(arc
							(start -0.1778 -0.2794)
							(mid -0.249642 -0.249642)
							(end -0.2794 -0.1778)
						)
						(arc
							(start -0.2794 0.1778)
							(mid -0.249642 0.249642)
							(end -0.1778 0.2794)
						)
						(arc
							(start 0.1778 0.2794)
							(mid 0.249642 0.249642)
							(end 0.2794 0.1778)
						)
						(arc
							(start 0.2794 -0.1778)
							(mid 0.249642 -0.249642)
							(end 0.1778 -0.2794)
						)
					)
					(width 0)
					(fill yes)
				)
			)
		)
	)
	(footprint ""
		(layer "F.Cu")
		(at 111.975646 -29.7434)
		(property "Reference" "C389"
			(at 0 0 0)
			(layer "F.SilkS")
			(hide yes)
			(effects
				(font
					(size 1.27 1.27)
				)
			)
		)
		(property "Value" "SCD033U25V2KX-GP"
			(at 1.1811 -2.7051 0)
			(unlocked yes)
			(layer "F.Fab")
			(hide yes)
			(effects
				(font
					(size 1.016 1.016)
					(thickness 0.1524)
				)
			)
		)
		(property "Device Type" "C402H22"
			(at 1.1811 -4.2291 0)
			(unlocked yes)
			(layer "F.Fab")
			(hide yes)
			(effects
				(font
					(size 1.016 1.016)
					(thickness 0.1524)
				)
			)
		)
		(duplicate_pad_numbers_are_jumpers no)
		(fp_rect
			(start -0.4318 0.9525)
			(end 0.4318 -0.9525)
			(stroke
				(width 0)
				(type default)
			)
			(fill no)
			(layer "F.CrtYd")
		)
		(fp_rect
			(start -0.4318 0.9525)
			(end 0.4318 -0.9525)
			(stroke
				(width 0)
				(type default)
			)
			(fill no)
			(layer "F.Fab")
		)
		(pad "1" smd custom
			(at 0 -0.4445)
			(size 0.1524 0.1524)
			(layers "F.Cu" "F.Mask" "F.Paste")
			(net "SW_HDD_P27")
			(options
				(clearance outline)
				(anchor circle)
			)
			(primitives
				(gr_poly
					(pts
						(arc
							(start 0.3048 -0.2032)
							(mid 0.275042 -0.275042)
							(end 0.2032 -0.3048)
						)
						(arc
							(start -0.2032 -0.3048)
							(mid -0.275042 -0.275042)
							(end -0.3048 -0.2032)
						)
						(arc
							(start -0.3048 0.2032)
							(mid -0.275042 0.275042)
							(end -0.2032 0.3048)
						)
						(arc
							(start 0.2032 0.3048)
							(mid 0.275042 0.275042)
							(end 0.3048 0.2032)
						)
					)
					(width 0)
					(fill yes)
				)
			)
		)
		(pad "2" smd custom
			(at 0 0.4445)
			(size 0.1524 0.1524)
			(layers "F.Cu" "F.Mask" "F.Paste")
			(net "GND")
			(options
				(clearance outline)
				(anchor circle)
			)
			(primitives
				(gr_poly
					(pts
						(arc
							(start 0.3048 -0.2032)
							(mid 0.275042 -0.275042)
							(end 0.2032 -0.3048)
						)
						(arc
							(start -0.2032 -0.3048)
							(mid -0.275042 -0.275042)
							(end -0.3048 -0.2032)
						)
						(arc
							(start -0.3048 0.2032)
							(mid -0.275042 0.275042)
							(end -0.2032 0.3048)
						)
						(arc
							(start 0.2032 0.3048)
							(mid 0.275042 0.275042)
							(end 0.3048 0.2032)
						)
					)
					(width 0)
					(fill yes)
				)
			)
		)
	)
	(footprint ""
		(layer "F.Cu")
		(at 55.372 -263.271)
		(property "Reference" "R175"
			(at 0 0 0)
			(layer "F.SilkS")
			(hide yes)
			(effects
				(font
					(size 1.27 1.27)
				)
			)
		)
		(property "Value" "2R6F-GP"
			(at -0.0508 -4.8514 0)
			(unlocked yes)
			(layer "F.Fab")
			(hide yes)
			(effects
				(font
					(size 1.016 1.016)
					(thickness 0.1524)
				)
			)
		)
		(property "Device Type" "R1206H26"
			(at 0 -6.3754 0)
			(unlocked yes)
			(layer "F.Fab")
			(hide yes)
			(effects
				(font
					(size 1.016 1.016)
					(thickness 0.1524)
				)
			)
		)
		(duplicate_pad_numbers_are_jumpers no)
		(fp_line
			(start -1.016 -2.2352)
			(end 1.016 -2.2352)
			(stroke
				(width 0.1524)
				(type default)
			)
			(layer "F.SilkS")
		)
		(fp_line
			(start -1.016 2.2352)
			(end -1.016 -2.2352)
			(stroke
				(width 0.1524)
				(type default)
			)
			(layer "F.SilkS")
		)
		(fp_line
			(start 1.016 -2.2352)
			(end 1.016 2.2352)
			(stroke
				(width 0.1524)
				(type default)
			)
			(layer "F.SilkS")
		)
		(fp_line
			(start 1.016 2.2352)
			(end -1.016 2.2352)
			(stroke
				(width 0.1524)
				(type default)
			)
			(layer "F.SilkS")
		)
		(fp_rect
			(start -1.0922 2.3114)
			(end 1.0922 -2.3114)
			(stroke
				(width 0)
				(type default)
			)
			(fill no)
			(layer "F.CrtYd")
		)
		(fp_poly
			(pts
				(xy -1.0922 -2.3114) (xy 1.0922 -2.3114) (xy 1.0922 2.3114) (xy -1.0922 2.3114)
			)
			(stroke
				(width 0)
				(type default)
			)
			(fill no)
			(layer "F.Fab")
		)
		(pad "1" smd rect
			(at 0 -1.397)
			(size 1.651 1.27)
			(layers "F.Cu" "F.Mask" "F.Paste")
			(net "P5V_HDD1")
		)
		(pad "2" smd rect
			(at 0 1.397)
			(size 1.651 1.27)
			(layers "F.Cu" "F.Mask" "F.Paste")
			(net "5V_PRE_1")
		)
	)
	(footprint ""
		(layer "F.Cu")
		(at 115.316 -141.224 180)
		(property "Reference" "Q63"
			(at 0 0 180)
			(layer "F.SilkS")
			(hide yes)
			(effects
				(font
					(size 1.27 1.27)
				)
			)
		)
		(property "Value" "AO4406AL-GP"
			(at -3.707384 -1.5367 180)
			(unlocked yes)
			(layer "F.Fab")
			(hide yes)
			(effects
				(font
					(size 1.016 1.016)
					(thickness 0.1524)
				)
			)
		)
		(property "Device Type" "SOIC8H69"
			(at -3.707384 -3.0607 180)
			(unlocked yes)
			(layer "F.Fab")
			(hide yes)
			(effects
				(font
					(size 1.016 1.016)
					(thickness 0.1524)
				)
			)
		)
		(duplicate_pad_numbers_are_jumpers no)
		(fp_line
			(start 2.1336 1.4224)
			(end 2.1336 -1.4224)
			(stroke
				(width 0.1524)
				(type default)
			)
			(layer "F.SilkS")
		)
		(fp_line
			(start 2.1336 -1.4224)
			(end -2.7432 -1.4224)
			(stroke
				(width 0.1524)
				(type default)
			)
			(layer "F.SilkS")
		)
		(fp_line
			(start -2.1844 -0.0508)
			(end -2.7178 0.508)
			(stroke
				(width 0.1524)
				(type default)
			)
			(layer "F.SilkS")
		)
		(fp_line
			(start -2.6289 3.4417)
			(end -2.6289 1.4732)
			(stroke
				(width 0.381)
				(type default)
			)
			(layer "F.SilkS")
		)
		(fp_line
			(start -2.7178 -0.508)
			(end -2.1844 -0.0508)
			(stroke
				(width 0.1524)
				(type default)
			)
			(layer "F.SilkS")
		)
		(fp_line
			(start -2.7432 1.4224)
			(end 2.1336 1.4224)
			(stroke
				(width 0.1524)
				(type default)
			)
			(layer "F.SilkS")
		)
		(fp_line
			(start -2.7432 1.4224)
			(end -2.6416 1.4224)
			(stroke
				(width 0.1524)
				(type default)
			)
			(layer "F.SilkS")
		)
		(fp_line
			(start -2.7432 -1.4224)
			(end -2.7432 1.4224)
			(stroke
				(width 0.1524)
				(type default)
			)
			(layer "F.SilkS")
		)
		(fp_poly
			(pts
				(xy -2.2098 -1.4224) (xy -2.2098 1.4224) (xy 2.2098 1.4224) (xy 2.2098 -1.4224)
			)
			(stroke
				(width 0)
				(type default)
			)
			(fill yes)
			(layer "F.SilkS")
		)
		(fp_rect
			(start -2.450084 2.999994)
			(end 2.450084 -2.999994)
			(stroke
				(width 0)
				(type default)
			)
			(fill no)
			(layer "F.CrtYd")
		)
		(fp_poly
			(pts
				(xy -2.8194 3.6322) (xy -2.8194 -3.6322) (xy 2.8194 -3.6322) (xy 2.8194 1.18364) (xy 2.450084 1.18364)
				(xy 2.450084 -2.999994) (xy -2.450084 -2.999994) (xy -2.450084 2.999994) (xy 2.450084 2.999994)
				(xy 2.450084 1.18618) (xy 2.8194 1.18618) (xy 2.8194 3.6322)
			)
			(stroke
				(width 0)
				(type default)
			)
			(fill no)
			(layer "F.CrtYd")
		)
		(fp_rect
			(start -2.8194 3.6322)
			(end 2.8194 -3.6322)
			(stroke
				(width 0)
				(type default)
			)
			(fill no)
			(layer "F.Fab")
		)
		(pad "1" smd rect
			(at -1.905 2.54 180)
			(size 0.635 1.651)
			(layers "F.Cu" "F.Mask" "F.Paste")
			(net "P5V_HDD15")
		)
		(pad "2" smd rect
			(at -0.635 2.54 180)
			(size 0.635 1.651)
			(layers "F.Cu" "F.Mask" "F.Paste")
			(net "P5V_HDD15")
		)
		(pad "3" smd rect
			(at 0.635 2.54 180)
			(size 0.635 1.651)
			(layers "F.Cu" "F.Mask" "F.Paste")
			(net "P5V_HDD15")
		)
		(pad "4" smd rect
			(at 1.905 2.54 180)
			(size 0.635 1.651)
			(layers "F.Cu" "F.Mask" "F.Paste")
			(net "SW_HDD_P15")
		)
		(pad "5" smd rect
			(at 1.905 -2.54 180)
			(size 0.635 1.651)
			(layers "F.Cu" "F.Mask" "F.Paste")
			(net "P5V_B_2")
		)
		(pad "6" smd rect
			(at 0.635 -2.54 180)
			(size 0.635 1.651)
			(layers "F.Cu" "F.Mask" "F.Paste")
			(net "P5V_B_2")
		)
		(pad "7" smd rect
			(at -0.635 -2.54 180)
			(size 0.635 1.651)
			(layers "F.Cu" "F.Mask" "F.Paste")
			(net "P5V_B_2")
		)
		(pad "8" smd rect
			(at -1.905 -2.54 180)
			(size 0.635 1.651)
			(layers "F.Cu" "F.Mask" "F.Paste")
			(net "P5V_B_2")
		)
	)
	(footprint ""
		(layer "F.Cu")
		(at 261.1247 -376.761756 180)
		(property "Reference" "Q210"
			(at 0 0 180)
			(layer "F.SilkS")
			(hide yes)
			(effects
				(font
					(size 1.27 1.27)
				)
			)
		)
		(property "Value" "MMBT2222A-3-GP"
			(at 0.10287 -10.29843 180)
			(unlocked yes)
			(layer "F.Fab")
			(hide yes)
			(effects
				(font
					(size 1.016 1.016)
					(thickness 0.1524)
				)
			)
		)
		(property "Device Type" "SOT23CBE2D4H44"
			(at 0.10287 -12.20343 180)
			(unlocked yes)
			(layer "F.Fab")
			(hide yes)
			(effects
				(font
					(size 1.016 1.016)
					(thickness 0.1524)
				)
			)
		)
		(duplicate_pad_numbers_are_jumpers no)
		(fp_line
			(start 1.651 1.778)
			(end 1.651 -1.778)
			(stroke
				(width 0.1524)
				(type default)
			)
			(layer "F.SilkS")
		)
		(fp_line
			(start 1.651 -1.778)
			(end -1.651 -1.778)
			(stroke
				(width 0.1524)
				(type default)
			)
			(layer "F.SilkS")
		)
		(fp_line
			(start -1.651 1.778)
			(end 1.651 1.778)
			(stroke
				(width 0.1524)
				(type default)
			)
			(layer "F.SilkS")
		)
		(fp_line
			(start -1.651 -1.778)
			(end -1.651 1.778)
			(stroke
				(width 0.1524)
				(type default)
			)
			(layer "F.SilkS")
		)
		(fp_poly
			(pts
				(xy -1.778 1.8796) (xy -1.778 -1.8796) (xy 1.778 -1.8796) (xy 1.778 1.8796)
			)
			(stroke
				(width 0)
				(type default)
			)
			(fill no)
			(layer "F.CrtYd")
		)
		(fp_poly
			(pts
				(xy -1.778 1.8796) (xy -1.778 -1.8796) (xy 1.778 -1.8796) (xy 1.778 1.8796)
			)
			(stroke
				(width 0)
				(type default)
			)
			(fill no)
			(layer "F.Fab")
		)
		(pad "B" smd custom
			(at -0.98425 0.9525 180)
			(size 0.1905 0.1905)
			(layers "F.Cu" "F.Mask" "F.Paste")
			(net "DRAWER_OUT_NET_B")
			(options
				(clearance outline)
				(anchor circle)
			)
			(primitives
				(gr_poly
					(pts
						(arc
							(start -0.1778 0.5715)
							(mid -0.321484 0.511984)
							(end -0.381 0.3683)
						)
						(arc
							(start -0.381 -0.3683)
							(mid -0.321484 -0.511984)
							(end -0.1778 -0.5715)
						)
						(arc
							(start 0.1778 -0.5715)
							(mid 0.321484 -0.511984)
							(end 0.381 -0.3683)
						)
						(arc
							(start 0.381 0.3683)
							(mid 0.321484 0.511984)
							(end 0.1778 0.5715)
						)
					)
					(width 0)
					(fill yes)
				)
			)
		)
		(pad "C" smd custom
			(at 0 -0.9525 180)
			(size 0.1905 0.1905)
			(layers "F.Cu" "F.Mask" "F.Paste")
			(net "DRAWER_OUT#_C")
			(options
				(clearance outline)
				(anchor circle)
			)
			(primitives
				(gr_poly
					(pts
						(arc
							(start -0.1778 0.5715)
							(mid -0.321484 0.511984)
							(end -0.381 0.3683)
						)
						(arc
							(start -0.381 -0.3683)
							(mid -0.321484 -0.511984)
							(end -0.1778 -0.5715)
						)
						(arc
							(start 0.1778 -0.5715)
							(mid 0.321484 -0.511984)
							(end 0.381 -0.3683)
						)
						(arc
							(start 0.381 0.3683)
							(mid 0.321484 0.511984)
							(end 0.1778 0.5715)
						)
					)
					(width 0)
					(fill yes)
				)
			)
		)
		(pad "E" smd custom
			(at 0.98425 0.9525 180)
			(size 0.1905 0.1905)
			(layers "F.Cu" "F.Mask" "F.Paste")
			(net "GND")
			(options
				(clearance outline)
				(anchor circle)
			)
			(primitives
				(gr_poly
					(pts
						(arc
							(start -0.1778 0.5715)
							(mid -0.321484 0.511984)
							(end -0.381 0.3683)
						)
						(arc
							(start -0.381 -0.3683)
							(mid -0.321484 -0.511984)
							(end -0.1778 -0.5715)
						)
						(arc
							(start 0.1778 -0.5715)
							(mid 0.321484 -0.511984)
							(end 0.381 -0.3683)
						)
						(arc
							(start 0.381 0.3683)
							(mid 0.321484 0.511984)
							(end 0.1778 0.5715)
						)
					)
					(width 0)
					(fill yes)
				)
			)
		)
	)
	(footprint ""
		(layer "F.Cu")
		(at 158.708852 -248.750074 -90)
		(property "Reference" "VIA10"
			(at 0 0 270)
			(layer "F.SilkS")
			(hide yes)
			(effects
				(font
					(size 1.27 1.27)
				)
			)
		)
		(property "Value" "100OHM-8L-2D36MM-L16-GP"
			(at -3.4036 -0.4572 270)
			(unlocked yes)
			(layer "F.Fab")
			(hide yes)
			(effects
				(font
					(size 1.016 1.016)
					(thickness 0.1524)
				)
			)
		)
		(property "Device Type" "VIA-PCIE-4P-427097"
			(at -3.4036 -1.9812 270)
			(unlocked yes)
			(layer "F.Fab")
			(hide yes)
			(effects
				(font
					(size 1.016 1.016)
					(thickness 0.1524)
				)
			)
		)
		(duplicate_pad_numbers_are_jumpers no)
		(fp_rect
			(start -2.1336 0.4826)
			(end 2.1336 -0.4826)
			(stroke
				(width 0)
				(type default)
			)
			(fill no)
			(layer "F.CrtYd")
		)
		(fp_rect
			(start -2.1336 0.4826)
			(end 2.1336 -0.4826)
			(stroke
				(width 0)
				(type default)
			)
			(fill no)
			(layer "F.Fab")
		)
		(pad "1" thru_hole circle
			(at -1.651 0 270)
			(size 0.508 0.508)
			(drill 0.254)
			(layers "*.Cu" "*.Mask")
			(remove_unused_layers no)
			(net "GND")
			(clearance 0.2286)
			(thermal_gap 0.2286)
		)
		(pad "2" thru_hole circle
			(at -0.635 0 270)
			(size 0.508 0.508)
			(drill 0.254)
			(layers "*.Cu" "*.Mask")
			(remove_unused_layers no)
			(net "PHY_DRV_B_TO_SCC_B_4_DP")
			(clearance 0.2286)
			(thermal_gap 0.2286)
		)
		(pad "3" thru_hole circle
			(at 0.635 0 270)
			(size 0.508 0.508)
			(drill 0.254)
			(layers "*.Cu" "*.Mask")
			(remove_unused_layers no)
			(net "PHY_DRV_B_TO_SCC_B_4_DN")
			(clearance 0.2286)
			(thermal_gap 0.2286)
		)
		(pad "4" thru_hole circle
			(at 1.651 0 270)
			(size 0.508 0.508)
			(drill 0.254)
			(layers "*.Cu" "*.Mask")
			(remove_unused_layers no)
			(net "GND")
			(clearance 0.2286)
			(thermal_gap 0.2286)
		)
	)
	(footprint ""
		(layer "F.Cu")
		(at 98.425 -148.082 -90)
		(property "Reference" "R392"
			(at 0 0 270)
			(layer "F.SilkS")
			(hide yes)
			(effects
				(font
					(size 1.27 1.27)
				)
			)
		)
		(property "Value" "10KR2F-2-GP"
			(at 0.064008 -3.993896 270)
			(unlocked yes)
			(layer "F.Fab")
			(hide yes)
			(effects
				(font
					(size 1.016 1.016)
					(thickness 0.1524)
				)
			)
		)
		(property "Device Type" "R402H16"
			(at 0.064008 -5.517896 270)
			(unlocked yes)
			(layer "F.Fab")
			(hide yes)
			(effects
				(font
					(size 1.016 1.016)
					(thickness 0.1524)
				)
			)
		)
		(duplicate_pad_numbers_are_jumpers no)
		(fp_line
			(start -0.508 -0.9398)
			(end -0.508 0.9398)
			(stroke
				(width 0.1524)
				(type default)
			)
			(layer "F.SilkS")
		)
		(fp_line
			(start 0.508 -0.9398)
			(end -0.508 -0.9398)
			(stroke
				(width 0.1524)
				(type default)
			)
			(layer "F.SilkS")
		)
		(fp_rect
			(start -0.508 0.9398)
			(end 0.508 -0.9398)
			(stroke
				(width 0)
				(type default)
			)
			(fill no)
			(layer "F.CrtYd")
		)
		(fp_rect
			(start -0.508 0.9398)
			(end 0.508 -0.9398)
			(stroke
				(width 0)
				(type default)
			)
			(fill no)
			(layer "F.Fab")
		)
		(pad "1" smd custom
			(at 0 -0.4445 270)
			(size 0.1397 0.1397)
			(layers "F.Cu" "F.Mask" "F.Paste")
			(net "P3V3_STBY_B")
			(options
				(clearance outline)
				(anchor circle)
			)
			(primitives
				(gr_poly
					(pts
						(arc
							(start -0.1778 -0.2794)
							(mid -0.249642 -0.249642)
							(end -0.2794 -0.1778)
						)
						(arc
							(start -0.2794 0.1778)
							(mid -0.249642 0.249642)
							(end -0.1778 0.2794)
						)
						(arc
							(start 0.1778 0.2794)
							(mid 0.249642 0.249642)
							(end 0.2794 0.1778)
						)
						(arc
							(start 0.2794 -0.1778)
							(mid 0.249642 -0.249642)
							(end 0.1778 -0.2794)
						)
					)
					(width 0)
					(fill yes)
				)
			)
		)
		(pad "2" smd custom
			(at 0 0.4445 270)
			(size 0.1397 0.1397)
			(layers "F.Cu" "F.Mask" "F.Paste")
			(net "HDD_PRSNT_14")
			(options
				(clearance outline)
				(anchor circle)
			)
			(primitives
				(gr_poly
					(pts
						(arc
							(start -0.1778 -0.2794)
							(mid -0.249642 -0.249642)
							(end -0.2794 -0.1778)
						)
						(arc
							(start -0.2794 0.1778)
							(mid -0.249642 0.249642)
							(end -0.1778 0.2794)
						)
						(arc
							(start 0.1778 0.2794)
							(mid 0.249642 0.249642)
							(end 0.2794 0.1778)
						)
						(arc
							(start 0.2794 -0.1778)
							(mid 0.249642 -0.249642)
							(end 0.1778 -0.2794)
						)
					)
					(width 0)
					(fill yes)
				)
			)
		)
	)
	(footprint ""
		(layer "F.Cu")
		(at 22.993096 -374.3071 90)
		(property "Reference" "R965"
			(at 0 0 90)
			(layer "F.SilkS")
			(hide yes)
			(effects
				(font
					(size 1.27 1.27)
				)
			)
		)
		(property "Value" "270R5J-2-GP"
			(at 0 -8.9535 90)
			(unlocked yes)
			(layer "F.Fab")
			(hide yes)
			(effects
				(font
					(size 1.27 1.016)
					(thickness 0.1524)
				)
			)
		)
		(property "Device Type" "R805H24"
			(at 0 -10.6299 90)
			(unlocked yes)
			(layer "F.Fab")
			(hide yes)
			(effects
				(font
					(size 1.27 1.016)
					(thickness 0.1524)
				)
			)
		)
		(duplicate_pad_numbers_are_jumpers no)
		(fp_line
			(start 0.889 -1.7018)
			(end -0.889 -1.7018)
			(stroke
				(width 0.1524)
				(type default)
			)
			(layer "F.SilkS")
		)
		(fp_line
			(start 0.889 -1.7018)
			(end 0.889 -0.381)
			(stroke
				(width 0.1524)
				(type default)
			)
			(layer "F.SilkS")
		)
		(fp_line
			(start -0.889 -1.7018)
			(end -0.889 0.2794)
			(stroke
				(width 0.1524)
				(type default)
			)
			(layer "F.SilkS")
		)
		(fp_line
			(start -0.889 0.0762)
			(end -0.889 1.7018)
			(stroke
				(width 0.1524)
				(type default)
			)
			(layer "F.SilkS")
		)
		(fp_line
			(start 0.889 1.7018)
			(end 0.889 -0.508)
			(stroke
				(width 0.1524)
				(type default)
			)
			(layer "F.SilkS")
		)
		(fp_line
			(start -0.889 1.7018)
			(end 0.889 1.7018)
			(stroke
				(width 0.1524)
				(type default)
			)
			(layer "F.SilkS")
		)
		(fp_poly
			(pts
				(xy 0.9652 -1.778) (xy 0.9652 1.778) (xy -0.9652 1.778) (xy -0.9652 -1.778)
			)
			(stroke
				(width 0)
				(type default)
			)
			(fill no)
			(layer "F.CrtYd")
		)
		(fp_rect
			(start -0.9652 1.778)
			(end 0.9652 -1.778)
			(stroke
				(width 0)
				(type default)
			)
			(fill no)
			(layer "F.Fab")
		)
		(pad "1" smd rect
			(at 0 -0.9652 90)
			(size 1.397 1.143)
			(layers "F.Cu" "F.Mask" "F.Paste")
			(net "FAN_LED_BLUE0")
		)
		(pad "2" smd rect
			(at 0 0.9652 90)
			(size 1.397 1.143)
			(layers "F.Cu" "F.Mask" "F.Paste")
			(net "FAN_BLUE0")
		)
	)
	(footprint ""
		(layer "F.Cu")
		(at 251.776992 -137.04697 -90)
		(property "Reference" "R441"
			(at 0 0 270)
			(layer "F.SilkS")
			(hide yes)
			(effects
				(font
					(size 1.27 1.27)
				)
			)
		)
		(property "Value" "10KR2F-2-GP"
			(at 0.064008 -3.993896 270)
			(unlocked yes)
			(layer "F.Fab")
			(hide yes)
			(effects
				(font
					(size 1.016 1.016)
					(thickness 0.1524)
				)
			)
		)
		(property "Device Type" "R402H16"
			(at 0.064008 -5.517896 270)
			(unlocked yes)
			(layer "F.Fab")
			(hide yes)
			(effects
				(font
					(size 1.016 1.016)
					(thickness 0.1524)
				)
			)
		)
		(duplicate_pad_numbers_are_jumpers no)
		(fp_line
			(start -0.508 -0.9398)
			(end -0.508 0.9398)
			(stroke
				(width 0.1524)
				(type default)
			)
			(layer "F.SilkS")
		)
		(fp_line
			(start 0.508 -0.9398)
			(end -0.508 -0.9398)
			(stroke
				(width 0.1524)
				(type default)
			)
			(layer "F.SilkS")
		)
		(fp_rect
			(start -0.508 0.9398)
			(end 0.508 -0.9398)
			(stroke
				(width 0)
				(type default)
			)
			(fill no)
			(layer "F.CrtYd")
		)
		(fp_rect
			(start -0.508 0.9398)
			(end 0.508 -0.9398)
			(stroke
				(width 0)
				(type default)
			)
			(fill no)
			(layer "F.Fab")
		)
		(pad "1" smd custom
			(at 0 -0.4445 270)
			(size 0.1397 0.1397)
			(layers "F.Cu" "F.Mask" "F.Paste")
			(net "P3V3_STBY_B")
			(options
				(clearance outline)
				(anchor circle)
			)
			(primitives
				(gr_poly
					(pts
						(arc
							(start -0.1778 -0.2794)
							(mid -0.249642 -0.249642)
							(end -0.2794 -0.1778)
						)
						(arc
							(start -0.2794 0.1778)
							(mid -0.249642 0.249642)
							(end -0.1778 0.2794)
						)
						(arc
							(start 0.1778 0.2794)
							(mid 0.249642 0.249642)
							(end 0.2794 0.1778)
						)
						(arc
							(start 0.2794 -0.1778)
							(mid 0.249642 -0.249642)
							(end 0.1778 -0.2794)
						)
					)
					(width 0)
					(fill yes)
				)
			)
		)
		(pad "2" smd custom
			(at 0 0.4445 270)
			(size 0.1397 0.1397)
			(layers "F.Cu" "F.Mask" "F.Paste")
			(net "I2C_SCC_BUFF_READY")
			(options
				(clearance outline)
				(anchor circle)
			)
			(primitives
				(gr_poly
					(pts
						(arc
							(start -0.1778 -0.2794)
							(mid -0.249642 -0.249642)
							(end -0.2794 -0.1778)
						)
						(arc
							(start -0.2794 0.1778)
							(mid -0.249642 0.249642)
							(end -0.1778 0.2794)
						)
						(arc
							(start 0.1778 0.2794)
							(mid 0.249642 0.249642)
							(end 0.2794 0.1778)
						)
						(arc
							(start 0.2794 -0.1778)
							(mid 0.249642 -0.249642)
							(end 0.1778 -0.2794)
						)
					)
					(width 0)
					(fill yes)
				)
			)
		)
	)
	(footprint ""
		(layer "F.Cu")
		(at 361.315 -152.908 180)
		(property "Reference" "C277"
			(at 0 0 180)
			(layer "F.SilkS")
			(hide yes)
			(effects
				(font
					(size 1.27 1.27)
				)
			)
		)
		(property "Value" "SC1U16V3KX-5GP"
			(at 0 -2.8194 180)
			(unlocked yes)
			(layer "F.Fab")
			(hide yes)
			(effects
				(font
					(size 1.016 1.016)
					(thickness 0.1524)
				)
			)
		)
		(property "Device Type" "C603H36"
			(at 0 -4.3434 180)
			(unlocked yes)
			(layer "F.Fab")
			(hide yes)
			(effects
				(font
					(size 1.016 1.016)
					(thickness 0.1524)
				)
			)
		)
		(duplicate_pad_numbers_are_jumpers no)
		(fp_line
			(start 0.508 0)
			(end -0.508 0)
			(stroke
				(width 0.2032)
				(type default)
			)
			(layer "F.SilkS")
		)
		(fp_rect
			(start -0.5842 1.3335)
			(end 0.5842 -1.3335)
			(stroke
				(width 0)
				(type default)
			)
			(fill no)
			(layer "F.CrtYd")
		)
		(fp_rect
			(start -0.5842 1.3335)
			(end 0.5842 -1.3335)
			(stroke
				(width 0)
				(type default)
			)
			(fill no)
			(layer "F.Fab")
		)
		(pad "1" smd custom
			(at 0 -0.762 180)
			(size 0.2159 0.2159)
			(layers "F.Cu" "F.Mask" "F.Paste")
			(net "P5V_HDD19")
			(options
				(clearance outline)
				(anchor circle)
			)
			(primitives
				(gr_poly
					(pts
						(arc
							(start -0.3302 -0.4318)
							(mid -0.402042 -0.402042)
							(end -0.4318 -0.3302)
						)
						(arc
							(start -0.4318 0.3302)
							(mid -0.402042 0.402042)
							(end -0.3302 0.4318)
						)
						(arc
							(start 0.3302 0.4318)
							(mid 0.402042 0.402042)
							(end 0.4318 0.3302)
						)
						(arc
							(start 0.4318 -0.3302)
							(mid 0.402042 -0.402042)
							(end 0.3302 -0.4318)
						)
					)
					(width 0)
					(fill yes)
				)
			)
		)
		(pad "2" smd custom
			(at 0 0.762 180)
			(size 0.2159 0.2159)
			(layers "F.Cu" "F.Mask" "F.Paste")
			(net "GND")
			(options
				(clearance outline)
				(anchor circle)
			)
			(primitives
				(gr_poly
					(pts
						(arc
							(start -0.3302 -0.4318)
							(mid -0.402042 -0.402042)
							(end -0.4318 -0.3302)
						)
						(arc
							(start -0.4318 0.3302)
							(mid -0.402042 0.402042)
							(end -0.3302 0.4318)
						)
						(arc
							(start 0.3302 0.4318)
							(mid 0.402042 0.402042)
							(end 0.4318 0.3302)
						)
						(arc
							(start 0.4318 -0.3302)
							(mid 0.402042 -0.402042)
							(end 0.3302 -0.4318)
						)
					)
					(width 0)
					(fill yes)
				)
			)
		)
	)
	(footprint ""
		(layer "F.Cu")
		(at 180.7464 -248.4882 -90)
		(property "Reference" "R244"
			(at 0 0 270)
			(layer "F.SilkS")
			(hide yes)
			(effects
				(font
					(size 1.27 1.27)
				)
			)
		)
		(property "Value" "1KR2F-3-GP"
			(at 0.064008 -3.993896 270)
			(unlocked yes)
			(layer "F.Fab")
			(hide yes)
			(effects
				(font
					(size 1.016 1.016)
					(thickness 0.1524)
				)
			)
		)
		(property "Device Type" "R402H16"
			(at 0.064008 -5.517896 270)
			(unlocked yes)
			(layer "F.Fab")
			(hide yes)
			(effects
				(font
					(size 1.016 1.016)
					(thickness 0.1524)
				)
			)
		)
		(duplicate_pad_numbers_are_jumpers no)
		(fp_line
			(start -0.508 -0.9398)
			(end -0.508 0.9398)
			(stroke
				(width 0.1524)
				(type default)
			)
			(layer "F.SilkS")
		)
		(fp_line
			(start 0.508 -0.9398)
			(end -0.508 -0.9398)
			(stroke
				(width 0.1524)
				(type default)
			)
			(layer "F.SilkS")
		)
		(fp_rect
			(start -0.508 0.9398)
			(end 0.508 -0.9398)
			(stroke
				(width 0)
				(type default)
			)
			(fill no)
			(layer "F.CrtYd")
		)
		(fp_rect
			(start -0.508 0.9398)
			(end 0.508 -0.9398)
			(stroke
				(width 0)
				(type default)
			)
			(fill no)
			(layer "F.Fab")
		)
		(pad "1" smd custom
			(at 0 -0.4445 270)
			(size 0.1397 0.1397)
			(layers "F.Cu" "F.Mask" "F.Paste")
			(net "P3V3_STBY_B")
			(options
				(clearance outline)
				(anchor circle)
			)
			(primitives
				(gr_poly
					(pts
						(arc
							(start -0.1778 -0.2794)
							(mid -0.249642 -0.249642)
							(end -0.2794 -0.1778)
						)
						(arc
							(start -0.2794 0.1778)
							(mid -0.249642 0.249642)
							(end -0.1778 0.2794)
						)
						(arc
							(start 0.1778 0.2794)
							(mid 0.249642 0.249642)
							(end 0.2794 0.1778)
						)
						(arc
							(start 0.2794 -0.1778)
							(mid 0.249642 -0.249642)
							(end 0.1778 -0.2794)
						)
					)
					(width 0)
					(fill yes)
				)
			)
		)
		(pad "2" smd custom
			(at 0 0.4445 270)
			(size 0.1397 0.1397)
			(layers "F.Cu" "F.Mask" "F.Paste")
			(net "SW_PWR_R_HDD5")
			(options
				(clearance outline)
				(anchor circle)
			)
			(primitives
				(gr_poly
					(pts
						(arc
							(start -0.1778 -0.2794)
							(mid -0.249642 -0.249642)
							(end -0.2794 -0.1778)
						)
						(arc
							(start -0.2794 0.1778)
							(mid -0.249642 0.249642)
							(end -0.1778 0.2794)
						)
						(arc
							(start 0.1778 0.2794)
							(mid 0.249642 0.249642)
							(end 0.2794 0.1778)
						)
						(arc
							(start 0.2794 -0.1778)
							(mid 0.249642 -0.249642)
							(end 0.1778 -0.2794)
						)
					)
					(width 0)
					(fill yes)
				)
			)
		)
	)
	(footprint ""
		(layer "F.Cu")
		(at 77.851 -150.622 -90)
		(property "Reference" "C216"
			(at 0 0 270)
			(layer "F.SilkS")
			(hide yes)
			(effects
				(font
					(size 1.27 1.27)
				)
			)
		)
		(property "Value" "SC4D7U25V5KX-1-GP"
			(at -0.0762 -6.1214 270)
			(unlocked yes)
			(layer "F.Fab")
			(hide yes)
			(effects
				(font
					(size 1.016 1.016)
					(thickness 0.1524)
				)
			)
		)
		(property "Device Type" "C805H58"
			(at -0.0762 -8.1534 270)
			(unlocked yes)
			(layer "F.Fab")
			(hide yes)
			(effects
				(font
					(size 1.016 1.016)
					(thickness 0.1524)
				)
			)
		)
		(duplicate_pad_numbers_are_jumpers no)
		(fp_line
			(start 0.635 0)
			(end -0.635 0)
			(stroke
				(width 0.508)
				(type default)
			)
			(layer "F.SilkS")
		)
		(fp_rect
			(start -0.9652 1.778)
			(end 0.9652 -1.778)
			(stroke
				(width 0)
				(type default)
			)
			(fill no)
			(layer "F.CrtYd")
		)
		(fp_poly
			(pts
				(xy -0.9652 -1.778) (xy 0.9652 -1.778) (xy 0.9652 1.778) (xy -0.9652 1.778)
			)
			(stroke
				(width 0)
				(type default)
			)
			(fill no)
			(layer "F.Fab")
		)
		(pad "1" smd rect
			(at 0 -0.9652 270)
			(size 1.397 1.143)
			(layers "F.Cu" "F.Mask" "F.Paste")
			(net "P12V_HDD14")
		)
		(pad "2" smd rect
			(at 0 0.9652 270)
			(size 1.397 1.143)
			(layers "F.Cu" "F.Mask" "F.Paste")
			(net "GND")
		)
	)
	(footprint ""
		(layer "F.Cu")
		(at 176.149 -131.572)
		(property "Reference" "R478"
			(at 0 0 0)
			(layer "F.SilkS")
			(hide yes)
			(effects
				(font
					(size 1.27 1.27)
				)
			)
		)
		(property "Value" "0R2J-2-GP"
			(at 0.064008 -3.993896 0)
			(unlocked yes)
			(layer "F.Fab")
			(hide yes)
			(effects
				(font
					(size 1.016 1.016)
					(thickness 0.1524)
				)
			)
		)
		(property "Device Type" "R402H16"
			(at 0.064008 -5.517896 0)
			(unlocked yes)
			(layer "F.Fab")
			(hide yes)
			(effects
				(font
					(size 1.016 1.016)
					(thickness 0.1524)
				)
			)
		)
		(duplicate_pad_numbers_are_jumpers no)
		(fp_line
			(start -0.508 -0.9398)
			(end -0.508 0.9398)
			(stroke
				(width 0.1524)
				(type default)
			)
			(layer "F.SilkS")
		)
		(fp_line
			(start 0.508 -0.9398)
			(end -0.508 -0.9398)
			(stroke
				(width 0.1524)
				(type default)
			)
			(layer "F.SilkS")
		)
		(fp_rect
			(start -0.508 0.9398)
			(end 0.508 -0.9398)
			(stroke
				(width 0)
				(type default)
			)
			(fill no)
			(layer "F.CrtYd")
		)
		(fp_rect
			(start -0.508 0.9398)
			(end 0.508 -0.9398)
			(stroke
				(width 0)
				(type default)
			)
			(fill no)
			(layer "F.Fab")
		)
		(pad "1" smd custom
			(at 0 -0.4445)
			(size 0.1397 0.1397)
			(layers "F.Cu" "F.Mask" "F.Paste")
			(net "SW_HDD_G17")
			(options
				(clearance outline)
				(anchor circle)
			)
			(primitives
				(gr_poly
					(pts
						(arc
							(start -0.1778 -0.2794)
							(mid -0.249642 -0.249642)
							(end -0.2794 -0.1778)
						)
						(arc
							(start -0.2794 0.1778)
							(mid -0.249642 0.249642)
							(end -0.1778 0.2794)
						)
						(arc
							(start 0.1778 0.2794)
							(mid 0.249642 0.249642)
							(end 0.2794 0.1778)
						)
						(arc
							(start 0.2794 -0.1778)
							(mid 0.249642 -0.249642)
							(end 0.1778 -0.2794)
						)
					)
					(width 0)
					(fill yes)
				)
			)
		)
		(pad "2" smd custom
			(at 0 0.4445)
			(size 0.1397 0.1397)
			(layers "F.Cu" "F.Mask" "F.Paste")
			(net "SW_HDD_R17")
			(options
				(clearance outline)
				(anchor circle)
			)
			(primitives
				(gr_poly
					(pts
						(arc
							(start -0.1778 -0.2794)
							(mid -0.249642 -0.249642)
							(end -0.2794 -0.1778)
						)
						(arc
							(start -0.2794 0.1778)
							(mid -0.249642 0.249642)
							(end -0.1778 0.2794)
						)
						(arc
							(start 0.1778 0.2794)
							(mid 0.249642 0.249642)
							(end 0.2794 0.1778)
						)
						(arc
							(start 0.2794 -0.1778)
							(mid 0.249642 -0.249642)
							(end 0.1778 -0.2794)
						)
					)
					(width 0)
					(fill yes)
				)
			)
		)
	)
	(footprint ""
		(layer "F.Cu")
		(at 83.566 -249.555 180)
		(property "Reference" "Q7"
			(at 0 0 180)
			(layer "F.SilkS")
			(hide yes)
			(effects
				(font
					(size 1.27 1.27)
				)
			)
		)
		(property "Value" "2N7002KDW-GP"
			(at -2.3622 -8.2042 180)
			(unlocked yes)
			(layer "F.Fab")
			(hide yes)
			(effects
				(font
					(size 1.016 1.016)
					(thickness 0.1524)
				)
			)
		)
		(property "Device Type" "SOT-363H44"
			(at -2.3622 -10.1092 180)
			(unlocked yes)
			(layer "F.Fab")
			(hide yes)
			(effects
				(font
					(size 1.016 1.016)
					(thickness 0.1524)
				)
			)
		)
		(duplicate_pad_numbers_are_jumpers no)
		(fp_line
			(start 1.4478 1.7018)
			(end 1.4478 -1.7018)
			(stroke
				(width 0.1524)
				(type default)
			)
			(layer "F.SilkS")
		)
		(fp_line
			(start 1.4478 -1.7018)
			(end -1.4478 -1.7018)
			(stroke
				(width 0.1524)
				(type default)
			)
			(layer "F.SilkS")
		)
		(fp_line
			(start -1.27 1.524)
			(end -1.27 0.6604)
			(stroke
				(width 0.4826)
				(type default)
			)
			(layer "F.SilkS")
		)
		(fp_line
			(start -1.4478 1.7018)
			(end 1.4478 1.7018)
			(stroke
				(width 0.1524)
				(type default)
			)
			(layer "F.SilkS")
		)
		(fp_line
			(start -1.4478 -1.7018)
			(end -1.4478 1.7018)
			(stroke
				(width 0.1524)
				(type default)
			)
			(layer "F.SilkS")
		)
		(fp_poly
			(pts
				(xy -1.524 -1.778) (xy 1.524 -1.778) (xy 1.524 1.778) (xy -1.524 1.778)
			)
			(stroke
				(width 0)
				(type default)
			)
			(fill no)
			(layer "F.CrtYd")
		)
		(fp_poly
			(pts
				(xy -1.524 -1.778) (xy 1.524 -1.778) (xy 1.524 1.778) (xy -1.524 1.778)
			)
			(stroke
				(width 0)
				(type default)
			)
			(fill no)
			(layer "F.Fab")
		)
		(pad "1" smd rect
			(at -0.65024 0.9398 180)
			(size 0.4064 1.016)
			(layers "F.Cu" "F.Mask" "F.Paste")
			(net "GND")
		)
		(pad "2" smd rect
			(at 0 0.9398 180)
			(size 0.4064 1.016)
			(layers "F.Cu" "F.Mask" "F.Paste")
			(net "SW_PWR_R_HDD2")
		)
		(pad "3" smd rect
			(at 0.65024 0.9398 180)
			(size 0.4064 1.016)
			(layers "F.Cu" "F.Mask" "F.Paste")
			(net "SW_HDD_P2")
		)
		(pad "4" smd rect
			(at 0.65024 -0.9398 180)
			(size 0.4064 1.016)
			(layers "F.Cu" "F.Mask" "F.Paste")
			(net "GND")
		)
		(pad "5" smd rect
			(at 0 -0.9398 180)
			(size 0.4064 1.016)
			(layers "F.Cu" "F.Mask" "F.Paste")
			(net "SW_HDD_G2")
		)
		(pad "6" smd rect
			(at -0.65024 -0.9398 180)
			(size 0.4064 1.016)
			(layers "F.Cu" "F.Mask" "F.Paste")
			(net "SW_HDD_R2")
		)
	)
	(footprint ""
		(layer "F.Cu")
		(at 331.7494 -249.4788 90)
		(property "Reference" "R259"
			(at 0 0 90)
			(layer "F.SilkS")
			(hide yes)
			(effects
				(font
					(size 1.27 1.27)
				)
			)
		)
		(property "Value" "4K7R2J-2-GP"
			(at 0.064008 -3.993896 90)
			(unlocked yes)
			(layer "F.Fab")
			(hide yes)
			(effects
				(font
					(size 1.016 1.016)
					(thickness 0.1524)
				)
			)
		)
		(property "Device Type" "R402H16"
			(at 0.064008 -5.517896 90)
			(unlocked yes)
			(layer "F.Fab")
			(hide yes)
			(effects
				(font
					(size 1.016 1.016)
					(thickness 0.1524)
				)
			)
		)
		(duplicate_pad_numbers_are_jumpers no)
		(fp_line
			(start 0.508 -0.9398)
			(end -0.508 -0.9398)
			(stroke
				(width 0.1524)
				(type default)
			)
			(layer "F.SilkS")
		)
		(fp_line
			(start -0.508 -0.9398)
			(end -0.508 0.9398)
			(stroke
				(width 0.1524)
				(type default)
			)
			(layer "F.SilkS")
		)
		(fp_rect
			(start -0.508 0.9398)
			(end 0.508 -0.9398)
			(stroke
				(width 0)
				(type default)
			)
			(fill no)
			(layer "F.CrtYd")
		)
		(fp_rect
			(start -0.508 0.9398)
			(end 0.508 -0.9398)
			(stroke
				(width 0)
				(type default)
			)
			(fill no)
			(layer "F.Fab")
		)
		(pad "1" smd custom
			(at 0 -0.4445 90)
			(size 0.1397 0.1397)
			(layers "F.Cu" "F.Mask" "F.Paste")
			(net "P12V_B")
			(options
				(clearance outline)
				(anchor circle)
			)
			(primitives
				(gr_poly
					(pts
						(arc
							(start -0.1778 -0.2794)
							(mid -0.249642 -0.249642)
							(end -0.2794 -0.1778)
						)
						(arc
							(start -0.2794 0.1778)
							(mid -0.249642 0.249642)
							(end -0.1778 0.2794)
						)
						(arc
							(start 0.1778 0.2794)
							(mid 0.249642 0.249642)
							(end 0.2794 0.1778)
						)
						(arc
							(start 0.2794 -0.1778)
							(mid 0.249642 -0.249642)
							(end 0.1778 -0.2794)
						)
					)
					(width 0)
					(fill yes)
				)
			)
		)
		(pad "2" smd custom
			(at 0 0.4445 90)
			(size 0.1397 0.1397)
			(layers "F.Cu" "F.Mask" "F.Paste")
			(net "SW_HDD_P6")
			(options
				(clearance outline)
				(anchor circle)
			)
			(primitives
				(gr_poly
					(pts
						(arc
							(start -0.1778 -0.2794)
							(mid -0.249642 -0.249642)
							(end -0.2794 -0.1778)
						)
						(arc
							(start -0.2794 0.1778)
							(mid -0.249642 0.249642)
							(end -0.1778 0.2794)
						)
						(arc
							(start 0.1778 0.2794)
							(mid 0.249642 0.249642)
							(end 0.2794 0.1778)
						)
						(arc
							(start 0.2794 -0.1778)
							(mid 0.249642 -0.249642)
							(end 0.1778 -0.2794)
						)
					)
					(width 0)
					(fill yes)
				)
			)
		)
	)
	(footprint ""
		(layer "F.Cu")
		(at 51.7652 -33.782 -90)
		(property "Reference" "C355"
			(at 0 0 270)
			(layer "F.SilkS")
			(hide yes)
			(effects
				(font
					(size 1.27 1.27)
				)
			)
		)
		(property "Value" "SC1U16V3KX-5GP"
			(at 0 -2.8194 270)
			(unlocked yes)
			(layer "F.Fab")
			(hide yes)
			(effects
				(font
					(size 1.016 1.016)
					(thickness 0.1524)
				)
			)
		)
		(property "Device Type" "C603H36"
			(at 0 -4.3434 270)
			(unlocked yes)
			(layer "F.Fab")
			(hide yes)
			(effects
				(font
					(size 1.016 1.016)
					(thickness 0.1524)
				)
			)
		)
		(duplicate_pad_numbers_are_jumpers no)
		(fp_line
			(start 0.508 0)
			(end -0.508 0)
			(stroke
				(width 0.2032)
				(type default)
			)
			(layer "F.SilkS")
		)
		(fp_rect
			(start -0.5842 1.3335)
			(end 0.5842 -1.3335)
			(stroke
				(width 0)
				(type default)
			)
			(fill no)
			(layer "F.CrtYd")
		)
		(fp_rect
			(start -0.5842 1.3335)
			(end 0.5842 -1.3335)
			(stroke
				(width 0)
				(type default)
			)
			(fill no)
			(layer "F.Fab")
		)
		(pad "1" smd custom
			(at 0 -0.762 270)
			(size 0.2159 0.2159)
			(layers "F.Cu" "F.Mask" "F.Paste")
			(net "P5V_HDD25")
			(options
				(clearance outline)
				(anchor circle)
			)
			(primitives
				(gr_poly
					(pts
						(arc
							(start -0.3302 -0.4318)
							(mid -0.402042 -0.402042)
							(end -0.4318 -0.3302)
						)
						(arc
							(start -0.4318 0.3302)
							(mid -0.402042 0.402042)
							(end -0.3302 0.4318)
						)
						(arc
							(start 0.3302 0.4318)
							(mid 0.402042 0.402042)
							(end 0.4318 0.3302)
						)
						(arc
							(start 0.4318 -0.3302)
							(mid 0.402042 -0.402042)
							(end 0.3302 -0.4318)
						)
					)
					(width 0)
					(fill yes)
				)
			)
		)
		(pad "2" smd custom
			(at 0 0.762 270)
			(size 0.2159 0.2159)
			(layers "F.Cu" "F.Mask" "F.Paste")
			(net "GND")
			(options
				(clearance outline)
				(anchor circle)
			)
			(primitives
				(gr_poly
					(pts
						(arc
							(start -0.3302 -0.4318)
							(mid -0.402042 -0.402042)
							(end -0.4318 -0.3302)
						)
						(arc
							(start -0.4318 0.3302)
							(mid -0.402042 0.402042)
							(end -0.3302 0.4318)
						)
						(arc
							(start 0.3302 0.4318)
							(mid 0.402042 0.402042)
							(end 0.4318 0.3302)
						)
						(arc
							(start 0.4318 -0.3302)
							(mid 0.402042 -0.402042)
							(end 0.3302 -0.4318)
						)
					)
					(width 0)
					(fill yes)
				)
			)
		)
	)
	(footprint ""
		(layer "F.Cu")
		(at 154.399996 -258.910074 -90)
		(property "Reference" "HDDSAS4"
			(at 0 0 270)
			(layer "F.SilkS")
			(hide yes)
			(effects
				(font
					(size 1.27 1.27)
				)
			)
		)
		(property "Value" "SKT-SAS15P-14P-45-GP"
			(at -20.7645 -8.9789 270)
			(unlocked yes)
			(layer "F.Fab")
			(hide yes)
			(effects
				(font
					(size 1.016 1.016)
					(thickness 0.1524)
				)
			)
		)
		(property "Device Type" "10120818-001C-TRLF"
			(at -20.7645 -10.5029 270)
			(unlocked yes)
			(layer "F.Fab")
			(hide yes)
			(effects
				(font
					(size 1.016 1.016)
					(thickness 0.1524)
				)
			)
		)
		(duplicate_pad_numbers_are_jumpers no)
		(fp_line
			(start 1.651 4.2926)
			(end 1.651 3.0099)
			(stroke
				(width 0.1524)
				(type default)
			)
			(layer "F.SilkS")
		)
		(fp_line
			(start 8.509 4.2926)
			(end 1.651 4.2926)
			(stroke
				(width 0.1524)
				(type default)
			)
			(layer "F.SilkS")
		)
		(fp_line
			(start -23.4188 3.0099)
			(end -23.4188 -3.2512)
			(stroke
				(width 0.1524)
				(type default)
			)
			(layer "F.SilkS")
		)
		(fp_line
			(start 1.651 3.0099)
			(end -23.4188 3.0099)
			(stroke
				(width 0.1524)
				(type default)
			)
			(layer "F.SilkS")
		)
		(fp_line
			(start 8.509 3.0099)
			(end 8.509 4.2926)
			(stroke
				(width 0.1524)
				(type default)
			)
			(layer "F.SilkS")
		)
		(fp_line
			(start 23.4188 3.0099)
			(end 8.509 3.0099)
			(stroke
				(width 0.1524)
				(type default)
			)
			(layer "F.SilkS")
		)
		(fp_line
			(start -23.4188 -3.2512)
			(end 23.4188 -3.2512)
			(stroke
				(width 0.1524)
				(type default)
			)
			(layer "F.SilkS")
		)
		(fp_line
			(start 23.4188 -3.2512)
			(end 23.4188 3.0099)
			(stroke
				(width 0.1524)
				(type default)
			)
			(layer "F.SilkS")
		)
		(fp_line
			(start 15.5067 -3.3401)
			(end 16.2687 -3.3401)
			(stroke
				(width 0.3302)
				(type default)
			)
			(layer "F.SilkS")
		)
		(fp_poly
			(pts
				(xy 15.868904 -3.230372) (xy 16.503904 -3.865372) (xy 15.233904 -3.865372)
			)
			(stroke
				(width 0)
				(type default)
			)
			(fill yes)
			(layer "F.SilkS")
		)
		(fp_poly
			(pts
				(xy -22.8727 -2.7559) (xy 22.8727 -2.7559) (xy 22.8727 2.7559) (xy 8.255 2.7559) (xy 8.255 3.5179)
				(xy 1.905 3.5179) (xy 1.905 2.7559) (xy -22.8727 2.7559)
			)
			(stroke
				(width 0)
				(type default)
			)
			(fill no)
			(layer "F.CrtYd")
		)
		(fp_poly
			(pts
				(xy 1.397 4.5466) (xy 1.397 3.2639) (xy -23.6728 3.2639) (xy -23.6728 -3.5052) (xy 23.6728 -3.5052)
				(xy 23.6728 -0.00635) (xy 22.8727 -0.00635) (xy 22.8727 -2.7559) (xy -22.8727 -2.7559) (xy -22.8727 2.7559)
				(xy 1.905 2.7559) (xy 1.905 3.5179) (xy 8.255 3.5179) (xy 8.255 2.7559) (xy 22.8727 2.7559) (xy 22.8727 0.00635)
				(xy 23.6728 0.00635) (xy 23.6728 3.2639) (xy 8.763 3.2639) (xy 8.763 4.5466)
			)
			(stroke
				(width 0)
				(type default)
			)
			(fill no)
			(layer "F.CrtYd")
		)
		(fp_poly
			(pts
				(xy 1.397 4.5466) (xy 1.397 3.2639) (xy -23.6728 3.2639) (xy -23.6728 -3.5052) (xy 23.6728 -3.5052)
				(xy 23.6728 3.2639) (xy 8.763 3.2639) (xy 8.763 4.5466)
			)
			(stroke
				(width 0)
				(type default)
			)
			(fill no)
			(layer "F.Fab")
		)
		(pad "" np_thru_hole circle
			(at -18.874994 0 270)
			(size 0.254 0.254)
			(drill 1.3462)
			(layers "*.Cu" "*.Mask")
			(clearance 0.9017)
			(thermal_gap 0.9017)
		)
		(pad "" np_thru_hole circle
			(at 18.874994 0 270)
			(size 0.254 0.254)
			(drill 0.9398)
			(layers "*.Cu" "*.Mask")
			(clearance 0.6985)
			(thermal_gap 0.6985)
		)
		(pad "G1" smd rect
			(at 21.874988 0 270)
			(size 2.5908 2.5908)
			(layers "F.Cu" "F.Mask" "F.Paste")
			(net "GND")
		)
		(pad "G2" smd rect
			(at -21.874988 0 270)
			(size 2.5908 2.5908)
			(layers "F.Cu" "F.Mask" "F.Paste")
			(net "GND")
		)
		(pad "P1" smd rect
			(at 1.905 -1.82499 270)
			(size 0.6096 2.3622)
			(layers "F.Cu" "F.Mask" "F.Paste")
			(net "Net_1609")
		)
		(pad "P2" smd rect
			(at 0.635 -1.82499 270)
			(size 0.6096 2.3622)
			(layers "F.Cu" "F.Mask" "F.Paste")
			(net "Net_1610")
		)
		(pad "P3" smd rect
			(at -0.635 -1.82499 270)
			(size 0.6096 2.3622)
			(layers "F.Cu" "F.Mask" "F.Paste")
			(net "Net_1611")
		)
		(pad "P4" smd rect
			(at -1.905 -1.82499 270)
			(size 0.6096 2.3622)
			(layers "F.Cu" "F.Mask" "F.Paste")
			(net "GND")
		)
		(pad "P5" smd rect
			(at -3.175 -1.82499 270)
			(size 0.6096 2.3622)
			(layers "F.Cu" "F.Mask" "F.Paste")
			(net "HDD_PRSNT_4")
		)
		(pad "P6" smd rect
			(at -4.445 -1.82499 270)
			(size 0.6096 2.3622)
			(layers "F.Cu" "F.Mask" "F.Paste")
			(net "GND")
		)
		(pad "P7" smd rect
			(at -5.715 -1.82499 270)
			(size 0.6096 2.3622)
			(layers "F.Cu" "F.Mask" "F.Paste")
			(net "5V_PRE_4")
		)
		(pad "P8" smd rect
			(at -6.985 -1.82499 270)
			(size 0.6096 2.3622)
			(layers "F.Cu" "F.Mask" "F.Paste")
			(net "P5V_HDD4")
		)
		(pad "P9" smd rect
			(at -8.255 -1.82499 270)
			(size 0.6096 2.3622)
			(layers "F.Cu" "F.Mask" "F.Paste")
			(net "P5V_HDD4")
		)
		(pad "P10" smd rect
			(at -9.525 -1.82499 270)
			(size 0.6096 2.3622)
			(layers "F.Cu" "F.Mask" "F.Paste")
			(net "GND")
		)
		(pad "P11" smd rect
			(at -10.795 -1.82499 270)
			(size 0.6096 2.3622)
			(layers "F.Cu" "F.Mask" "F.Paste")
			(net "ACT_HDD_4")
		)
		(pad "P12" smd rect
			(at -12.065 -1.82499 270)
			(size 0.6096 2.3622)
			(layers "F.Cu" "F.Mask" "F.Paste")
			(net "GND")
		)
		(pad "P13" smd rect
			(at -13.335 -1.82499 270)
			(size 0.6096 2.3622)
			(layers "F.Cu" "F.Mask" "F.Paste")
			(net "12V_PRE_4")
		)
		(pad "P14" smd rect
			(at -14.605 -1.82499 270)
			(size 0.6096 2.3622)
			(layers "F.Cu" "F.Mask" "F.Paste")
			(net "P12V_HDD4")
		)
		(pad "P15" smd rect
			(at -15.875 -1.82499 270)
			(size 0.6096 2.3622)
			(layers "F.Cu" "F.Mask" "F.Paste")
			(net "P12V_HDD4")
		)
		(pad "S1" smd rect
			(at 15.875 -1.82499 270)
			(size 0.6096 2.3622)
			(layers "F.Cu" "F.Mask" "F.Paste")
			(net "GND")
		)
		(pad "S2" smd rect
			(at 14.605 -1.82499 270)
			(size 0.6096 2.3622)
			(layers "F.Cu" "F.Mask" "F.Paste")
			(net "SAS_HDD_RX_P4")
		)
		(pad "S3" smd rect
			(at 13.335 -1.82499 270)
			(size 0.6096 2.3622)
			(layers "F.Cu" "F.Mask" "F.Paste")
			(net "SAS_HDD_RX_N4")
		)
		(pad "S4" smd rect
			(at 12.065 -1.82499 270)
			(size 0.6096 2.3622)
			(layers "F.Cu" "F.Mask" "F.Paste")
			(net "GND")
		)
		(pad "S5" smd rect
			(at 10.795 -1.82499 270)
			(size 0.6096 2.3622)
			(layers "F.Cu" "F.Mask" "F.Paste")
			(net "PHY_DRV_B_TO_SCC_B_4_DN")
		)
		(pad "S6" smd rect
			(at 9.525 -1.82499 270)
			(size 0.6096 2.3622)
			(layers "F.Cu" "F.Mask" "F.Paste")
			(net "PHY_DRV_B_TO_SCC_B_4_DP")
		)
		(pad "S7" smd rect
			(at 8.255 -1.82499 270)
			(size 0.6096 2.3622)
			(layers "F.Cu" "F.Mask" "F.Paste")
			(net "GND")
		)
		(pad "S8" smd rect
			(at 7.480046 2.845054 270)
			(size 0.508 2.3622)
			(layers "F.Cu" "F.Mask" "F.Paste")
			(net "GND")
		)
		(pad "S9" smd rect
			(at 6.679946 2.845054 270)
			(size 0.508 2.3622)
			(layers "F.Cu" "F.Mask" "F.Paste")
			(net "Net_462")
		)
		(pad "S10" smd rect
			(at 5.8801 2.845054 270)
			(size 0.508 2.3622)
			(layers "F.Cu" "F.Mask" "F.Paste")
			(net "Net_354")
		)
		(pad "S11" smd rect
			(at 5.08 2.845054 270)
			(size 0.508 2.3622)
			(layers "F.Cu" "F.Mask" "F.Paste")
			(net "GND")
		)
		(pad "S12" smd rect
			(at 4.2799 2.845054 270)
			(size 0.508 2.3622)
			(layers "F.Cu" "F.Mask" "F.Paste")
			(net "Net_390")
		)
		(pad "S13" smd rect
			(at 3.480054 2.845054 270)
			(size 0.508 2.3622)
			(layers "F.Cu" "F.Mask" "F.Paste")
			(net "Net_426")
		)
		(pad "S14" smd rect
			(at 2.679954 2.845054 270)
			(size 0.508 2.3622)
			(layers "F.Cu" "F.Mask" "F.Paste")
			(net "GND")
		)
		(zone
			(layer "F.Cu")
			(hatch none 0.5)
			(connect_pads
				(clearance 0)
			)
			(min_thickness 0.25)
			(keepout
				(tracks not_allowed)
				(vias allowed)
				(pads allowed)
				(copperpour not_allowed)
				(footprints allowed)
			)
			(placement
				(enabled no)
				(sheetname "")
			)
			(fill
				(thermal_gap 0.5)
				(thermal_bridge_width 0.5)
				(island_removal_mode 0)
			)
			(polygon
				(pts
					(xy 158.057596 -275.648674) (xy 150.983696 -275.648674) (xy 150.983696 -282.582874) (xy 152.088596 -282.582874)
					(xy 152.088596 -278.468074) (xy 156.711396 -278.468074) (xy 156.711396 -282.582874) (xy 158.057596 -282.582874)
				)
			)
		)
		(zone
			(layer "F.Cu")
			(hatch none 0.5)
			(connect_pads
				(clearance 0)
			)
			(min_thickness 0.25)
			(keepout
				(tracks allowed)
				(vias not_allowed)
				(pads allowed)
				(copperpour not_allowed)
				(footprints allowed)
			)
			(placement
				(enabled no)
				(sheetname "")
			)
			(fill
				(thermal_gap 0.5)
				(thermal_bridge_width 0.5)
				(island_removal_mode 0)
			)
			(polygon
				(pts
					(xy 158.057596 -275.648674) (xy 150.983696 -275.648674) (xy 150.983696 -282.582874) (xy 152.088596 -282.582874)
					(xy 152.088596 -278.468074) (xy 156.711396 -278.468074) (xy 156.711396 -282.582874) (xy 158.057596 -282.582874)
				)
			)
		)
		(zone
			(layer "F.Cu")
			(hatch none 0.5)
			(connect_pads
				(clearance 0)
			)
			(min_thickness 0.25)
			(keepout
				(tracks allowed)
				(vias not_allowed)
				(pads allowed)
				(copperpour not_allowed)
				(footprints allowed)
			)
			(placement
				(enabled no)
				(sheetname "")
			)
			(fill
				(thermal_gap 0.5)
				(thermal_bridge_width 0.5)
				(island_removal_mode 0)
			)
			(polygon
				(pts
					(xy 158.057596 -242.171474) (xy 150.983696 -242.171474) (xy 150.983696 -235.237274) (xy 152.088596 -235.237274)
					(xy 152.088596 -239.352074) (xy 156.711396 -239.352074) (xy 156.711396 -235.237274) (xy 158.057596 -235.237274)
				)
			)
		)
		(zone
			(layer "F.Cu")
			(hatch none 0.5)
			(connect_pads
				(clearance 0)
			)
			(min_thickness 0.25)
			(keepout
				(tracks not_allowed)
				(vias allowed)
				(pads allowed)
				(copperpour not_allowed)
				(footprints allowed)
			)
			(placement
				(enabled no)
				(sheetname "")
			)
			(fill
				(thermal_gap 0.5)
				(thermal_bridge_width 0.5)
				(island_removal_mode 0)
			)
			(polygon
				(pts
					(xy 158.057596 -242.171474) (xy 150.983696 -242.171474) (xy 150.983696 -235.237274) (xy 152.088596 -235.237274)
					(xy 152.088596 -239.352074) (xy 156.711396 -239.352074) (xy 156.711396 -235.237274) (xy 158.057596 -235.237274)
				)
			)
		)
		(zone
			(layers "F.Cu" "B.Cu" "In1.Cu" "In2.Cu" "In3.Cu" "In4.Cu" "In5.Cu" "In6.Cu")
			(hatch none 0.5)
			(connect_pads
				(clearance 0)
			)
			(min_thickness 0.25)
			(keepout
				(tracks not_allowed)
				(vias allowed)
				(pads allowed)
				(copperpour not_allowed)
				(footprints allowed)
			)
			(placement
				(enabled no)
				(sheetname "")
			)
			(fill
				(thermal_gap 0.5)
				(thermal_bridge_width 0.5)
				(island_removal_mode 0)
			)
			(polygon
				(pts
					(arc
						(start 155.174696 -240.03508)
						(mid 153.625296 -240.03508)
						(end 155.174696 -240.03508)
					)
				)
			)
		)
		(zone
			(layers "F.Cu" "B.Cu" "In1.Cu" "In2.Cu" "In3.Cu" "In4.Cu" "In5.Cu" "In6.Cu")
			(hatch none 0.5)
			(connect_pads
				(clearance 0)
			)
			(min_thickness 0.25)
			(keepout
				(tracks not_allowed)
				(vias allowed)
				(pads allowed)
				(copperpour not_allowed)
				(footprints allowed)
			)
			(placement
				(enabled no)
				(sheetname "")
			)
			(fill
				(thermal_gap 0.5)
				(thermal_bridge_width 0.5)
				(island_removal_mode 0)
			)
			(polygon
				(pts
					(arc
						(start 155.377896 -277.785068)
						(mid 153.422096 -277.785068)
						(end 155.377896 -277.785068)
					)
				)
			)
		)
	)
	(footprint ""
		(layer "F.Cu")
		(at 323.364606 -376.7836 -90)
		(property "Reference" "R1307"
			(at 0 0 270)
			(layer "F.SilkS")
			(hide yes)
			(effects
				(font
					(size 1.27 1.27)
				)
			)
		)
		(property "Value" "4K7R2F-GP"
			(at 0.064008 -3.993896 270)
			(unlocked yes)
			(layer "F.Fab")
			(hide yes)
			(effects
				(font
					(size 1.016 1.016)
					(thickness 0.1524)
				)
			)
		)
		(property "Device Type" "R402H16"
			(at 0.064008 -5.517896 270)
			(unlocked yes)
			(layer "F.Fab")
			(hide yes)
			(effects
				(font
					(size 1.016 1.016)
					(thickness 0.1524)
				)
			)
		)
		(duplicate_pad_numbers_are_jumpers no)
		(fp_line
			(start -0.508 -0.9398)
			(end -0.508 0.9398)
			(stroke
				(width 0.1524)
				(type default)
			)
			(layer "F.SilkS")
		)
		(fp_line
			(start 0.508 -0.9398)
			(end -0.508 -0.9398)
			(stroke
				(width 0.1524)
				(type default)
			)
			(layer "F.SilkS")
		)
		(fp_rect
			(start -0.508 0.9398)
			(end 0.508 -0.9398)
			(stroke
				(width 0)
				(type default)
			)
			(fill no)
			(layer "F.CrtYd")
		)
		(fp_rect
			(start -0.508 0.9398)
			(end 0.508 -0.9398)
			(stroke
				(width 0)
				(type default)
			)
			(fill no)
			(layer "F.Fab")
		)
		(pad "1" smd custom
			(at 0 -0.4445 270)
			(size 0.1397 0.1397)
			(layers "F.Cu" "F.Mask" "F.Paste")
			(net "FAN_YELLOW_LED2")
			(options
				(clearance outline)
				(anchor circle)
			)
			(primitives
				(gr_poly
					(pts
						(arc
							(start -0.1778 -0.2794)
							(mid -0.249642 -0.249642)
							(end -0.2794 -0.1778)
						)
						(arc
							(start -0.2794 0.1778)
							(mid -0.249642 0.249642)
							(end -0.1778 0.2794)
						)
						(arc
							(start 0.1778 0.2794)
							(mid 0.249642 0.249642)
							(end 0.2794 0.1778)
						)
						(arc
							(start 0.2794 -0.1778)
							(mid 0.249642 -0.249642)
							(end 0.1778 -0.2794)
						)
					)
					(width 0)
					(fill yes)
				)
			)
		)
		(pad "2" smd custom
			(at 0 0.4445 270)
			(size 0.1397 0.1397)
			(layers "F.Cu" "F.Mask" "F.Paste")
			(net "FAN_LED2_D2")
			(options
				(clearance outline)
				(anchor circle)
			)
			(primitives
				(gr_poly
					(pts
						(arc
							(start -0.1778 -0.2794)
							(mid -0.249642 -0.249642)
							(end -0.2794 -0.1778)
						)
						(arc
							(start -0.2794 0.1778)
							(mid -0.249642 0.249642)
							(end -0.1778 0.2794)
						)
						(arc
							(start 0.1778 0.2794)
							(mid 0.249642 0.249642)
							(end 0.2794 0.1778)
						)
						(arc
							(start 0.2794 -0.1778)
							(mid 0.249642 -0.249642)
							(end 0.1778 -0.2794)
						)
					)
					(width 0)
					(fill yes)
				)
			)
		)
	)
	(footprint ""
		(layer "F.Cu")
		(at 159.324802 -293.799768)
		(property "Reference" ""
			(at 0 0 0)
			(layer "F.SilkS")
			(hide yes)
			(effects
				(font
					(size 1.27 1.27)
				)
			)
		)
		(property "Value" "*"
			(at -8.398764 -8.057642 0)
			(unlocked yes)
			(layer "F.Fab")
			(hide yes)
			(effects
				(font
					(size 1.016 1.016)
					(thickness 0.1524)
				)
			)
		)
		(duplicate_pad_numbers_are_jumpers no)
		(fp_poly
			(pts
				(arc
					(start 7.3152 0)
					(mid 0 7.3152)
					(end -7.3152 0)
				)
				(arc
					(start -7.3152 -5.9944)
					(mid 0 -13.3096)
					(end 7.3152 -5.9944)
				)
			)
			(stroke
				(width 0)
				(type default)
			)
			(fill no)
			(layer "B.CrtYd")
		)
		(fp_poly
			(pts
				(arc
					(start 7.3152 0)
					(mid 0 7.3152)
					(end -7.3152 0)
				)
				(arc
					(start -7.3152 -5.9944)
					(mid 0 -13.3096)
					(end 7.3152 -5.9944)
				)
			)
			(stroke
				(width 0)
				(type default)
			)
			(fill no)
			(layer "F.CrtYd")
		)
		(fp_poly
			(pts
				(arc
					(start 7.3152 0)
					(mid 0 7.3152)
					(end -7.3152 0)
				)
				(arc
					(start -7.3152 -5.9944)
					(mid 0 -13.3096)
					(end 7.3152 -5.9944)
				)
			)
			(stroke
				(width 0)
				(type default)
			)
			(fill no)
			(layer "B.Fab")
		)
		(fp_poly
			(pts
				(arc
					(start 7.3152 0)
					(mid 0 7.3152)
					(end -7.3152 0)
				)
				(arc
					(start -7.3152 -5.9944)
					(mid 0 -13.3096)
					(end 7.3152 -5.9944)
				)
			)
			(stroke
				(width 0)
				(type default)
			)
			(fill no)
			(layer "F.Fab")
		)
		(pad "1" thru_hole oval
			(at 0 0)
			(size 14.0208 20.0152)
			(drill 0.0254
				(offset 0 -2.9972)
			)
			(layers "*.Cu" "*.Mask")
			(remove_unused_layers no)
			(net "Net_39")
			(clearance -1.002284)
			(thermal_gap 0.1524)
			(padstack
				(mode front_inner_back)
				(layer "Inner"
					(shape custom)
					(size 2.928012 2.928012)
					(options
						(anchor circle)
					)
					(primitives
						(gr_poly
							(pts
								(arc
									(start 4.571746 -2.084324)
									(mid 0.000333 7.430372)
									(end -4.571492 -2.084324)
								)
								(arc
									(start -4.571492 -2.084324)
									(mid -3.570296 -3.611977)
									(end -2.875026 -5.30098)
								)
								(arc
									(start -2.875026 -5.30098)
									(mid 0.000217 -7.43089)
									(end 2.87528 -5.30098)
								)
								(arc
									(start 2.87528 -5.30098)
									(mid 3.570511 -3.611956)
									(end 4.571746 -2.084324)
								)
							)
							(width 0)
							(fill yes)
						)
					)
					(clearance 0.1524)
				)
				(layer "B.Cu"
					(shape oval)
					(size 14.0208 20.0152)
					(offset 0 -2.9972)
					(clearance -1.002284)
				)
			)
		)
		(zone
			(layers "F.Cu" "B.Cu" "In1.Cu" "In2.Cu" "In3.Cu" "In4.Cu" "In5.Cu" "In6.Cu")
			(hatch none 0.5)
			(connect_pads
				(clearance 0)
			)
			(min_thickness 0.25)
			(keepout
				(tracks not_allowed)
				(vias allowed)
				(pads allowed)
				(copperpour not_allowed)
				(footprints allowed)
			)
			(placement
				(enabled no)
				(sheetname "")
			)
			(fill
				(thermal_gap 0.5)
				(thermal_bridge_width 0.5)
				(island_removal_mode 0)
			)
			(polygon
				(pts
					(arc
						(start 152.314402 -299.794168)
						(mid 159.324802 -306.804568)
						(end 166.335202 -299.794168)
					)
					(arc
						(start 166.335202 -293.799768)
						(mid 159.324802 -286.789368)
						(end 152.314402 -293.799768)
					)
				)
			)
		)
	)
	(footprint ""
		(layer "F.Cu")
		(at 239.268 -226.06 -90)
		(property "Reference" "C18"
			(at 0 0 270)
			(layer "F.SilkS")
			(hide yes)
			(effects
				(font
					(size 1.27 1.27)
				)
			)
		)
		(property "Value" "SCD1U16V2KX-3GP"
			(at 1.1811 -2.7051 270)
			(unlocked yes)
			(layer "F.Fab")
			(hide yes)
			(effects
				(font
					(size 1.016 1.016)
					(thickness 0.1524)
				)
			)
		)
		(property "Device Type" "C402H22"
			(at 1.1811 -4.2291 270)
			(unlocked yes)
			(layer "F.Fab")
			(hide yes)
			(effects
				(font
					(size 1.016 1.016)
					(thickness 0.1524)
				)
			)
		)
		(duplicate_pad_numbers_are_jumpers no)
		(fp_rect
			(start -0.4318 0.9525)
			(end 0.4318 -0.9525)
			(stroke
				(width 0)
				(type default)
			)
			(fill no)
			(layer "F.CrtYd")
		)
		(fp_rect
			(start -0.4318 0.9525)
			(end 0.4318 -0.9525)
			(stroke
				(width 0)
				(type default)
			)
			(fill no)
			(layer "F.Fab")
		)
		(pad "1" smd custom
			(at 0 -0.4445 270)
			(size 0.1524 0.1524)
			(layers "F.Cu" "F.Mask" "F.Paste")
			(net "GPIO_VCC_U10")
			(options
				(clearance outline)
				(anchor circle)
			)
			(primitives
				(gr_poly
					(pts
						(arc
							(start 0.3048 -0.2032)
							(mid 0.275042 -0.275042)
							(end 0.2032 -0.3048)
						)
						(arc
							(start -0.2032 -0.3048)
							(mid -0.275042 -0.275042)
							(end -0.3048 -0.2032)
						)
						(arc
							(start -0.3048 0.2032)
							(mid -0.275042 0.275042)
							(end -0.2032 0.3048)
						)
						(arc
							(start 0.2032 0.3048)
							(mid 0.275042 0.275042)
							(end 0.3048 0.2032)
						)
					)
					(width 0)
					(fill yes)
				)
			)
		)
		(pad "2" smd custom
			(at 0 0.4445 270)
			(size 0.1524 0.1524)
			(layers "F.Cu" "F.Mask" "F.Paste")
			(net "GND")
			(options
				(clearance outline)
				(anchor circle)
			)
			(primitives
				(gr_poly
					(pts
						(arc
							(start 0.3048 -0.2032)
							(mid 0.275042 -0.275042)
							(end 0.2032 -0.3048)
						)
						(arc
							(start -0.2032 -0.3048)
							(mid -0.275042 -0.275042)
							(end -0.3048 -0.2032)
						)
						(arc
							(start -0.3048 0.2032)
							(mid -0.275042 0.275042)
							(end -0.2032 0.3048)
						)
						(arc
							(start 0.2032 0.3048)
							(mid 0.275042 0.275042)
							(end 0.3048 0.2032)
						)
					)
					(width 0)
					(fill yes)
				)
			)
		)
	)
	(footprint ""
		(layer "F.Cu")
		(at 190.213488 -129.66065 90)
		(property "Reference" "C250"
			(at 0 0 90)
			(layer "F.SilkS")
			(hide yes)
			(effects
				(font
					(size 1.27 1.27)
				)
			)
		)
		(property "Value" "SCD01U16V1KX-GP"
			(at -2.8321 -1.7399 90)
			(unlocked yes)
			(layer "F.Fab")
			(hide yes)
			(effects
				(font
					(size 1.016 1.016)
					(thickness 0.1524)
				)
			)
		)
		(property "Device Type" "C0201H13"
			(at -2.8321 -3.2639 90)
			(unlocked yes)
			(layer "F.Fab")
			(hide yes)
			(effects
				(font
					(size 1.016 1.016)
					(thickness 0.1524)
				)
			)
		)
		(duplicate_pad_numbers_are_jumpers no)
		(fp_rect
			(start -0.2794 0.6477)
			(end 0.2794 -0.6477)
			(stroke
				(width 0)
				(type default)
			)
			(fill no)
			(layer "F.CrtYd")
		)
		(fp_rect
			(start -0.2794 0.6477)
			(end 0.2794 -0.6477)
			(stroke
				(width 0)
				(type default)
			)
			(fill no)
			(layer "F.Fab")
		)
		(pad "1" smd custom
			(at 0 -0.2794 90)
			(size 0.0762 0.0762)
			(layers "F.Cu" "F.Mask" "F.Paste")
			(net "SAS_HDD_RX_P17")
			(options
				(clearance outline)
				(anchor circle)
			)
			(primitives
				(gr_poly
					(pts
						(arc
							(start 0.1524 -0.127)
							(mid 0.137521 -0.162921)
							(end 0.1016 -0.1778)
						)
						(arc
							(start -0.1016 -0.1778)
							(mid -0.137521 -0.162921)
							(end -0.1524 -0.127)
						)
						(arc
							(start -0.1524 0.127)
							(mid -0.137521 0.162921)
							(end -0.1016 0.1778)
						)
						(arc
							(start 0.1016 0.1778)
							(mid 0.137521 0.162921)
							(end 0.1524 0.127)
						)
					)
					(width 0)
					(fill yes)
				)
			)
		)
		(pad "2" smd custom
			(at 0 0.2794 90)
			(size 0.0762 0.0762)
			(layers "F.Cu" "F.Mask" "F.Paste")
			(net "PHY_SCC_B_TO_DRV_B_17_DP")
			(options
				(clearance outline)
				(anchor circle)
			)
			(primitives
				(gr_poly
					(pts
						(arc
							(start 0.1524 -0.127)
							(mid 0.137521 -0.162921)
							(end 0.1016 -0.1778)
						)
						(arc
							(start -0.1016 -0.1778)
							(mid -0.137521 -0.162921)
							(end -0.1524 -0.127)
						)
						(arc
							(start -0.1524 0.127)
							(mid -0.137521 0.162921)
							(end -0.1016 0.1778)
						)
						(arc
							(start 0.1016 0.1778)
							(mid 0.137521 0.162921)
							(end 0.1524 0.127)
						)
					)
					(width 0)
					(fill yes)
				)
			)
		)
	)
	(footprint ""
		(layer "F.Cu")
		(at 14.859 -139.446 -90)
		(property "Reference" "R361"
			(at 0 0 270)
			(layer "F.SilkS")
			(hide yes)
			(effects
				(font
					(size 1.27 1.27)
				)
			)
		)
		(property "Value" "300KR2F-GP"
			(at 0.064008 -3.993896 270)
			(unlocked yes)
			(layer "F.Fab")
			(hide yes)
			(effects
				(font
					(size 1.016 1.016)
					(thickness 0.1524)
				)
			)
		)
		(property "Device Type" "R402H16"
			(at 0.064008 -5.517896 270)
			(unlocked yes)
			(layer "F.Fab")
			(hide yes)
			(effects
				(font
					(size 1.016 1.016)
					(thickness 0.1524)
				)
			)
		)
		(duplicate_pad_numbers_are_jumpers no)
		(fp_line
			(start -0.508 -0.9398)
			(end -0.508 0.9398)
			(stroke
				(width 0.1524)
				(type default)
			)
			(layer "F.SilkS")
		)
		(fp_line
			(start 0.508 -0.9398)
			(end -0.508 -0.9398)
			(stroke
				(width 0.1524)
				(type default)
			)
			(layer "F.SilkS")
		)
		(fp_rect
			(start -0.508 0.9398)
			(end 0.508 -0.9398)
			(stroke
				(width 0)
				(type default)
			)
			(fill no)
			(layer "F.CrtYd")
		)
		(fp_rect
			(start -0.508 0.9398)
			(end 0.508 -0.9398)
			(stroke
				(width 0)
				(type default)
			)
			(fill no)
			(layer "F.Fab")
		)
		(pad "1" smd custom
			(at 0 -0.4445 270)
			(size 0.1397 0.1397)
			(layers "F.Cu" "F.Mask" "F.Paste")
			(net "SW_HDD_N12")
			(options
				(clearance outline)
				(anchor circle)
			)
			(primitives
				(gr_poly
					(pts
						(arc
							(start -0.1778 -0.2794)
							(mid -0.249642 -0.249642)
							(end -0.2794 -0.1778)
						)
						(arc
							(start -0.2794 0.1778)
							(mid -0.249642 0.249642)
							(end -0.1778 0.2794)
						)
						(arc
							(start 0.1778 0.2794)
							(mid 0.249642 0.249642)
							(end 0.2794 0.1778)
						)
						(arc
							(start 0.2794 -0.1778)
							(mid 0.249642 -0.249642)
							(end 0.1778 -0.2794)
						)
					)
					(width 0)
					(fill yes)
				)
			)
		)
		(pad "2" smd custom
			(at 0 0.4445 270)
			(size 0.1397 0.1397)
			(layers "F.Cu" "F.Mask" "F.Paste")
			(net "P12V_B")
			(options
				(clearance outline)
				(anchor circle)
			)
			(primitives
				(gr_poly
					(pts
						(arc
							(start -0.1778 -0.2794)
							(mid -0.249642 -0.249642)
							(end -0.2794 -0.1778)
						)
						(arc
							(start -0.2794 0.1778)
							(mid -0.249642 0.249642)
							(end -0.1778 0.2794)
						)
						(arc
							(start 0.1778 0.2794)
							(mid 0.249642 0.249642)
							(end 0.2794 0.1778)
						)
						(arc
							(start 0.2794 -0.1778)
							(mid 0.249642 -0.249642)
							(end 0.1778 -0.2794)
						)
					)
					(width 0)
					(fill yes)
				)
			)
		)
	)
	(footprint ""
		(layer "F.Cu")
		(at 259.6515 -379.174756 -90)
		(property "Reference" "R1067"
			(at 0 0 270)
			(layer "F.SilkS")
			(hide yes)
			(effects
				(font
					(size 1.27 1.27)
				)
			)
		)
		(property "Value" "0R2J-2-GP"
			(at 0.064008 -3.993896 270)
			(unlocked yes)
			(layer "F.Fab")
			(hide yes)
			(effects
				(font
					(size 1.016 1.016)
					(thickness 0.1524)
				)
			)
		)
		(property "Device Type" "R402H16"
			(at 0.064008 -5.517896 270)
			(unlocked yes)
			(layer "F.Fab")
			(hide yes)
			(effects
				(font
					(size 1.016 1.016)
					(thickness 0.1524)
				)
			)
		)
		(duplicate_pad_numbers_are_jumpers no)
		(fp_line
			(start -0.508 -0.9398)
			(end -0.508 0.9398)
			(stroke
				(width 0.1524)
				(type default)
			)
			(layer "F.SilkS")
		)
		(fp_line
			(start 0.508 -0.9398)
			(end -0.508 -0.9398)
			(stroke
				(width 0.1524)
				(type default)
			)
			(layer "F.SilkS")
		)
		(fp_rect
			(start -0.508 0.9398)
			(end 0.508 -0.9398)
			(stroke
				(width 0)
				(type default)
			)
			(fill no)
			(layer "F.CrtYd")
		)
		(fp_rect
			(start -0.508 0.9398)
			(end 0.508 -0.9398)
			(stroke
				(width 0)
				(type default)
			)
			(fill no)
			(layer "F.Fab")
		)
		(pad "1" smd custom
			(at 0 -0.4445 270)
			(size 0.1397 0.1397)
			(layers "F.Cu" "F.Mask" "F.Paste")
			(net "DRAWER_OUT#_C")
			(options
				(clearance outline)
				(anchor circle)
			)
			(primitives
				(gr_poly
					(pts
						(arc
							(start -0.1778 -0.2794)
							(mid -0.249642 -0.249642)
							(end -0.2794 -0.1778)
						)
						(arc
							(start -0.2794 0.1778)
							(mid -0.249642 0.249642)
							(end -0.1778 0.2794)
						)
						(arc
							(start 0.1778 0.2794)
							(mid 0.249642 0.249642)
							(end 0.2794 0.1778)
						)
						(arc
							(start 0.2794 -0.1778)
							(mid 0.249642 -0.249642)
							(end 0.1778 -0.2794)
						)
					)
					(width 0)
					(fill yes)
				)
			)
		)
		(pad "2" smd custom
			(at 0 0.4445 270)
			(size 0.1397 0.1397)
			(layers "F.Cu" "F.Mask" "F.Paste")
			(net "DRAWER_MOSFET_G")
			(options
				(clearance outline)
				(anchor circle)
			)
			(primitives
				(gr_poly
					(pts
						(arc
							(start -0.1778 -0.2794)
							(mid -0.249642 -0.249642)
							(end -0.2794 -0.1778)
						)
						(arc
							(start -0.2794 0.1778)
							(mid -0.249642 0.249642)
							(end -0.1778 0.2794)
						)
						(arc
							(start 0.1778 0.2794)
							(mid 0.249642 0.249642)
							(end 0.2794 0.1778)
						)
						(arc
							(start 0.2794 -0.1778)
							(mid 0.249642 -0.249642)
							(end 0.1778 -0.2794)
						)
					)
					(width 0)
					(fill yes)
				)
			)
		)
	)
	(footprint ""
		(layer "F.Cu")
		(at 362.966 -147.066 -90)
		(property "Reference" "R506"
			(at 0 0 270)
			(layer "F.SilkS")
			(hide yes)
			(effects
				(font
					(size 1.27 1.27)
				)
			)
		)
		(property "Value" "2R6F-GP"
			(at -0.0508 -4.8514 270)
			(unlocked yes)
			(layer "F.Fab")
			(hide yes)
			(effects
				(font
					(size 1.016 1.016)
					(thickness 0.1524)
				)
			)
		)
		(property "Device Type" "R1206H26"
			(at 0 -6.3754 270)
			(unlocked yes)
			(layer "F.Fab")
			(hide yes)
			(effects
				(font
					(size 1.016 1.016)
					(thickness 0.1524)
				)
			)
		)
		(duplicate_pad_numbers_are_jumpers no)
		(fp_line
			(start -1.016 2.2352)
			(end -1.016 -2.2352)
			(stroke
				(width 0.1524)
				(type default)
			)
			(layer "F.SilkS")
		)
		(fp_line
			(start 1.016 2.2352)
			(end -1.016 2.2352)
			(stroke
				(width 0.1524)
				(type default)
			)
			(layer "F.SilkS")
		)
		(fp_line
			(start -1.016 -2.2352)
			(end 1.016 -2.2352)
			(stroke
				(width 0.1524)
				(type default)
			)
			(layer "F.SilkS")
		)
		(fp_line
			(start 1.016 -2.2352)
			(end 1.016 2.2352)
			(stroke
				(width 0.1524)
				(type default)
			)
			(layer "F.SilkS")
		)
		(fp_rect
			(start -1.0922 2.3114)
			(end 1.0922 -2.3114)
			(stroke
				(width 0)
				(type default)
			)
			(fill no)
			(layer "F.CrtYd")
		)
		(fp_poly
			(pts
				(xy -1.0922 -2.3114) (xy 1.0922 -2.3114) (xy 1.0922 2.3114) (xy -1.0922 2.3114)
			)
			(stroke
				(width 0)
				(type default)
			)
			(fill no)
			(layer "F.Fab")
		)
		(pad "1" smd rect
			(at 0 -1.397 270)
			(size 1.651 1.27)
			(layers "F.Cu" "F.Mask" "F.Paste")
			(net "P5V_HDD19")
		)
		(pad "2" smd rect
			(at 0 1.397 270)
			(size 1.651 1.27)
			(layers "F.Cu" "F.Mask" "F.Paste")
			(net "5V_PRE_19")
		)
	)
	(footprint ""
		(layer "F.Cu")
		(at 50.546 -265.684 90)
		(property "Reference" "R177"
			(at 0 0 90)
			(layer "F.SilkS")
			(hide yes)
			(effects
				(font
					(size 1.27 1.27)
				)
			)
		)
		(property "Value" "2R6F-GP"
			(at -0.0508 -4.8514 90)
			(unlocked yes)
			(layer "F.Fab")
			(hide yes)
			(effects
				(font
					(size 1.016 1.016)
					(thickness 0.1524)
				)
			)
		)
		(property "Device Type" "R1206H26"
			(at 0 -6.3754 90)
			(unlocked yes)
			(layer "F.Fab")
			(hide yes)
			(effects
				(font
					(size 1.016 1.016)
					(thickness 0.1524)
				)
			)
		)
		(duplicate_pad_numbers_are_jumpers no)
		(fp_line
			(start 1.016 -2.2352)
			(end 1.016 2.2352)
			(stroke
				(width 0.1524)
				(type default)
			)
			(layer "F.SilkS")
		)
		(fp_line
			(start -1.016 -2.2352)
			(end 1.016 -2.2352)
			(stroke
				(width 0.1524)
				(type default)
			)
			(layer "F.SilkS")
		)
		(fp_line
			(start 1.016 2.2352)
			(end -1.016 2.2352)
			(stroke
				(width 0.1524)
				(type default)
			)
			(layer "F.SilkS")
		)
		(fp_line
			(start -1.016 2.2352)
			(end -1.016 -2.2352)
			(stroke
				(width 0.1524)
				(type default)
			)
			(layer "F.SilkS")
		)
		(fp_rect
			(start -1.0922 2.3114)
			(end 1.0922 -2.3114)
			(stroke
				(width 0)
				(type default)
			)
			(fill no)
			(layer "F.CrtYd")
		)
		(fp_poly
			(pts
				(xy -1.0922 -2.3114) (xy 1.0922 -2.3114) (xy 1.0922 2.3114) (xy -1.0922 2.3114)
			)
			(stroke
				(width 0)
				(type default)
			)
			(fill no)
			(layer "F.Fab")
		)
		(pad "1" smd rect
			(at 0 -1.397 90)
			(size 1.651 1.27)
			(layers "F.Cu" "F.Mask" "F.Paste")
			(net "P12V_HDD1")
		)
		(pad "2" smd rect
			(at 0 1.397 90)
			(size 1.651 1.27)
			(layers "F.Cu" "F.Mask" "F.Paste")
			(net "12V_PRE_1")
		)
	)
	(footprint ""
		(layer "F.Cu")
		(at 19.701002 -229.49535 180)
		(property "Reference" "R1115"
			(at 0 0 180)
			(layer "F.SilkS")
			(hide yes)
			(effects
				(font
					(size 1.27 1.27)
				)
			)
		)
		(property "Value" "619KR2F-GP"
			(at 0.064008 -3.993896 180)
			(unlocked yes)
			(layer "F.Fab")
			(hide yes)
			(effects
				(font
					(size 1.016 1.016)
					(thickness 0.1524)
				)
			)
		)
		(property "Device Type" "R402H16"
			(at 0.064008 -5.517896 180)
			(unlocked yes)
			(layer "F.Fab")
			(hide yes)
			(effects
				(font
					(size 1.016 1.016)
					(thickness 0.1524)
				)
			)
		)
		(duplicate_pad_numbers_are_jumpers no)
		(fp_line
			(start 0.508 -0.9398)
			(end -0.508 -0.9398)
			(stroke
				(width 0.1524)
				(type default)
			)
			(layer "F.SilkS")
		)
		(fp_line
			(start -0.508 -0.9398)
			(end -0.508 0.9398)
			(stroke
				(width 0.1524)
				(type default)
			)
			(layer "F.SilkS")
		)
		(fp_rect
			(start -0.508 0.9398)
			(end 0.508 -0.9398)
			(stroke
				(width 0)
				(type default)
			)
			(fill no)
			(layer "F.CrtYd")
		)
		(fp_rect
			(start -0.508 0.9398)
			(end 0.508 -0.9398)
			(stroke
				(width 0)
				(type default)
			)
			(fill no)
			(layer "F.Fab")
		)
		(pad "1" smd custom
			(at 0 -0.4445 180)
			(size 0.1397 0.1397)
			(layers "F.Cu" "F.Mask" "F.Paste")
			(net "P5V_B_1_RF")
			(options
				(clearance outline)
				(anchor circle)
			)
			(primitives
				(gr_poly
					(pts
						(arc
							(start -0.1778 -0.2794)
							(mid -0.249642 -0.249642)
							(end -0.2794 -0.1778)
						)
						(arc
							(start -0.2794 0.1778)
							(mid -0.249642 0.249642)
							(end -0.1778 0.2794)
						)
						(arc
							(start 0.1778 0.2794)
							(mid 0.249642 0.249642)
							(end 0.2794 0.1778)
						)
						(arc
							(start 0.2794 -0.1778)
							(mid 0.249642 -0.249642)
							(end 0.1778 -0.2794)
						)
					)
					(width 0)
					(fill yes)
				)
			)
		)
		(pad "2" smd custom
			(at 0 0.4445 180)
			(size 0.1397 0.1397)
			(layers "F.Cu" "F.Mask" "F.Paste")
			(net "AGND_P5V_B_1")
			(options
				(clearance outline)
				(anchor circle)
			)
			(primitives
				(gr_poly
					(pts
						(arc
							(start -0.1778 -0.2794)
							(mid -0.249642 -0.249642)
							(end -0.2794 -0.1778)
						)
						(arc
							(start -0.2794 0.1778)
							(mid -0.249642 0.249642)
							(end -0.1778 0.2794)
						)
						(arc
							(start 0.1778 0.2794)
							(mid 0.249642 0.249642)
							(end 0.2794 0.1778)
						)
						(arc
							(start 0.2794 -0.1778)
							(mid 0.249642 -0.249642)
							(end 0.1778 -0.2794)
						)
					)
					(width 0)
					(fill yes)
				)
			)
		)
	)
	(footprint ""
		(layer "F.Cu")
		(at 339.743796 -99.860354 90)
		(property "Reference" "Q266"
			(at 0 0 90)
			(layer "F.SilkS")
			(hide yes)
			(effects
				(font
					(size 1.27 1.27)
				)
			)
		)
		(property "Value" "SSM3K324R-GP"
			(at 0.127 -8.9662 90)
			(unlocked yes)
			(layer "F.Fab")
			(hide yes)
			(effects
				(font
					(size 1.016 1.016)
					(thickness 0.1524)
				)
			)
		)
		(property "Device Type" "SOT23DGS2D4H35"
			(at 0.127 -10.4902 90)
			(unlocked yes)
			(layer "F.Fab")
			(hide yes)
			(effects
				(font
					(size 1.016 1.016)
					(thickness 0.1524)
				)
			)
		)
		(duplicate_pad_numbers_are_jumpers no)
		(fp_line
			(start 1.651 -1.778)
			(end -1.651 -1.778)
			(stroke
				(width 0.1524)
				(type default)
			)
			(layer "F.SilkS")
		)
		(fp_line
			(start -1.651 -1.778)
			(end -1.651 1.778)
			(stroke
				(width 0.1524)
				(type default)
			)
			(layer "F.SilkS")
		)
		(fp_line
			(start 1.651 1.778)
			(end 1.651 -1.778)
			(stroke
				(width 0.1524)
				(type default)
			)
			(layer "F.SilkS")
		)
		(fp_line
			(start -1.651 1.778)
			(end 1.651 1.778)
			(stroke
				(width 0.1524)
				(type default)
			)
			(layer "F.SilkS")
		)
		(fp_poly
			(pts
				(xy -1.778 1.8796) (xy -1.778 -1.8796) (xy 1.778 -1.8796) (xy 1.778 1.8796)
			)
			(stroke
				(width 0)
				(type default)
			)
			(fill no)
			(layer "F.CrtYd")
		)
		(fp_poly
			(pts
				(xy -1.778 1.8796) (xy -1.778 -1.8796) (xy 1.778 -1.8796) (xy 1.778 1.8796)
			)
			(stroke
				(width 0)
				(type default)
			)
			(fill no)
			(layer "F.Fab")
		)
		(pad "D" smd custom
			(at 0 -0.9525 90)
			(size 0.1905 0.1905)
			(layers "F.Cu" "F.Mask" "F.Paste")
			(net "DRV_ACT_19_N")
			(options
				(clearance outline)
				(anchor circle)
			)
			(primitives
				(gr_poly
					(pts
						(arc
							(start -0.1778 0.5715)
							(mid -0.321484 0.511984)
							(end -0.381 0.3683)
						)
						(arc
							(start -0.381 -0.3683)
							(mid -0.321484 -0.511984)
							(end -0.1778 -0.5715)
						)
						(arc
							(start 0.1778 -0.5715)
							(mid 0.321484 -0.511984)
							(end 0.381 -0.3683)
						)
						(arc
							(start 0.381 0.3683)
							(mid 0.321484 0.511984)
							(end 0.1778 0.5715)
						)
					)
					(width 0)
					(fill yes)
				)
			)
		)
		(pad "G" smd custom
			(at -0.98425 0.9525 90)
			(size 0.1905 0.1905)
			(layers "F.Cu" "F.Mask" "F.Paste")
			(net "DRIVE_B_19_ACT")
			(options
				(clearance outline)
				(anchor circle)
			)
			(primitives
				(gr_poly
					(pts
						(arc
							(start -0.1778 0.5715)
							(mid -0.321484 0.511984)
							(end -0.381 0.3683)
						)
						(arc
							(start -0.381 -0.3683)
							(mid -0.321484 -0.511984)
							(end -0.1778 -0.5715)
						)
						(arc
							(start 0.1778 -0.5715)
							(mid 0.321484 -0.511984)
							(end 0.381 -0.3683)
						)
						(arc
							(start 0.381 0.3683)
							(mid 0.321484 0.511984)
							(end 0.1778 0.5715)
						)
					)
					(width 0)
					(fill yes)
				)
			)
		)
		(pad "S" smd custom
			(at 0.98425 0.9525 90)
			(size 0.1905 0.1905)
			(layers "F.Cu" "F.Mask" "F.Paste")
			(net "GND")
			(options
				(clearance outline)
				(anchor circle)
			)
			(primitives
				(gr_poly
					(pts
						(arc
							(start -0.1778 0.5715)
							(mid -0.321484 0.511984)
							(end -0.381 0.3683)
						)
						(arc
							(start -0.381 -0.3683)
							(mid -0.321484 -0.511984)
							(end -0.1778 -0.5715)
						)
						(arc
							(start 0.1778 -0.5715)
							(mid 0.321484 -0.511984)
							(end 0.381 -0.3683)
						)
						(arc
							(start 0.381 0.3683)
							(mid 0.321484 0.511984)
							(end 0.1778 0.5715)
						)
					)
					(width 0)
					(fill yes)
				)
			)
		)
	)
	(footprint ""
		(layer "F.Cu")
		(at 261.915402 -372.907814 180)
		(property "Reference" "Q209"
			(at 0 0 180)
			(layer "F.SilkS")
			(hide yes)
			(effects
				(font
					(size 1.27 1.27)
				)
			)
		)
		(property "Value" "2N7002K-2-GP"
			(at 0.127 -8.9662 180)
			(unlocked yes)
			(layer "F.Fab")
			(hide yes)
			(effects
				(font
					(size 1.016 1.016)
					(thickness 0.1524)
				)
			)
		)
		(property "Device Type" "SOT23DGS2D4H44"
			(at 0.127 -10.4902 180)
			(unlocked yes)
			(layer "F.Fab")
			(hide yes)
			(effects
				(font
					(size 1.016 1.016)
					(thickness 0.1524)
				)
			)
		)
		(duplicate_pad_numbers_are_jumpers no)
		(fp_line
			(start 1.651 1.778)
			(end 1.651 -1.778)
			(stroke
				(width 0.1524)
				(type default)
			)
			(layer "F.SilkS")
		)
		(fp_line
			(start 1.651 -1.778)
			(end -1.651 -1.778)
			(stroke
				(width 0.1524)
				(type default)
			)
			(layer "F.SilkS")
		)
		(fp_line
			(start -1.651 1.778)
			(end 1.651 1.778)
			(stroke
				(width 0.1524)
				(type default)
			)
			(layer "F.SilkS")
		)
		(fp_line
			(start -1.651 -1.778)
			(end -1.651 1.778)
			(stroke
				(width 0.1524)
				(type default)
			)
			(layer "F.SilkS")
		)
		(fp_poly
			(pts
				(xy -1.778 1.8796) (xy -1.778 -1.8796) (xy 1.778 -1.8796) (xy 1.778 1.8796)
			)
			(stroke
				(width 0)
				(type default)
			)
			(fill no)
			(layer "F.CrtYd")
		)
		(fp_poly
			(pts
				(xy -1.778 1.8796) (xy -1.778 -1.8796) (xy 1.778 -1.8796) (xy 1.778 1.8796)
			)
			(stroke
				(width 0)
				(type default)
			)
			(fill no)
			(layer "F.Fab")
		)
		(pad "D" smd custom
			(at 0 -0.9525 180)
			(size 0.1905 0.1905)
			(layers "F.Cu" "F.Mask" "F.Paste")
			(net "DRAWER_CLOSED_N")
			(options
				(clearance outline)
				(anchor circle)
			)
			(primitives
				(gr_poly
					(pts
						(arc
							(start -0.1778 0.5715)
							(mid -0.321484 0.511984)
							(end -0.381 0.3683)
						)
						(arc
							(start -0.381 -0.3683)
							(mid -0.321484 -0.511984)
							(end -0.1778 -0.5715)
						)
						(arc
							(start 0.1778 -0.5715)
							(mid 0.321484 -0.511984)
							(end 0.381 -0.3683)
						)
						(arc
							(start 0.381 0.3683)
							(mid 0.321484 0.511984)
							(end 0.1778 0.5715)
						)
					)
					(width 0)
					(fill yes)
				)
			)
		)
		(pad "G" smd custom
			(at -0.98425 0.9525 180)
			(size 0.1905 0.1905)
			(layers "F.Cu" "F.Mask" "F.Paste")
			(net "DRAWER_MOSFET_G")
			(options
				(clearance outline)
				(anchor circle)
			)
			(primitives
				(gr_poly
					(pts
						(arc
							(start -0.1778 0.5715)
							(mid -0.321484 0.511984)
							(end -0.381 0.3683)
						)
						(arc
							(start -0.381 -0.3683)
							(mid -0.321484 -0.511984)
							(end -0.1778 -0.5715)
						)
						(arc
							(start 0.1778 -0.5715)
							(mid 0.321484 -0.511984)
							(end 0.381 -0.3683)
						)
						(arc
							(start 0.381 0.3683)
							(mid 0.321484 0.511984)
							(end 0.1778 0.5715)
						)
					)
					(width 0)
					(fill yes)
				)
			)
		)
		(pad "S" smd custom
			(at 0.98425 0.9525 180)
			(size 0.1905 0.1905)
			(layers "F.Cu" "F.Mask" "F.Paste")
			(net "GND")
			(options
				(clearance outline)
				(anchor circle)
			)
			(primitives
				(gr_poly
					(pts
						(arc
							(start -0.1778 0.5715)
							(mid -0.321484 0.511984)
							(end -0.381 0.3683)
						)
						(arc
							(start -0.381 -0.3683)
							(mid -0.321484 -0.511984)
							(end -0.1778 -0.5715)
						)
						(arc
							(start 0.1778 -0.5715)
							(mid 0.321484 -0.511984)
							(end 0.381 -0.3683)
						)
						(arc
							(start 0.381 0.3683)
							(mid 0.321484 0.511984)
							(end 0.1778 0.5715)
						)
					)
					(width 0)
					(fill yes)
				)
			)
		)
	)
	(footprint ""
		(layer "F.Cu")
		(at 479.298 -275.463 180)
		(property "Reference" "C180"
			(at 0 0 180)
			(layer "F.SilkS")
			(hide yes)
			(effects
				(font
					(size 1.27 1.27)
				)
			)
		)
		(property "Value" "SC1U25V3KX-GP"
			(at 0 -2.8194 180)
			(unlocked yes)
			(layer "F.Fab")
			(hide yes)
			(effects
				(font
					(size 1.016 1.016)
					(thickness 0.1524)
				)
			)
		)
		(property "Device Type" "C603H36"
			(at 0 -4.3434 180)
			(unlocked yes)
			(layer "F.Fab")
			(hide yes)
			(effects
				(font
					(size 1.016 1.016)
					(thickness 0.1524)
				)
			)
		)
		(duplicate_pad_numbers_are_jumpers no)
		(fp_line
			(start 0.508 0)
			(end -0.508 0)
			(stroke
				(width 0.2032)
				(type default)
			)
			(layer "F.SilkS")
		)
		(fp_rect
			(start -0.5842 1.3335)
			(end 0.5842 -1.3335)
			(stroke
				(width 0)
				(type default)
			)
			(fill no)
			(layer "F.CrtYd")
		)
		(fp_rect
			(start -0.5842 1.3335)
			(end 0.5842 -1.3335)
			(stroke
				(width 0)
				(type default)
			)
			(fill no)
			(layer "F.Fab")
		)
		(pad "1" smd custom
			(at 0 -0.762 180)
			(size 0.2159 0.2159)
			(layers "F.Cu" "F.Mask" "F.Paste")
			(net "P12V_HDD11")
			(options
				(clearance outline)
				(anchor circle)
			)
			(primitives
				(gr_poly
					(pts
						(arc
							(start -0.3302 -0.4318)
							(mid -0.402042 -0.402042)
							(end -0.4318 -0.3302)
						)
						(arc
							(start -0.4318 0.3302)
							(mid -0.402042 0.402042)
							(end -0.3302 0.4318)
						)
						(arc
							(start 0.3302 0.4318)
							(mid 0.402042 0.402042)
							(end 0.4318 0.3302)
						)
						(arc
							(start 0.4318 -0.3302)
							(mid 0.402042 -0.402042)
							(end 0.3302 -0.4318)
						)
					)
					(width 0)
					(fill yes)
				)
			)
		)
		(pad "2" smd custom
			(at 0 0.762 180)
			(size 0.2159 0.2159)
			(layers "F.Cu" "F.Mask" "F.Paste")
			(net "GND")
			(options
				(clearance outline)
				(anchor circle)
			)
			(primitives
				(gr_poly
					(pts
						(arc
							(start -0.3302 -0.4318)
							(mid -0.402042 -0.402042)
							(end -0.4318 -0.3302)
						)
						(arc
							(start -0.4318 0.3302)
							(mid -0.402042 0.402042)
							(end -0.3302 0.4318)
						)
						(arc
							(start 0.3302 0.4318)
							(mid 0.402042 0.402042)
							(end 0.4318 0.3302)
						)
						(arc
							(start 0.4318 -0.3302)
							(mid 0.402042 -0.402042)
							(end 0.3302 -0.4318)
						)
					)
					(width 0)
					(fill yes)
				)
			)
		)
	)
	(footprint ""
		(layer "F.Cu")
		(at 362.966 -274.955 180)
		(property "Reference" "C126"
			(at 0 0 180)
			(layer "F.SilkS")
			(hide yes)
			(effects
				(font
					(size 1.27 1.27)
				)
			)
		)
		(property "Value" "SC4D7U25V5KX-1-GP"
			(at -0.0762 -6.1214 180)
			(unlocked yes)
			(layer "F.Fab")
			(hide yes)
			(effects
				(font
					(size 1.016 1.016)
					(thickness 0.1524)
				)
			)
		)
		(property "Device Type" "C805H58"
			(at -0.0762 -8.1534 180)
			(unlocked yes)
			(layer "F.Fab")
			(hide yes)
			(effects
				(font
					(size 1.016 1.016)
					(thickness 0.1524)
				)
			)
		)
		(duplicate_pad_numbers_are_jumpers no)
		(fp_line
			(start 0.635 0)
			(end -0.635 0)
			(stroke
				(width 0.508)
				(type default)
			)
			(layer "F.SilkS")
		)
		(fp_rect
			(start -0.9652 1.778)
			(end 0.9652 -1.778)
			(stroke
				(width 0)
				(type default)
			)
			(fill no)
			(layer "F.CrtYd")
		)
		(fp_poly
			(pts
				(xy -0.9652 -1.778) (xy 0.9652 -1.778) (xy 0.9652 1.778) (xy -0.9652 1.778)
			)
			(stroke
				(width 0)
				(type default)
			)
			(fill no)
			(layer "F.Fab")
		)
		(pad "1" smd rect
			(at 0 -0.9652 180)
			(size 1.397 1.143)
			(layers "F.Cu" "F.Mask" "F.Paste")
			(net "P12V_HDD7")
		)
		(pad "2" smd rect
			(at 0 0.9652 180)
			(size 1.397 1.143)
			(layers "F.Cu" "F.Mask" "F.Paste")
			(net "GND")
		)
	)
	(footprint ""
		(layer "F.Cu")
		(at 146.939 -141.224 180)
		(property "Reference" "Q70"
			(at 0 0 180)
			(layer "F.SilkS")
			(hide yes)
			(effects
				(font
					(size 1.27 1.27)
				)
			)
		)
		(property "Value" "AO4406AL-GP"
			(at -3.707384 -1.5367 180)
			(unlocked yes)
			(layer "F.Fab")
			(hide yes)
			(effects
				(font
					(size 1.016 1.016)
					(thickness 0.1524)
				)
			)
		)
		(property "Device Type" "SOIC8H69"
			(at -3.707384 -3.0607 180)
			(unlocked yes)
			(layer "F.Fab")
			(hide yes)
			(effects
				(font
					(size 1.016 1.016)
					(thickness 0.1524)
				)
			)
		)
		(duplicate_pad_numbers_are_jumpers no)
		(fp_line
			(start 2.1336 1.4224)
			(end 2.1336 -1.4224)
			(stroke
				(width 0.1524)
				(type default)
			)
			(layer "F.SilkS")
		)
		(fp_line
			(start 2.1336 -1.4224)
			(end -2.7432 -1.4224)
			(stroke
				(width 0.1524)
				(type default)
			)
			(layer "F.SilkS")
		)
		(fp_line
			(start -2.1844 -0.0508)
			(end -2.7178 0.508)
			(stroke
				(width 0.1524)
				(type default)
			)
			(layer "F.SilkS")
		)
		(fp_line
			(start -2.6289 3.4417)
			(end -2.6289 1.4732)
			(stroke
				(width 0.381)
				(type default)
			)
			(layer "F.SilkS")
		)
		(fp_line
			(start -2.7178 -0.508)
			(end -2.1844 -0.0508)
			(stroke
				(width 0.1524)
				(type default)
			)
			(layer "F.SilkS")
		)
		(fp_line
			(start -2.7432 1.4224)
			(end 2.1336 1.4224)
			(stroke
				(width 0.1524)
				(type default)
			)
			(layer "F.SilkS")
		)
		(fp_line
			(start -2.7432 1.4224)
			(end -2.6416 1.4224)
			(stroke
				(width 0.1524)
				(type default)
			)
			(layer "F.SilkS")
		)
		(fp_line
			(start -2.7432 -1.4224)
			(end -2.7432 1.4224)
			(stroke
				(width 0.1524)
				(type default)
			)
			(layer "F.SilkS")
		)
		(fp_poly
			(pts
				(xy -2.2098 -1.4224) (xy -2.2098 1.4224) (xy 2.2098 1.4224) (xy 2.2098 -1.4224)
			)
			(stroke
				(width 0)
				(type default)
			)
			(fill yes)
			(layer "F.SilkS")
		)
		(fp_rect
			(start -2.450084 2.999994)
			(end 2.450084 -2.999994)
			(stroke
				(width 0)
				(type default)
			)
			(fill no)
			(layer "F.CrtYd")
		)
		(fp_poly
			(pts
				(xy -2.8194 3.6322) (xy -2.8194 -3.6322) (xy 2.8194 -3.6322) (xy 2.8194 1.18364) (xy 2.450084 1.18364)
				(xy 2.450084 -2.999994) (xy -2.450084 -2.999994) (xy -2.450084 2.999994) (xy 2.450084 2.999994)
				(xy 2.450084 1.18618) (xy 2.8194 1.18618) (xy 2.8194 3.6322)
			)
			(stroke
				(width 0)
				(type default)
			)
			(fill no)
			(layer "F.CrtYd")
		)
		(fp_rect
			(start -2.8194 3.6322)
			(end 2.8194 -3.6322)
			(stroke
				(width 0)
				(type default)
			)
			(fill no)
			(layer "F.Fab")
		)
		(pad "1" smd rect
			(at -1.905 2.54 180)
			(size 0.635 1.651)
			(layers "F.Cu" "F.Mask" "F.Paste")
			(net "P5V_HDD16")
		)
		(pad "2" smd rect
			(at -0.635 2.54 180)
			(size 0.635 1.651)
			(layers "F.Cu" "F.Mask" "F.Paste")
			(net "P5V_HDD16")
		)
		(pad "3" smd rect
			(at 0.635 2.54 180)
			(size 0.635 1.651)
			(layers "F.Cu" "F.Mask" "F.Paste")
			(net "P5V_HDD16")
		)
		(pad "4" smd rect
			(at 1.905 2.54 180)
			(size 0.635 1.651)
			(layers "F.Cu" "F.Mask" "F.Paste")
			(net "SW_HDD_P16")
		)
		(pad "5" smd rect
			(at 1.905 -2.54 180)
			(size 0.635 1.651)
			(layers "F.Cu" "F.Mask" "F.Paste")
			(net "P5V_B_2")
		)
		(pad "6" smd rect
			(at 0.635 -2.54 180)
			(size 0.635 1.651)
			(layers "F.Cu" "F.Mask" "F.Paste")
			(net "P5V_B_2")
		)
		(pad "7" smd rect
			(at -0.635 -2.54 180)
			(size 0.635 1.651)
			(layers "F.Cu" "F.Mask" "F.Paste")
			(net "P5V_B_2")
		)
		(pad "8" smd rect
			(at -1.905 -2.54 180)
			(size 0.635 1.651)
			(layers "F.Cu" "F.Mask" "F.Paste")
			(net "P5V_B_2")
		)
	)
	(footprint ""
		(layer "F.Cu")
		(at 477.0882 -268.2494)
		(property "Reference" "TP76"
			(at 0 0 0)
			(layer "F.SilkS")
			(hide yes)
			(effects
				(font
					(size 1.27 1.27)
				)
			)
		)
		(property "Value" "*"
			(at -0.0508 -1.6764 0)
			(unlocked yes)
			(layer "F.Fab")
			(hide yes)
			(effects
				(font
					(size 1.016 1.016)
					(thickness 0.1524)
				)
			)
		)
		(property "Device Type" "TPAD32"
			(at -0.0508 -3.2004 0)
			(unlocked yes)
			(layer "F.Fab")
			(hide yes)
			(effects
				(font
					(size 1.016 1.016)
					(thickness 0.1524)
				)
			)
		)
		(duplicate_pad_numbers_are_jumpers no)
		(fp_poly
			(pts
				(arc
					(start 0.4064 0)
					(mid -0.4064 0)
					(end 0.4064 0)
				)
			)
			(stroke
				(width 0)
				(type default)
			)
			(fill no)
			(layer "F.CrtYd")
		)
		(fp_poly
			(pts
				(arc
					(start 0.7112 0)
					(mid -0.7112 0)
					(end 0.7112 0)
				)
			)
			(stroke
				(width 0)
				(type default)
			)
			(fill no)
			(layer "F.Fab")
		)
		(pad "1" smd circle
			(at 0 0)
			(size 0.8128 0.8128)
			(layers "F.Cu" "F.Mask" "F.Paste")
			(net "ACT_HDD_11")
		)
	)
	(footprint ""
		(layer "F.Cu")
		(at 300.709076 -340.812882 180)
		(property "Reference" "R102"
			(at 0 0 180)
			(layer "F.SilkS")
			(hide yes)
			(effects
				(font
					(size 1.27 1.27)
				)
			)
		)
		(property "Value" "100KR2F-L1-GP"
			(at 0.064008 -3.993896 180)
			(unlocked yes)
			(layer "F.Fab")
			(hide yes)
			(effects
				(font
					(size 1.016 1.016)
					(thickness 0.1524)
				)
			)
		)
		(property "Device Type" "R402H16"
			(at 0.064008 -5.517896 180)
			(unlocked yes)
			(layer "F.Fab")
			(hide yes)
			(effects
				(font
					(size 1.016 1.016)
					(thickness 0.1524)
				)
			)
		)
		(duplicate_pad_numbers_are_jumpers no)
		(fp_line
			(start 0.508 -0.9398)
			(end -0.508 -0.9398)
			(stroke
				(width 0.1524)
				(type default)
			)
			(layer "F.SilkS")
		)
		(fp_line
			(start -0.508 -0.9398)
			(end -0.508 0.9398)
			(stroke
				(width 0.1524)
				(type default)
			)
			(layer "F.SilkS")
		)
		(fp_rect
			(start -0.508 0.9398)
			(end 0.508 -0.9398)
			(stroke
				(width 0)
				(type default)
			)
			(fill no)
			(layer "F.CrtYd")
		)
		(fp_rect
			(start -0.508 0.9398)
			(end 0.508 -0.9398)
			(stroke
				(width 0)
				(type default)
			)
			(fill no)
			(layer "F.Fab")
		)
		(pad "1" smd custom
			(at 0 -0.4445 180)
			(size 0.1397 0.1397)
			(layers "F.Cu" "F.Mask" "F.Paste")
			(net "PWM_SCC_B_ZONE_C")
			(options
				(clearance outline)
				(anchor circle)
			)
			(primitives
				(gr_poly
					(pts
						(arc
							(start -0.1778 -0.2794)
							(mid -0.249642 -0.249642)
							(end -0.2794 -0.1778)
						)
						(arc
							(start -0.2794 0.1778)
							(mid -0.249642 0.249642)
							(end -0.1778 0.2794)
						)
						(arc
							(start 0.1778 0.2794)
							(mid 0.249642 0.249642)
							(end 0.2794 0.1778)
						)
						(arc
							(start 0.2794 -0.1778)
							(mid 0.249642 -0.249642)
							(end 0.1778 -0.2794)
						)
					)
					(width 0)
					(fill yes)
				)
			)
		)
		(pad "2" smd custom
			(at 0 0.4445 180)
			(size 0.1397 0.1397)
			(layers "F.Cu" "F.Mask" "F.Paste")
			(net "GND")
			(options
				(clearance outline)
				(anchor circle)
			)
			(primitives
				(gr_poly
					(pts
						(arc
							(start -0.1778 -0.2794)
							(mid -0.249642 -0.249642)
							(end -0.2794 -0.1778)
						)
						(arc
							(start -0.2794 0.1778)
							(mid -0.249642 0.249642)
							(end -0.1778 0.2794)
						)
						(arc
							(start 0.1778 0.2794)
							(mid 0.249642 0.249642)
							(end 0.2794 0.1778)
						)
						(arc
							(start 0.2794 -0.1778)
							(mid 0.249642 -0.249642)
							(end 0.1778 -0.2794)
						)
					)
					(width 0)
					(fill yes)
				)
			)
		)
	)
	(footprint ""
		(layer "F.Cu")
		(at 403.351746 -97.390204 -90)
		(property "Reference" "R481"
			(at 0 0 270)
			(layer "F.SilkS")
			(hide yes)
			(effects
				(font
					(size 1.27 1.27)
				)
			)
		)
		(property "Value" "4K7R2F-GP"
			(at 0.064008 -3.993896 270)
			(unlocked yes)
			(layer "F.Fab")
			(hide yes)
			(effects
				(font
					(size 1.016 1.016)
					(thickness 0.1524)
				)
			)
		)
		(property "Device Type" "R402H16"
			(at 0.064008 -5.517896 270)
			(unlocked yes)
			(layer "F.Fab")
			(hide yes)
			(effects
				(font
					(size 1.016 1.016)
					(thickness 0.1524)
				)
			)
		)
		(duplicate_pad_numbers_are_jumpers no)
		(fp_line
			(start -0.508 -0.9398)
			(end -0.508 0.9398)
			(stroke
				(width 0.1524)
				(type default)
			)
			(layer "F.SilkS")
		)
		(fp_line
			(start 0.508 -0.9398)
			(end -0.508 -0.9398)
			(stroke
				(width 0.1524)
				(type default)
			)
			(layer "F.SilkS")
		)
		(fp_rect
			(start -0.508 0.9398)
			(end 0.508 -0.9398)
			(stroke
				(width 0)
				(type default)
			)
			(fill no)
			(layer "F.CrtYd")
		)
		(fp_rect
			(start -0.508 0.9398)
			(end 0.508 -0.9398)
			(stroke
				(width 0)
				(type default)
			)
			(fill no)
			(layer "F.Fab")
		)
		(pad "1" smd custom
			(at 0 -0.4445 270)
			(size 0.1397 0.1397)
			(layers "F.Cu" "F.Mask" "F.Paste")
			(net "DRIVE_B_21_ACT")
			(options
				(clearance outline)
				(anchor circle)
			)
			(primitives
				(gr_poly
					(pts
						(arc
							(start -0.1778 -0.2794)
							(mid -0.249642 -0.249642)
							(end -0.2794 -0.1778)
						)
						(arc
							(start -0.2794 0.1778)
							(mid -0.249642 0.249642)
							(end -0.1778 0.2794)
						)
						(arc
							(start 0.1778 0.2794)
							(mid 0.249642 0.249642)
							(end 0.2794 0.1778)
						)
						(arc
							(start 0.2794 -0.1778)
							(mid 0.249642 -0.249642)
							(end 0.1778 -0.2794)
						)
					)
					(width 0)
					(fill yes)
				)
			)
		)
		(pad "2" smd custom
			(at 0 0.4445 270)
			(size 0.1397 0.1397)
			(layers "F.Cu" "F.Mask" "F.Paste")
			(net "GND")
			(options
				(clearance outline)
				(anchor circle)
			)
			(primitives
				(gr_poly
					(pts
						(arc
							(start -0.1778 -0.2794)
							(mid -0.249642 -0.249642)
							(end -0.2794 -0.1778)
						)
						(arc
							(start -0.2794 0.1778)
							(mid -0.249642 0.249642)
							(end -0.1778 0.2794)
						)
						(arc
							(start 0.1778 0.2794)
							(mid 0.249642 0.249642)
							(end 0.2794 0.1778)
						)
						(arc
							(start 0.2794 -0.1778)
							(mid 0.249642 -0.249642)
							(end 0.1778 -0.2794)
						)
					)
					(width 0)
					(fill yes)
				)
			)
		)
	)
	(footprint ""
		(layer "F.Cu")
		(at 397.129 -17.145 180)
		(property "Reference" "R822"
			(at 0 0 180)
			(layer "F.SilkS")
			(hide yes)
			(effects
				(font
					(size 1.27 1.27)
				)
			)
		)
		(property "Value" "200KR2F-L-GP"
			(at 0.064008 -3.993896 180)
			(unlocked yes)
			(layer "F.Fab")
			(hide yes)
			(effects
				(font
					(size 1.016 1.016)
					(thickness 0.1524)
				)
			)
		)
		(property "Device Type" "R402H16"
			(at 0.064008 -5.517896 180)
			(unlocked yes)
			(layer "F.Fab")
			(hide yes)
			(effects
				(font
					(size 1.016 1.016)
					(thickness 0.1524)
				)
			)
		)
		(duplicate_pad_numbers_are_jumpers no)
		(fp_line
			(start 0.508 -0.9398)
			(end -0.508 -0.9398)
			(stroke
				(width 0.1524)
				(type default)
			)
			(layer "F.SilkS")
		)
		(fp_line
			(start -0.508 -0.9398)
			(end -0.508 0.9398)
			(stroke
				(width 0.1524)
				(type default)
			)
			(layer "F.SilkS")
		)
		(fp_rect
			(start -0.508 0.9398)
			(end 0.508 -0.9398)
			(stroke
				(width 0)
				(type default)
			)
			(fill no)
			(layer "F.CrtYd")
		)
		(fp_rect
			(start -0.508 0.9398)
			(end 0.508 -0.9398)
			(stroke
				(width 0)
				(type default)
			)
			(fill no)
			(layer "F.Fab")
		)
		(pad "1" smd custom
			(at 0 -0.4445 180)
			(size 0.1397 0.1397)
			(layers "F.Cu" "F.Mask" "F.Paste")
			(net "SW_HDD_R32")
			(options
				(clearance outline)
				(anchor circle)
			)
			(primitives
				(gr_poly
					(pts
						(arc
							(start -0.1778 -0.2794)
							(mid -0.249642 -0.249642)
							(end -0.2794 -0.1778)
						)
						(arc
							(start -0.2794 0.1778)
							(mid -0.249642 0.249642)
							(end -0.1778 0.2794)
						)
						(arc
							(start 0.1778 0.2794)
							(mid 0.249642 0.249642)
							(end 0.2794 0.1778)
						)
						(arc
							(start 0.2794 -0.1778)
							(mid 0.249642 -0.249642)
							(end 0.1778 -0.2794)
						)
					)
					(width 0)
					(fill yes)
				)
			)
		)
		(pad "2" smd custom
			(at 0 0.4445 180)
			(size 0.1397 0.1397)
			(layers "F.Cu" "F.Mask" "F.Paste")
			(net "SW_HDD_N32")
			(options
				(clearance outline)
				(anchor circle)
			)
			(primitives
				(gr_poly
					(pts
						(arc
							(start -0.1778 -0.2794)
							(mid -0.249642 -0.249642)
							(end -0.2794 -0.1778)
						)
						(arc
							(start -0.2794 0.1778)
							(mid -0.249642 0.249642)
							(end -0.1778 0.2794)
						)
						(arc
							(start 0.1778 0.2794)
							(mid 0.249642 0.249642)
							(end 0.2794 0.1778)
						)
						(arc
							(start 0.2794 -0.1778)
							(mid 0.249642 -0.249642)
							(end 0.1778 -0.2794)
						)
					)
					(width 0)
					(fill yes)
				)
			)
		)
	)
	(footprint ""
		(layer "F.Cu")
		(at 54.0004 -246.3038 -90)
		(property "Reference" "R182"
			(at 0 0 270)
			(layer "F.SilkS")
			(hide yes)
			(effects
				(font
					(size 1.27 1.27)
				)
			)
		)
		(property "Value" "0R2J-2-GP"
			(at 0.064008 -3.993896 270)
			(unlocked yes)
			(layer "F.Fab")
			(hide yes)
			(effects
				(font
					(size 1.016 1.016)
					(thickness 0.1524)
				)
			)
		)
		(property "Device Type" "R402H16"
			(at 0.064008 -5.517896 270)
			(unlocked yes)
			(layer "F.Fab")
			(hide yes)
			(effects
				(font
					(size 1.016 1.016)
					(thickness 0.1524)
				)
			)
		)
		(duplicate_pad_numbers_are_jumpers no)
		(fp_line
			(start -0.508 -0.9398)
			(end -0.508 0.9398)
			(stroke
				(width 0.1524)
				(type default)
			)
			(layer "F.SilkS")
		)
		(fp_line
			(start 0.508 -0.9398)
			(end -0.508 -0.9398)
			(stroke
				(width 0.1524)
				(type default)
			)
			(layer "F.SilkS")
		)
		(fp_rect
			(start -0.508 0.9398)
			(end 0.508 -0.9398)
			(stroke
				(width 0)
				(type default)
			)
			(fill no)
			(layer "F.CrtYd")
		)
		(fp_rect
			(start -0.508 0.9398)
			(end 0.508 -0.9398)
			(stroke
				(width 0)
				(type default)
			)
			(fill no)
			(layer "F.Fab")
		)
		(pad "1" smd custom
			(at 0 -0.4445 270)
			(size 0.1397 0.1397)
			(layers "F.Cu" "F.Mask" "F.Paste")
			(net "DRIVE_B_1_PWR")
			(options
				(clearance outline)
				(anchor circle)
			)
			(primitives
				(gr_poly
					(pts
						(arc
							(start -0.1778 -0.2794)
							(mid -0.249642 -0.249642)
							(end -0.2794 -0.1778)
						)
						(arc
							(start -0.2794 0.1778)
							(mid -0.249642 0.249642)
							(end -0.1778 0.2794)
						)
						(arc
							(start 0.1778 0.2794)
							(mid 0.249642 0.249642)
							(end 0.2794 0.1778)
						)
						(arc
							(start 0.2794 -0.1778)
							(mid 0.249642 -0.249642)
							(end 0.1778 -0.2794)
						)
					)
					(width 0)
					(fill yes)
				)
			)
		)
		(pad "2" smd custom
			(at 0 0.4445 270)
			(size 0.1397 0.1397)
			(layers "F.Cu" "F.Mask" "F.Paste")
			(net "SW_PWR_R_HDD1")
			(options
				(clearance outline)
				(anchor circle)
			)
			(primitives
				(gr_poly
					(pts
						(arc
							(start -0.1778 -0.2794)
							(mid -0.249642 -0.249642)
							(end -0.2794 -0.1778)
						)
						(arc
							(start -0.2794 0.1778)
							(mid -0.249642 0.249642)
							(end -0.1778 0.2794)
						)
						(arc
							(start 0.1778 0.2794)
							(mid 0.249642 0.249642)
							(end 0.2794 0.1778)
						)
						(arc
							(start 0.2794 -0.1778)
							(mid 0.249642 -0.249642)
							(end 0.1778 -0.2794)
						)
					)
					(width 0)
					(fill yes)
				)
			)
		)
	)
	(footprint ""
		(layer "F.Cu")
		(at 45.7962 -214.757 180)
		(property "Reference" "Q220"
			(at 0 0 180)
			(layer "F.SilkS")
			(hide yes)
			(effects
				(font
					(size 1.27 1.27)
				)
			)
		)
		(property "Value" "2N7002K-2-GP"
			(at 0.127 -8.9662 180)
			(unlocked yes)
			(layer "F.Fab")
			(hide yes)
			(effects
				(font
					(size 1.016 1.016)
					(thickness 0.1524)
				)
			)
		)
		(property "Device Type" "SOT23DGS2D4H44"
			(at 0.127 -10.4902 180)
			(unlocked yes)
			(layer "F.Fab")
			(hide yes)
			(effects
				(font
					(size 1.016 1.016)
					(thickness 0.1524)
				)
			)
		)
		(duplicate_pad_numbers_are_jumpers no)
		(fp_line
			(start 1.651 1.778)
			(end 1.651 -1.778)
			(stroke
				(width 0.1524)
				(type default)
			)
			(layer "F.SilkS")
		)
		(fp_line
			(start 1.651 -1.778)
			(end -1.651 -1.778)
			(stroke
				(width 0.1524)
				(type default)
			)
			(layer "F.SilkS")
		)
		(fp_line
			(start -1.651 1.778)
			(end 1.651 1.778)
			(stroke
				(width 0.1524)
				(type default)
			)
			(layer "F.SilkS")
		)
		(fp_line
			(start -1.651 -1.778)
			(end -1.651 1.778)
			(stroke
				(width 0.1524)
				(type default)
			)
			(layer "F.SilkS")
		)
		(fp_poly
			(pts
				(xy -1.778 1.8796) (xy -1.778 -1.8796) (xy 1.778 -1.8796) (xy 1.778 1.8796)
			)
			(stroke
				(width 0)
				(type default)
			)
			(fill no)
			(layer "F.CrtYd")
		)
		(fp_poly
			(pts
				(xy -1.778 1.8796) (xy -1.778 -1.8796) (xy 1.778 -1.8796) (xy 1.778 1.8796)
			)
			(stroke
				(width 0)
				(type default)
			)
			(fill no)
			(layer "F.Fab")
		)
		(pad "D" smd custom
			(at 0 -0.9525 180)
			(size 0.1905 0.1905)
			(layers "F.Cu" "F.Mask" "F.Paste")
			(net "FLT_HDD1_N")
			(options
				(clearance outline)
				(anchor circle)
			)
			(primitives
				(gr_poly
					(pts
						(arc
							(start -0.1778 0.5715)
							(mid -0.321484 0.511984)
							(end -0.381 0.3683)
						)
						(arc
							(start -0.381 -0.3683)
							(mid -0.321484 -0.511984)
							(end -0.1778 -0.5715)
						)
						(arc
							(start 0.1778 -0.5715)
							(mid 0.321484 -0.511984)
							(end 0.381 -0.3683)
						)
						(arc
							(start 0.381 0.3683)
							(mid 0.321484 0.511984)
							(end 0.1778 0.5715)
						)
					)
					(width 0)
					(fill yes)
				)
			)
		)
		(pad "G" smd custom
			(at -0.98425 0.9525 180)
			(size 0.1905 0.1905)
			(layers "F.Cu" "F.Mask" "F.Paste")
			(net "DRIVE_B_1_FLT_LED")
			(options
				(clearance outline)
				(anchor circle)
			)
			(primitives
				(gr_poly
					(pts
						(arc
							(start -0.1778 0.5715)
							(mid -0.321484 0.511984)
							(end -0.381 0.3683)
						)
						(arc
							(start -0.381 -0.3683)
							(mid -0.321484 -0.511984)
							(end -0.1778 -0.5715)
						)
						(arc
							(start 0.1778 -0.5715)
							(mid 0.321484 -0.511984)
							(end 0.381 -0.3683)
						)
						(arc
							(start 0.381 0.3683)
							(mid 0.321484 0.511984)
							(end 0.1778 0.5715)
						)
					)
					(width 0)
					(fill yes)
				)
			)
		)
		(pad "S" smd custom
			(at 0.98425 0.9525 180)
			(size 0.1905 0.1905)
			(layers "F.Cu" "F.Mask" "F.Paste")
			(net "GND")
			(options
				(clearance outline)
				(anchor circle)
			)
			(primitives
				(gr_poly
					(pts
						(arc
							(start -0.1778 0.5715)
							(mid -0.321484 0.511984)
							(end -0.381 0.3683)
						)
						(arc
							(start -0.381 -0.3683)
							(mid -0.321484 -0.511984)
							(end -0.1778 -0.5715)
						)
						(arc
							(start 0.1778 -0.5715)
							(mid 0.321484 -0.511984)
							(end 0.381 -0.3683)
						)
						(arc
							(start 0.381 0.3683)
							(mid 0.321484 0.511984)
							(end 0.1778 0.5715)
						)
					)
					(width 0)
					(fill yes)
				)
			)
		)
	)
	(footprint ""
		(layer "F.Cu")
		(at 24.22017 -228.351842 -90)
		(property "Reference" "R1105"
			(at 0 0 270)
			(layer "F.SilkS")
			(hide yes)
			(effects
				(font
					(size 1.27 1.27)
				)
			)
		)
		(property "Value" "15KR2F-GP"
			(at 0.064008 -3.993896 270)
			(unlocked yes)
			(layer "F.Fab")
			(hide yes)
			(effects
				(font
					(size 1.016 1.016)
					(thickness 0.1524)
				)
			)
		)
		(property "Device Type" "R402H16"
			(at 0.064008 -5.517896 270)
			(unlocked yes)
			(layer "F.Fab")
			(hide yes)
			(effects
				(font
					(size 1.016 1.016)
					(thickness 0.1524)
				)
			)
		)
		(duplicate_pad_numbers_are_jumpers no)
		(fp_line
			(start -0.508 -0.9398)
			(end -0.508 0.9398)
			(stroke
				(width 0.1524)
				(type default)
			)
			(layer "F.SilkS")
		)
		(fp_line
			(start 0.508 -0.9398)
			(end -0.508 -0.9398)
			(stroke
				(width 0.1524)
				(type default)
			)
			(layer "F.SilkS")
		)
		(fp_rect
			(start -0.508 0.9398)
			(end 0.508 -0.9398)
			(stroke
				(width 0)
				(type default)
			)
			(fill no)
			(layer "F.CrtYd")
		)
		(fp_rect
			(start -0.508 0.9398)
			(end 0.508 -0.9398)
			(stroke
				(width 0)
				(type default)
			)
			(fill no)
			(layer "F.Fab")
		)
		(pad "1" smd custom
			(at 0 -0.4445 270)
			(size 0.1397 0.1397)
			(layers "F.Cu" "F.Mask" "F.Paste")
			(net "P5V_B_1_PGOOD")
			(options
				(clearance outline)
				(anchor circle)
			)
			(primitives
				(gr_poly
					(pts
						(arc
							(start -0.1778 -0.2794)
							(mid -0.249642 -0.249642)
							(end -0.2794 -0.1778)
						)
						(arc
							(start -0.2794 0.1778)
							(mid -0.249642 0.249642)
							(end -0.1778 0.2794)
						)
						(arc
							(start 0.1778 0.2794)
							(mid 0.249642 0.249642)
							(end 0.2794 0.1778)
						)
						(arc
							(start 0.2794 -0.1778)
							(mid 0.249642 -0.249642)
							(end 0.1778 -0.2794)
						)
					)
					(width 0)
					(fill yes)
				)
			)
		)
		(pad "2" smd custom
			(at 0 0.4445 270)
			(size 0.1397 0.1397)
			(layers "F.Cu" "F.Mask" "F.Paste")
			(net "GND")
			(options
				(clearance outline)
				(anchor circle)
			)
			(primitives
				(gr_poly
					(pts
						(arc
							(start -0.1778 -0.2794)
							(mid -0.249642 -0.249642)
							(end -0.2794 -0.1778)
						)
						(arc
							(start -0.2794 0.1778)
							(mid -0.249642 0.249642)
							(end -0.1778 0.2794)
						)
						(arc
							(start 0.1778 0.2794)
							(mid 0.249642 0.249642)
							(end 0.2794 0.1778)
						)
						(arc
							(start 0.2794 -0.1778)
							(mid 0.249642 -0.249642)
							(end 0.1778 -0.2794)
						)
					)
					(width 0)
					(fill yes)
				)
			)
		)
	)
	(footprint ""
		(layer "F.Cu")
		(at 440.908186 -113.996978)
		(property "Reference" "R1158"
			(at 0 0 0)
			(layer "F.SilkS")
			(hide yes)
			(effects
				(font
					(size 1.27 1.27)
				)
			)
		)
		(property "Value" "0R3J-0-U-GP"
			(at -0.0254 -2.5146 0)
			(unlocked yes)
			(layer "F.Fab")
			(hide yes)
			(effects
				(font
					(size 1.016 1.016)
					(thickness 0.1524)
				)
			)
		)
		(property "Device Type" "R603H22"
			(at -0.0254 -4.0386 0)
			(unlocked yes)
			(layer "F.Fab")
			(hide yes)
			(effects
				(font
					(size 1.016 1.016)
					(thickness 0.1524)
				)
			)
		)
		(duplicate_pad_numbers_are_jumpers no)
		(fp_line
			(start -0.4826 0)
			(end -0.2032 0)
			(stroke
				(width 0.2032)
				(type default)
			)
			(layer "F.SilkS")
		)
		(fp_line
			(start 0.2032 0)
			(end 0.4826 0)
			(stroke
				(width 0.2032)
				(type default)
			)
			(layer "F.SilkS")
		)
		(fp_rect
			(start -0.5842 1.3335)
			(end 0.5842 -1.3335)
			(stroke
				(width 0)
				(type default)
			)
			(fill no)
			(layer "F.CrtYd")
		)
		(fp_rect
			(start -0.5842 1.3335)
			(end 0.5842 -1.3335)
			(stroke
				(width 0)
				(type default)
			)
			(fill no)
			(layer "F.Fab")
		)
		(pad "1" smd custom
			(at 0 -0.762)
			(size 0.2159 0.2159)
			(layers "F.Cu" "F.Mask" "F.Paste")
			(net "P5V_B_4_VBST")
			(options
				(clearance outline)
				(anchor circle)
			)
			(primitives
				(gr_poly
					(pts
						(arc
							(start -0.3302 -0.4318)
							(mid -0.402042 -0.402042)
							(end -0.4318 -0.3302)
						)
						(arc
							(start -0.4318 0.3302)
							(mid -0.402042 0.402042)
							(end -0.3302 0.4318)
						)
						(arc
							(start 0.3302 0.4318)
							(mid 0.402042 0.402042)
							(end 0.4318 0.3302)
						)
						(arc
							(start 0.4318 -0.3302)
							(mid 0.402042 -0.402042)
							(end 0.3302 -0.4318)
						)
					)
					(width 0)
					(fill yes)
				)
			)
		)
		(pad "2" smd custom
			(at 0 0.762)
			(size 0.2159 0.2159)
			(layers "F.Cu" "F.Mask" "F.Paste")
			(net "P5V_B_4_VBST_RC")
			(options
				(clearance outline)
				(anchor circle)
			)
			(primitives
				(gr_poly
					(pts
						(arc
							(start -0.3302 -0.4318)
							(mid -0.402042 -0.402042)
							(end -0.4318 -0.3302)
						)
						(arc
							(start -0.4318 0.3302)
							(mid -0.402042 0.402042)
							(end -0.3302 0.4318)
						)
						(arc
							(start 0.3302 0.4318)
							(mid 0.402042 0.402042)
							(end 0.4318 0.3302)
						)
						(arc
							(start 0.4318 -0.3302)
							(mid 0.402042 -0.402042)
							(end 0.3302 -0.4318)
						)
					)
					(width 0)
					(fill yes)
				)
			)
		)
	)
	(footprint ""
		(layer "F.Cu")
		(at 240.919 -215.265 180)
		(property "Reference" "R80"
			(at 0 0 180)
			(layer "F.SilkS")
			(hide yes)
			(effects
				(font
					(size 1.27 1.27)
				)
			)
		)
		(property "Value" "4K7R2F-GP"
			(at 0.064008 -3.993896 180)
			(unlocked yes)
			(layer "F.Fab")
			(hide yes)
			(effects
				(font
					(size 1.016 1.016)
					(thickness 0.1524)
				)
			)
		)
		(property "Device Type" "R402H16"
			(at 0.064008 -5.517896 180)
			(unlocked yes)
			(layer "F.Fab")
			(hide yes)
			(effects
				(font
					(size 1.016 1.016)
					(thickness 0.1524)
				)
			)
		)
		(duplicate_pad_numbers_are_jumpers no)
		(fp_line
			(start 0.508 -0.9398)
			(end -0.508 -0.9398)
			(stroke
				(width 0.1524)
				(type default)
			)
			(layer "F.SilkS")
		)
		(fp_line
			(start -0.508 -0.9398)
			(end -0.508 0.9398)
			(stroke
				(width 0.1524)
				(type default)
			)
			(layer "F.SilkS")
		)
		(fp_rect
			(start -0.508 0.9398)
			(end 0.508 -0.9398)
			(stroke
				(width 0)
				(type default)
			)
			(fill no)
			(layer "F.CrtYd")
		)
		(fp_rect
			(start -0.508 0.9398)
			(end 0.508 -0.9398)
			(stroke
				(width 0)
				(type default)
			)
			(fill no)
			(layer "F.Fab")
		)
		(pad "1" smd custom
			(at 0 -0.4445 180)
			(size 0.1397 0.1397)
			(layers "F.Cu" "F.Mask" "F.Paste")
			(net "P3V3_STBY_B")
			(options
				(clearance outline)
				(anchor circle)
			)
			(primitives
				(gr_poly
					(pts
						(arc
							(start -0.1778 -0.2794)
							(mid -0.249642 -0.249642)
							(end -0.2794 -0.1778)
						)
						(arc
							(start -0.2794 0.1778)
							(mid -0.249642 0.249642)
							(end -0.1778 0.2794)
						)
						(arc
							(start 0.1778 0.2794)
							(mid 0.249642 0.249642)
							(end 0.2794 0.1778)
						)
						(arc
							(start 0.2794 -0.1778)
							(mid 0.249642 -0.249642)
							(end 0.1778 -0.2794)
						)
					)
					(width 0)
					(fill yes)
				)
			)
		)
		(pad "2" smd custom
			(at 0 0.4445 180)
			(size 0.1397 0.1397)
			(layers "F.Cu" "F.Mask" "F.Paste")
			(net "IO_EXP3_A0")
			(options
				(clearance outline)
				(anchor circle)
			)
			(primitives
				(gr_poly
					(pts
						(arc
							(start -0.1778 -0.2794)
							(mid -0.249642 -0.249642)
							(end -0.2794 -0.1778)
						)
						(arc
							(start -0.2794 0.1778)
							(mid -0.249642 0.249642)
							(end -0.1778 0.2794)
						)
						(arc
							(start 0.1778 0.2794)
							(mid 0.249642 0.249642)
							(end 0.2794 0.1778)
						)
						(arc
							(start 0.2794 -0.1778)
							(mid 0.249642 -0.249642)
							(end 0.1778 -0.2794)
						)
					)
					(width 0)
					(fill yes)
				)
			)
		)
	)
	(footprint ""
		(layer "F.Cu")
		(at 213.35238 -247.88622)
		(property "Reference" "R189"
			(at 0 0 0)
			(layer "F.SilkS")
			(hide yes)
			(effects
				(font
					(size 1.27 1.27)
				)
			)
		)
		(property "Value" "200KR2F-L-GP"
			(at 0.064008 -3.993896 0)
			(unlocked yes)
			(layer "F.Fab")
			(hide yes)
			(effects
				(font
					(size 1.016 1.016)
					(thickness 0.1524)
				)
			)
		)
		(property "Device Type" "R402H16"
			(at 0.064008 -5.517896 0)
			(unlocked yes)
			(layer "F.Fab")
			(hide yes)
			(effects
				(font
					(size 1.016 1.016)
					(thickness 0.1524)
				)
			)
		)
		(duplicate_pad_numbers_are_jumpers no)
		(fp_line
			(start -0.508 -0.9398)
			(end -0.508 0.9398)
			(stroke
				(width 0.1524)
				(type default)
			)
			(layer "F.SilkS")
		)
		(fp_line
			(start 0.508 -0.9398)
			(end -0.508 -0.9398)
			(stroke
				(width 0.1524)
				(type default)
			)
			(layer "F.SilkS")
		)
		(fp_rect
			(start -0.508 0.9398)
			(end 0.508 -0.9398)
			(stroke
				(width 0)
				(type default)
			)
			(fill no)
			(layer "F.CrtYd")
		)
		(fp_rect
			(start -0.508 0.9398)
			(end 0.508 -0.9398)
			(stroke
				(width 0)
				(type default)
			)
			(fill no)
			(layer "F.Fab")
		)
		(pad "1" smd custom
			(at 0 -0.4445)
			(size 0.1397 0.1397)
			(layers "F.Cu" "F.Mask" "F.Paste")
			(net "P3V3_STBY_B")
			(options
				(clearance outline)
				(anchor circle)
			)
			(primitives
				(gr_poly
					(pts
						(arc
							(start -0.1778 -0.2794)
							(mid -0.249642 -0.249642)
							(end -0.2794 -0.1778)
						)
						(arc
							(start -0.2794 0.1778)
							(mid -0.249642 0.249642)
							(end -0.1778 0.2794)
						)
						(arc
							(start 0.1778 0.2794)
							(mid 0.249642 0.249642)
							(end 0.2794 0.1778)
						)
						(arc
							(start 0.2794 -0.1778)
							(mid 0.249642 -0.249642)
							(end 0.1778 -0.2794)
						)
					)
					(width 0)
					(fill yes)
				)
			)
		)
		(pad "2" smd custom
			(at 0 0.4445)
			(size 0.1397 0.1397)
			(layers "F.Cu" "F.Mask" "F.Paste")
			(net "DRIVE_INSERT_ALERT_B_N")
			(options
				(clearance outline)
				(anchor circle)
			)
			(primitives
				(gr_poly
					(pts
						(arc
							(start -0.1778 -0.2794)
							(mid -0.249642 -0.249642)
							(end -0.2794 -0.1778)
						)
						(arc
							(start -0.2794 0.1778)
							(mid -0.249642 0.249642)
							(end -0.1778 0.2794)
						)
						(arc
							(start 0.1778 0.2794)
							(mid 0.249642 0.249642)
							(end 0.2794 0.1778)
						)
						(arc
							(start 0.2794 -0.1778)
							(mid 0.249642 -0.249642)
							(end 0.1778 -0.2794)
						)
					)
					(width 0)
					(fill yes)
				)
			)
		)
	)
	(footprint ""
		(layer "F.Cu")
		(at 434.393594 -214.860378 90)
		(property "Reference" "Q253"
			(at 0 0 90)
			(layer "F.SilkS")
			(hide yes)
			(effects
				(font
					(size 1.27 1.27)
				)
			)
		)
		(property "Value" "SSM3K324R-GP"
			(at 0.127 -8.9662 90)
			(unlocked yes)
			(layer "F.Fab")
			(hide yes)
			(effects
				(font
					(size 1.016 1.016)
					(thickness 0.1524)
				)
			)
		)
		(property "Device Type" "SOT23DGS2D4H35"
			(at 0.127 -10.4902 90)
			(unlocked yes)
			(layer "F.Fab")
			(hide yes)
			(effects
				(font
					(size 1.016 1.016)
					(thickness 0.1524)
				)
			)
		)
		(duplicate_pad_numbers_are_jumpers no)
		(fp_line
			(start 1.651 -1.778)
			(end -1.651 -1.778)
			(stroke
				(width 0.1524)
				(type default)
			)
			(layer "F.SilkS")
		)
		(fp_line
			(start -1.651 -1.778)
			(end -1.651 1.778)
			(stroke
				(width 0.1524)
				(type default)
			)
			(layer "F.SilkS")
		)
		(fp_line
			(start 1.651 1.778)
			(end 1.651 -1.778)
			(stroke
				(width 0.1524)
				(type default)
			)
			(layer "F.SilkS")
		)
		(fp_line
			(start -1.651 1.778)
			(end 1.651 1.778)
			(stroke
				(width 0.1524)
				(type default)
			)
			(layer "F.SilkS")
		)
		(fp_poly
			(pts
				(xy -1.778 1.8796) (xy -1.778 -1.8796) (xy 1.778 -1.8796) (xy 1.778 1.8796)
			)
			(stroke
				(width 0)
				(type default)
			)
			(fill no)
			(layer "F.CrtYd")
		)
		(fp_poly
			(pts
				(xy -1.778 1.8796) (xy -1.778 -1.8796) (xy 1.778 -1.8796) (xy 1.778 1.8796)
			)
			(stroke
				(width 0)
				(type default)
			)
			(fill no)
			(layer "F.Fab")
		)
		(pad "D" smd custom
			(at 0 -0.9525 90)
			(size 0.1905 0.1905)
			(layers "F.Cu" "F.Mask" "F.Paste")
			(net "DRV_ACT_10_N")
			(options
				(clearance outline)
				(anchor circle)
			)
			(primitives
				(gr_poly
					(pts
						(arc
							(start -0.1778 0.5715)
							(mid -0.321484 0.511984)
							(end -0.381 0.3683)
						)
						(arc
							(start -0.381 -0.3683)
							(mid -0.321484 -0.511984)
							(end -0.1778 -0.5715)
						)
						(arc
							(start 0.1778 -0.5715)
							(mid 0.321484 -0.511984)
							(end 0.381 -0.3683)
						)
						(arc
							(start 0.381 0.3683)
							(mid 0.321484 0.511984)
							(end 0.1778 0.5715)
						)
					)
					(width 0)
					(fill yes)
				)
			)
		)
		(pad "G" smd custom
			(at -0.98425 0.9525 90)
			(size 0.1905 0.1905)
			(layers "F.Cu" "F.Mask" "F.Paste")
			(net "DRIVE_B_10_ACT")
			(options
				(clearance outline)
				(anchor circle)
			)
			(primitives
				(gr_poly
					(pts
						(arc
							(start -0.1778 0.5715)
							(mid -0.321484 0.511984)
							(end -0.381 0.3683)
						)
						(arc
							(start -0.381 -0.3683)
							(mid -0.321484 -0.511984)
							(end -0.1778 -0.5715)
						)
						(arc
							(start 0.1778 -0.5715)
							(mid 0.321484 -0.511984)
							(end 0.381 -0.3683)
						)
						(arc
							(start 0.381 0.3683)
							(mid 0.321484 0.511984)
							(end 0.1778 0.5715)
						)
					)
					(width 0)
					(fill yes)
				)
			)
		)
		(pad "S" smd custom
			(at 0.98425 0.9525 90)
			(size 0.1905 0.1905)
			(layers "F.Cu" "F.Mask" "F.Paste")
			(net "GND")
			(options
				(clearance outline)
				(anchor circle)
			)
			(primitives
				(gr_poly
					(pts
						(arc
							(start -0.1778 0.5715)
							(mid -0.321484 0.511984)
							(end -0.381 0.3683)
						)
						(arc
							(start -0.381 -0.3683)
							(mid -0.321484 -0.511984)
							(end -0.1778 -0.5715)
						)
						(arc
							(start 0.1778 -0.5715)
							(mid 0.321484 -0.511984)
							(end 0.381 -0.3683)
						)
						(arc
							(start 0.381 0.3683)
							(mid 0.321484 0.511984)
							(end 0.1778 0.5715)
						)
					)
					(width 0)
					(fill yes)
				)
			)
		)
	)
	(footprint ""
		(layer "F.Cu")
		(at 20.701 -141.224 180)
		(property "Reference" "Q46"
			(at 0 0 180)
			(layer "F.SilkS")
			(hide yes)
			(effects
				(font
					(size 1.27 1.27)
				)
			)
		)
		(property "Value" "AO4406AL-GP"
			(at -3.707384 -1.5367 180)
			(unlocked yes)
			(layer "F.Fab")
			(hide yes)
			(effects
				(font
					(size 1.016 1.016)
					(thickness 0.1524)
				)
			)
		)
		(property "Device Type" "SOIC8H69"
			(at -3.707384 -3.0607 180)
			(unlocked yes)
			(layer "F.Fab")
			(hide yes)
			(effects
				(font
					(size 1.016 1.016)
					(thickness 0.1524)
				)
			)
		)
		(duplicate_pad_numbers_are_jumpers no)
		(fp_line
			(start 2.1336 1.4224)
			(end 2.1336 -1.4224)
			(stroke
				(width 0.1524)
				(type default)
			)
			(layer "F.SilkS")
		)
		(fp_line
			(start 2.1336 -1.4224)
			(end -2.7432 -1.4224)
			(stroke
				(width 0.1524)
				(type default)
			)
			(layer "F.SilkS")
		)
		(fp_line
			(start -2.1844 -0.0508)
			(end -2.7178 0.508)
			(stroke
				(width 0.1524)
				(type default)
			)
			(layer "F.SilkS")
		)
		(fp_line
			(start -2.6289 3.4417)
			(end -2.6289 1.4732)
			(stroke
				(width 0.381)
				(type default)
			)
			(layer "F.SilkS")
		)
		(fp_line
			(start -2.7178 -0.508)
			(end -2.1844 -0.0508)
			(stroke
				(width 0.1524)
				(type default)
			)
			(layer "F.SilkS")
		)
		(fp_line
			(start -2.7432 1.4224)
			(end 2.1336 1.4224)
			(stroke
				(width 0.1524)
				(type default)
			)
			(layer "F.SilkS")
		)
		(fp_line
			(start -2.7432 1.4224)
			(end -2.6416 1.4224)
			(stroke
				(width 0.1524)
				(type default)
			)
			(layer "F.SilkS")
		)
		(fp_line
			(start -2.7432 -1.4224)
			(end -2.7432 1.4224)
			(stroke
				(width 0.1524)
				(type default)
			)
			(layer "F.SilkS")
		)
		(fp_poly
			(pts
				(xy -2.2098 -1.4224) (xy -2.2098 1.4224) (xy 2.2098 1.4224) (xy 2.2098 -1.4224)
			)
			(stroke
				(width 0)
				(type default)
			)
			(fill yes)
			(layer "F.SilkS")
		)
		(fp_rect
			(start -2.450084 2.999994)
			(end 2.450084 -2.999994)
			(stroke
				(width 0)
				(type default)
			)
			(fill no)
			(layer "F.CrtYd")
		)
		(fp_poly
			(pts
				(xy -2.8194 3.6322) (xy -2.8194 -3.6322) (xy 2.8194 -3.6322) (xy 2.8194 1.18364) (xy 2.450084 1.18364)
				(xy 2.450084 -2.999994) (xy -2.450084 -2.999994) (xy -2.450084 2.999994) (xy 2.450084 2.999994)
				(xy 2.450084 1.18618) (xy 2.8194 1.18618) (xy 2.8194 3.6322)
			)
			(stroke
				(width 0)
				(type default)
			)
			(fill no)
			(layer "F.CrtYd")
		)
		(fp_rect
			(start -2.8194 3.6322)
			(end 2.8194 -3.6322)
			(stroke
				(width 0)
				(type default)
			)
			(fill no)
			(layer "F.Fab")
		)
		(pad "1" smd rect
			(at -1.905 2.54 180)
			(size 0.635 1.651)
			(layers "F.Cu" "F.Mask" "F.Paste")
			(net "P5V_HDD12")
		)
		(pad "2" smd rect
			(at -0.635 2.54 180)
			(size 0.635 1.651)
			(layers "F.Cu" "F.Mask" "F.Paste")
			(net "P5V_HDD12")
		)
		(pad "3" smd rect
			(at 0.635 2.54 180)
			(size 0.635 1.651)
			(layers "F.Cu" "F.Mask" "F.Paste")
			(net "P5V_HDD12")
		)
		(pad "4" smd rect
			(at 1.905 2.54 180)
			(size 0.635 1.651)
			(layers "F.Cu" "F.Mask" "F.Paste")
			(net "SW_HDD_P12")
		)
		(pad "5" smd rect
			(at 1.905 -2.54 180)
			(size 0.635 1.651)
			(layers "F.Cu" "F.Mask" "F.Paste")
			(net "P5V_B_1")
		)
		(pad "6" smd rect
			(at 0.635 -2.54 180)
			(size 0.635 1.651)
			(layers "F.Cu" "F.Mask" "F.Paste")
			(net "P5V_B_1")
		)
		(pad "7" smd rect
			(at -0.635 -2.54 180)
			(size 0.635 1.651)
			(layers "F.Cu" "F.Mask" "F.Paste")
			(net "P5V_B_1")
		)
		(pad "8" smd rect
			(at -1.905 -2.54 180)
			(size 0.635 1.651)
			(layers "F.Cu" "F.Mask" "F.Paste")
			(net "P5V_B_1")
		)
	)
	(footprint ""
		(layer "F.Cu")
		(at 215.122506 -98.58121 180)
		(property "Reference" "R357"
			(at 0 0 180)
			(layer "F.SilkS")
			(hide yes)
			(effects
				(font
					(size 1.27 1.27)
				)
			)
		)
		(property "Value" "0R2J-2-GP"
			(at 0.064008 -3.993896 180)
			(unlocked yes)
			(layer "F.Fab")
			(hide yes)
			(effects
				(font
					(size 1.016 1.016)
					(thickness 0.1524)
				)
			)
		)
		(property "Device Type" "R402H16"
			(at 0.064008 -5.517896 180)
			(unlocked yes)
			(layer "F.Fab")
			(hide yes)
			(effects
				(font
					(size 1.016 1.016)
					(thickness 0.1524)
				)
			)
		)
		(duplicate_pad_numbers_are_jumpers no)
		(fp_line
			(start 0.508 -0.9398)
			(end -0.508 -0.9398)
			(stroke
				(width 0.1524)
				(type default)
			)
			(layer "F.SilkS")
		)
		(fp_line
			(start -0.508 -0.9398)
			(end -0.508 0.9398)
			(stroke
				(width 0.1524)
				(type default)
			)
			(layer "F.SilkS")
		)
		(fp_rect
			(start -0.508 0.9398)
			(end 0.508 -0.9398)
			(stroke
				(width 0)
				(type default)
			)
			(fill no)
			(layer "F.CrtYd")
		)
		(fp_rect
			(start -0.508 0.9398)
			(end 0.508 -0.9398)
			(stroke
				(width 0)
				(type default)
			)
			(fill no)
			(layer "F.Fab")
		)
		(pad "1" smd custom
			(at 0 -0.4445 180)
			(size 0.1397 0.1397)
			(layers "F.Cu" "F.Mask" "F.Paste")
			(net "I2C_CLIP_A_SCL")
			(options
				(clearance outline)
				(anchor circle)
			)
			(primitives
				(gr_poly
					(pts
						(arc
							(start -0.1778 -0.2794)
							(mid -0.249642 -0.249642)
							(end -0.2794 -0.1778)
						)
						(arc
							(start -0.2794 0.1778)
							(mid -0.249642 0.249642)
							(end -0.1778 0.2794)
						)
						(arc
							(start 0.1778 0.2794)
							(mid 0.249642 0.249642)
							(end 0.2794 0.1778)
						)
						(arc
							(start 0.2794 -0.1778)
							(mid 0.249642 -0.249642)
							(end 0.1778 -0.2794)
						)
					)
					(width 0)
					(fill yes)
				)
			)
		)
		(pad "2" smd custom
			(at 0 0.4445 180)
			(size 0.1397 0.1397)
			(layers "F.Cu" "F.Mask" "F.Paste")
			(net "I2C_CLIP_B_SCL")
			(options
				(clearance outline)
				(anchor circle)
			)
			(primitives
				(gr_poly
					(pts
						(arc
							(start -0.1778 -0.2794)
							(mid -0.249642 -0.249642)
							(end -0.2794 -0.1778)
						)
						(arc
							(start -0.2794 0.1778)
							(mid -0.249642 0.249642)
							(end -0.1778 0.2794)
						)
						(arc
							(start 0.1778 0.2794)
							(mid 0.249642 0.249642)
							(end 0.2794 0.1778)
						)
						(arc
							(start 0.2794 -0.1778)
							(mid 0.249642 -0.249642)
							(end 0.1778 -0.2794)
						)
					)
					(width 0)
					(fill yes)
				)
			)
		)
	)
	(footprint ""
		(layer "F.Cu")
		(at 178.689 -363.474)
		(property "Reference" "RR985"
			(at 0 0 0)
			(layer "F.SilkS")
			(hide yes)
			(effects
				(font
					(size 1.27 1.27)
				)
			)
		)
		(property "Value" "0R2J-2-GP"
			(at 0.064008 -3.993896 0)
			(unlocked yes)
			(layer "F.Fab")
			(hide yes)
			(effects
				(font
					(size 1.016 1.016)
					(thickness 0.1524)
				)
			)
		)
		(property "Device Type" "R402H16"
			(at 0.064008 -5.517896 0)
			(unlocked yes)
			(layer "F.Fab")
			(hide yes)
			(effects
				(font
					(size 1.016 1.016)
					(thickness 0.1524)
				)
			)
		)
		(duplicate_pad_numbers_are_jumpers no)
		(fp_line
			(start -0.508 -0.9398)
			(end -0.508 0.9398)
			(stroke
				(width 0.1524)
				(type default)
			)
			(layer "F.SilkS")
		)
		(fp_line
			(start 0.508 -0.9398)
			(end -0.508 -0.9398)
			(stroke
				(width 0.1524)
				(type default)
			)
			(layer "F.SilkS")
		)
		(fp_rect
			(start -0.508 0.9398)
			(end 0.508 -0.9398)
			(stroke
				(width 0)
				(type default)
			)
			(fill no)
			(layer "F.CrtYd")
		)
		(fp_rect
			(start -0.508 0.9398)
			(end 0.508 -0.9398)
			(stroke
				(width 0)
				(type default)
			)
			(fill no)
			(layer "F.Fab")
		)
		(pad "1" smd custom
			(at 0 -0.4445)
			(size 0.1397 0.1397)
			(layers "F.Cu" "F.Mask" "F.Paste")
			(net "MB0_CM_ADR1_R")
			(options
				(clearance outline)
				(anchor circle)
			)
			(primitives
				(gr_poly
					(pts
						(arc
							(start -0.1778 -0.2794)
							(mid -0.249642 -0.249642)
							(end -0.2794 -0.1778)
						)
						(arc
							(start -0.2794 0.1778)
							(mid -0.249642 0.249642)
							(end -0.1778 0.2794)
						)
						(arc
							(start 0.1778 0.2794)
							(mid 0.249642 0.249642)
							(end 0.2794 0.1778)
						)
						(arc
							(start 0.2794 -0.1778)
							(mid 0.249642 -0.249642)
							(end 0.1778 -0.2794)
						)
					)
					(width 0)
					(fill yes)
				)
			)
		)
		(pad "2" smd custom
			(at 0 0.4445)
			(size 0.1397 0.1397)
			(layers "F.Cu" "F.Mask" "F.Paste")
			(net "AGND_CURRENT_MON")
			(options
				(clearance outline)
				(anchor circle)
			)
			(primitives
				(gr_poly
					(pts
						(arc
							(start -0.1778 -0.2794)
							(mid -0.249642 -0.249642)
							(end -0.2794 -0.1778)
						)
						(arc
							(start -0.2794 0.1778)
							(mid -0.249642 0.249642)
							(end -0.1778 0.2794)
						)
						(arc
							(start 0.1778 0.2794)
							(mid 0.249642 0.249642)
							(end 0.2794 0.1778)
						)
						(arc
							(start 0.2794 -0.1778)
							(mid 0.249642 -0.249642)
							(end 0.1778 -0.2794)
						)
					)
					(width 0)
					(fill yes)
				)
			)
		)
	)
	(footprint ""
		(layer "F.Cu")
		(at 306.68976 -361.404916)
		(property "Reference" "C708"
			(at 0 0 0)
			(layer "F.SilkS")
			(hide yes)
			(effects
				(font
					(size 1.27 1.27)
				)
			)
		)
		(property "Value" "SCD1U16V2KX-3GP"
			(at 1.1811 -2.7051 0)
			(unlocked yes)
			(layer "F.Fab")
			(hide yes)
			(effects
				(font
					(size 1.016 1.016)
					(thickness 0.1524)
				)
			)
		)
		(property "Device Type" "C402H22"
			(at 1.1811 -4.2291 0)
			(unlocked yes)
			(layer "F.Fab")
			(hide yes)
			(effects
				(font
					(size 1.016 1.016)
					(thickness 0.1524)
				)
			)
		)
		(duplicate_pad_numbers_are_jumpers no)
		(fp_rect
			(start -0.4318 0.9525)
			(end 0.4318 -0.9525)
			(stroke
				(width 0)
				(type default)
			)
			(fill no)
			(layer "F.CrtYd")
		)
		(fp_rect
			(start -0.4318 0.9525)
			(end 0.4318 -0.9525)
			(stroke
				(width 0)
				(type default)
			)
			(fill no)
			(layer "F.Fab")
		)
		(pad "1" smd custom
			(at 0 -0.4445)
			(size 0.1524 0.1524)
			(layers "F.Cu" "F.Mask" "F.Paste")
			(net "FANTACH_B_OE")
			(options
				(clearance outline)
				(anchor circle)
			)
			(primitives
				(gr_poly
					(pts
						(arc
							(start 0.3048 -0.2032)
							(mid 0.275042 -0.275042)
							(end 0.2032 -0.3048)
						)
						(arc
							(start -0.2032 -0.3048)
							(mid -0.275042 -0.275042)
							(end -0.3048 -0.2032)
						)
						(arc
							(start -0.3048 0.2032)
							(mid -0.275042 0.275042)
							(end -0.2032 0.3048)
						)
						(arc
							(start 0.2032 0.3048)
							(mid 0.275042 0.275042)
							(end 0.3048 0.2032)
						)
					)
					(width 0)
					(fill yes)
				)
			)
		)
		(pad "2" smd custom
			(at 0 0.4445)
			(size 0.1524 0.1524)
			(layers "F.Cu" "F.Mask" "F.Paste")
			(net "GND")
			(options
				(clearance outline)
				(anchor circle)
			)
			(primitives
				(gr_poly
					(pts
						(arc
							(start 0.3048 -0.2032)
							(mid 0.275042 -0.275042)
							(end 0.2032 -0.3048)
						)
						(arc
							(start -0.2032 -0.3048)
							(mid -0.275042 -0.275042)
							(end -0.3048 -0.2032)
						)
						(arc
							(start -0.3048 0.2032)
							(mid -0.275042 0.275042)
							(end -0.2032 0.3048)
						)
						(arc
							(start 0.2032 0.3048)
							(mid 0.275042 0.275042)
							(end 0.3048 0.2032)
						)
					)
					(width 0)
					(fill yes)
				)
			)
		)
	)
	(footprint ""
		(layer "F.Cu")
		(at 320.592196 -371.0432 180)
		(property "Reference" "U51"
			(at 0 0 180)
			(layer "F.SilkS")
			(hide yes)
			(effects
				(font
					(size 1.27 1.27)
				)
			)
		)
		(property "Value" "SN74LVC1G08DCKR-GP"
			(at -2.3368 -8.6868 180)
			(unlocked yes)
			(layer "F.Fab")
			(hide yes)
			(effects
				(font
					(size 1.016 1.016)
					(thickness 0.1524)
				)
			)
		)
		(property "Device Type" "SC70-5H44"
			(at -2.3114 -10.414 180)
			(unlocked yes)
			(layer "F.Fab")
			(hide yes)
			(effects
				(font
					(size 1.016 1.016)
					(thickness 0.1524)
				)
			)
		)
		(duplicate_pad_numbers_are_jumpers no)
		(fp_line
			(start 1.3843 -1.8034)
			(end 1.3843 -1.1176)
			(stroke
				(width 0.3302)
				(type default)
			)
			(layer "F.SilkS")
		)
		(fp_line
			(start 1.27 1.7018)
			(end -1.27 1.7018)
			(stroke
				(width 0.1524)
				(type default)
			)
			(layer "F.SilkS")
		)
		(fp_line
			(start 1.27 -1.7018)
			(end 1.27 1.7018)
			(stroke
				(width 0.1524)
				(type default)
			)
			(layer "F.SilkS")
		)
		(fp_line
			(start 0.6604 -1.8034)
			(end 1.3843 -1.8034)
			(stroke
				(width 0.3302)
				(type default)
			)
			(layer "F.SilkS")
		)
		(fp_line
			(start -1.27 1.7018)
			(end -1.27 -1.7018)
			(stroke
				(width 0.1524)
				(type default)
			)
			(layer "F.SilkS")
		)
		(fp_line
			(start -1.27 -1.7018)
			(end 1.27 -1.7018)
			(stroke
				(width 0.1524)
				(type default)
			)
			(layer "F.SilkS")
		)
		(fp_rect
			(start -1.524 1.9558)
			(end 1.524 -1.9558)
			(stroke
				(width 0)
				(type default)
			)
			(fill no)
			(layer "F.CrtYd")
		)
		(fp_poly
			(pts
				(xy -1.524 -1.9558) (xy 1.524 -1.9558) (xy 1.524 1.9558) (xy -1.524 1.9558)
			)
			(stroke
				(width 0)
				(type default)
			)
			(fill no)
			(layer "F.Fab")
		)
		(pad "1" smd rect
			(at 0.65024 -0.8255 180)
			(size 0.4064 1.2192)
			(layers "F.Cu" "F.Mask" "F.Paste")
			(net "RDPB_FAN_LED2")
		)
		(pad "2" smd rect
			(at 0 -0.8255 180)
			(size 0.4064 1.2192)
			(layers "F.Cu" "F.Mask" "F.Paste")
			(net "FDPB_FAN_LED2")
		)
		(pad "3" smd rect
			(at -0.65024 -0.8255 180)
			(size 0.4064 1.2192)
			(layers "F.Cu" "F.Mask" "F.Paste")
			(net "GND")
		)
		(pad "4" smd rect
			(at -0.65024 0.8255 180)
			(size 0.4064 1.2192)
			(layers "F.Cu" "F.Mask" "F.Paste")
			(net "FAN_LED2")
		)
		(pad "5" smd rect
			(at 0.65024 0.8255 180)
			(size 0.4064 1.2192)
			(layers "F.Cu" "F.Mask" "F.Paste")
			(net "P3V3_IN")
		)
	)
	(footprint ""
		(layer "F.Cu")
		(at 49.55286 -118.310406 -90)
		(property "Reference" "C641"
			(at 0 0 270)
			(layer "F.SilkS")
			(hide yes)
			(effects
				(font
					(size 1.27 1.27)
				)
			)
		)
		(property "Value" "SC1U16V3KX-5GP"
			(at 0 -2.8194 270)
			(unlocked yes)
			(layer "F.Fab")
			(hide yes)
			(effects
				(font
					(size 1.016 1.016)
					(thickness 0.1524)
				)
			)
		)
		(property "Device Type" "C603H36"
			(at 0 -4.3434 270)
			(unlocked yes)
			(layer "F.Fab")
			(hide yes)
			(effects
				(font
					(size 1.016 1.016)
					(thickness 0.1524)
				)
			)
		)
		(duplicate_pad_numbers_are_jumpers no)
		(fp_line
			(start 0.508 0)
			(end -0.508 0)
			(stroke
				(width 0.2032)
				(type default)
			)
			(layer "F.SilkS")
		)
		(fp_rect
			(start -0.5842 1.3335)
			(end 0.5842 -1.3335)
			(stroke
				(width 0)
				(type default)
			)
			(fill no)
			(layer "F.CrtYd")
		)
		(fp_rect
			(start -0.5842 1.3335)
			(end 0.5842 -1.3335)
			(stroke
				(width 0)
				(type default)
			)
			(fill no)
			(layer "F.Fab")
		)
		(pad "1" smd custom
			(at 0 -0.762 270)
			(size 0.2159 0.2159)
			(layers "F.Cu" "F.Mask" "F.Paste")
			(net "P5V_B_2_EN_R")
			(options
				(clearance outline)
				(anchor circle)
			)
			(primitives
				(gr_poly
					(pts
						(arc
							(start -0.3302 -0.4318)
							(mid -0.402042 -0.402042)
							(end -0.4318 -0.3302)
						)
						(arc
							(start -0.4318 0.3302)
							(mid -0.402042 0.402042)
							(end -0.3302 0.4318)
						)
						(arc
							(start 0.3302 0.4318)
							(mid 0.402042 0.402042)
							(end 0.4318 0.3302)
						)
						(arc
							(start 0.4318 -0.3302)
							(mid 0.402042 -0.402042)
							(end 0.3302 -0.4318)
						)
					)
					(width 0)
					(fill yes)
				)
			)
		)
		(pad "2" smd custom
			(at 0 0.762 270)
			(size 0.2159 0.2159)
			(layers "F.Cu" "F.Mask" "F.Paste")
			(net "GND")
			(options
				(clearance outline)
				(anchor circle)
			)
			(primitives
				(gr_poly
					(pts
						(arc
							(start -0.3302 -0.4318)
							(mid -0.402042 -0.402042)
							(end -0.4318 -0.3302)
						)
						(arc
							(start -0.4318 0.3302)
							(mid -0.402042 0.402042)
							(end -0.3302 0.4318)
						)
						(arc
							(start 0.3302 0.4318)
							(mid 0.402042 0.402042)
							(end 0.4318 0.3302)
						)
						(arc
							(start 0.4318 -0.3302)
							(mid 0.402042 -0.402042)
							(end 0.3302 -0.4318)
						)
					)
					(width 0)
					(fill yes)
				)
			)
		)
	)
	(footprint ""
		(layer "F.Cu")
		(at 331.0382 -16.2306 -90)
		(property "Reference" "C428"
			(at 0 0 270)
			(layer "F.SilkS")
			(hide yes)
			(effects
				(font
					(size 1.27 1.27)
				)
			)
		)
		(property "Value" "SCD033U25V2KX-GP"
			(at 1.1811 -2.7051 270)
			(unlocked yes)
			(layer "F.Fab")
			(hide yes)
			(effects
				(font
					(size 1.016 1.016)
					(thickness 0.1524)
				)
			)
		)
		(property "Device Type" "C402H22"
			(at 1.1811 -4.2291 270)
			(unlocked yes)
			(layer "F.Fab")
			(hide yes)
			(effects
				(font
					(size 1.016 1.016)
					(thickness 0.1524)
				)
			)
		)
		(duplicate_pad_numbers_are_jumpers no)
		(fp_rect
			(start -0.4318 0.9525)
			(end 0.4318 -0.9525)
			(stroke
				(width 0)
				(type default)
			)
			(fill no)
			(layer "F.CrtYd")
		)
		(fp_rect
			(start -0.4318 0.9525)
			(end 0.4318 -0.9525)
			(stroke
				(width 0)
				(type default)
			)
			(fill no)
			(layer "F.Fab")
		)
		(pad "1" smd custom
			(at 0 -0.4445 270)
			(size 0.1524 0.1524)
			(layers "F.Cu" "F.Mask" "F.Paste")
			(net "SW_HDD_P30")
			(options
				(clearance outline)
				(anchor circle)
			)
			(primitives
				(gr_poly
					(pts
						(arc
							(start 0.3048 -0.2032)
							(mid 0.275042 -0.275042)
							(end 0.2032 -0.3048)
						)
						(arc
							(start -0.2032 -0.3048)
							(mid -0.275042 -0.275042)
							(end -0.3048 -0.2032)
						)
						(arc
							(start -0.3048 0.2032)
							(mid -0.275042 0.275042)
							(end -0.2032 0.3048)
						)
						(arc
							(start 0.2032 0.3048)
							(mid 0.275042 0.275042)
							(end 0.3048 0.2032)
						)
					)
					(width 0)
					(fill yes)
				)
			)
		)
		(pad "2" smd custom
			(at 0 0.4445 270)
			(size 0.1524 0.1524)
			(layers "F.Cu" "F.Mask" "F.Paste")
			(net "GND")
			(options
				(clearance outline)
				(anchor circle)
			)
			(primitives
				(gr_poly
					(pts
						(arc
							(start 0.3048 -0.2032)
							(mid 0.275042 -0.275042)
							(end 0.2032 -0.3048)
						)
						(arc
							(start -0.2032 -0.3048)
							(mid -0.275042 -0.275042)
							(end -0.3048 -0.2032)
						)
						(arc
							(start -0.3048 0.2032)
							(mid -0.275042 0.275042)
							(end -0.2032 0.3048)
						)
						(arc
							(start 0.2032 0.3048)
							(mid 0.275042 0.275042)
							(end 0.3048 0.2032)
						)
					)
					(width 0)
					(fill yes)
				)
			)
		)
	)
	(footprint ""
		(layer "F.Cu")
		(at 466.909404 -374.2309 90)
		(property "Reference" "R977"
			(at 0 0 90)
			(layer "F.SilkS")
			(hide yes)
			(effects
				(font
					(size 1.27 1.27)
				)
			)
		)
		(property "Value" "1KR5F-1-GP"
			(at 0 -8.9535 90)
			(unlocked yes)
			(layer "F.Fab")
			(hide yes)
			(effects
				(font
					(size 1.27 1.016)
					(thickness 0.1524)
				)
			)
		)
		(property "Device Type" "R805H24"
			(at 0 -10.6299 90)
			(unlocked yes)
			(layer "F.Fab")
			(hide yes)
			(effects
				(font
					(size 1.27 1.016)
					(thickness 0.1524)
				)
			)
		)
		(duplicate_pad_numbers_are_jumpers no)
		(fp_line
			(start 0.889 -1.7018)
			(end -0.889 -1.7018)
			(stroke
				(width 0.1524)
				(type default)
			)
			(layer "F.SilkS")
		)
		(fp_line
			(start 0.889 -1.7018)
			(end 0.889 -0.381)
			(stroke
				(width 0.1524)
				(type default)
			)
			(layer "F.SilkS")
		)
		(fp_line
			(start -0.889 -1.7018)
			(end -0.889 0.2794)
			(stroke
				(width 0.1524)
				(type default)
			)
			(layer "F.SilkS")
		)
		(fp_line
			(start -0.889 0.0762)
			(end -0.889 1.7018)
			(stroke
				(width 0.1524)
				(type default)
			)
			(layer "F.SilkS")
		)
		(fp_line
			(start 0.889 1.7018)
			(end 0.889 -0.508)
			(stroke
				(width 0.1524)
				(type default)
			)
			(layer "F.SilkS")
		)
		(fp_line
			(start -0.889 1.7018)
			(end 0.889 1.7018)
			(stroke
				(width 0.1524)
				(type default)
			)
			(layer "F.SilkS")
		)
		(fp_poly
			(pts
				(xy 0.9652 -1.778) (xy 0.9652 1.778) (xy -0.9652 1.778) (xy -0.9652 -1.778)
			)
			(stroke
				(width 0)
				(type default)
			)
			(fill no)
			(layer "F.CrtYd")
		)
		(fp_rect
			(start -0.9652 1.778)
			(end 0.9652 -1.778)
			(stroke
				(width 0)
				(type default)
			)
			(fill no)
			(layer "F.Fab")
		)
		(pad "1" smd rect
			(at 0 -0.9652 90)
			(size 1.397 1.143)
			(layers "F.Cu" "F.Mask" "F.Paste")
			(net "FAN_YELLOW_3")
		)
		(pad "2" smd rect
			(at 0 0.9652 90)
			(size 1.397 1.143)
			(layers "F.Cu" "F.Mask" "F.Paste")
			(net "FAN_LED_YELLOW_3")
		)
	)
	(footprint ""
		(layer "F.Cu")
		(at 302.212248 -352.672142 -90)
		(property "Reference" "U17"
			(at 0 0 270)
			(layer "F.SilkS")
			(hide yes)
			(effects
				(font
					(size 1.27 1.27)
				)
			)
		)
		(property "Value" "SN74CBTLV3245APWR-GP"
			(at -0.889 -6.2738 270)
			(unlocked yes)
			(layer "F.Fab")
			(hide yes)
			(effects
				(font
					(size 1.016 1.016)
					(thickness 0.1524)
				)
			)
		)
		(property "Device Type" "TSOIC20H48"
			(at -0.9144 -7.8994 270)
			(unlocked yes)
			(layer "F.Fab")
			(hide yes)
			(effects
				(font
					(size 1.016 1.016)
					(thickness 0.1524)
				)
			)
		)
		(duplicate_pad_numbers_are_jumpers no)
		(fp_line
			(start -3.556 4.064)
			(end -3.556 1.778)
			(stroke
				(width 0.508)
				(type default)
			)
			(layer "F.SilkS")
		)
		(fp_line
			(start -3.556 1.397)
			(end -3.556 1.778)
			(stroke
				(width 0.2032)
				(type default)
			)
			(layer "F.SilkS")
		)
		(fp_line
			(start 3.175 1.397)
			(end -3.556 1.397)
			(stroke
				(width 0.2032)
				(type default)
			)
			(layer "F.SilkS")
		)
		(fp_line
			(start -2.667 0)
			(end -3.556 0.889)
			(stroke
				(width 0.2032)
				(type default)
			)
			(layer "F.SilkS")
		)
		(fp_line
			(start -2.667 0)
			(end -3.556 -0.889)
			(stroke
				(width 0.2032)
				(type default)
			)
			(layer "F.SilkS")
		)
		(fp_line
			(start -3.556 -1.397)
			(end -3.556 4.064)
			(stroke
				(width 0.2032)
				(type default)
			)
			(layer "F.SilkS")
		)
		(fp_line
			(start -3.556 -1.397)
			(end 3.175 -1.397)
			(stroke
				(width 0.2032)
				(type default)
			)
			(layer "F.SilkS")
		)
		(fp_line
			(start 3.175 -1.397)
			(end 3.175 1.397)
			(stroke
				(width 0.2032)
				(type default)
			)
			(layer "F.SilkS")
		)
		(fp_poly
			(pts
				(xy -3.25628 -1.8542) (xy 3.25628 -1.8542) (xy 3.25628 1.8542) (xy -3.25628 1.8542)
			)
			(stroke
				(width 0)
				(type default)
			)
			(fill yes)
			(layer "F.SilkS")
		)
		(fp_rect
			(start -3.556 3.81)
			(end 3.556 -3.81)
			(stroke
				(width 0)
				(type default)
			)
			(fill no)
			(layer "F.CrtYd")
		)
		(fp_poly
			(pts
				(xy -3.556 -3.81) (xy 3.556 -3.81) (xy 3.556 3.81) (xy -3.556 3.81)
			)
			(stroke
				(width 0)
				(type default)
			)
			(fill no)
			(layer "F.Fab")
		)
		(pad "1" smd rect
			(at -2.92608 2.8194 270)
			(size 0.3556 1.524)
			(layers "F.Cu" "F.Mask" "F.Paste")
			(net "Net_106")
		)
		(pad "2" smd rect
			(at -2.27584 2.8194 270)
			(size 0.3556 1.524)
			(layers "F.Cu" "F.Mask" "F.Paste")
			(net "FANTACH_B_F0")
		)
		(pad "3" smd rect
			(at -1.6256 2.8194 270)
			(size 0.3556 1.524)
			(layers "F.Cu" "F.Mask" "F.Paste")
			(net "FANTACH_B_R0")
		)
		(pad "4" smd rect
			(at -0.97536 2.8194 270)
			(size 0.3556 1.524)
			(layers "F.Cu" "F.Mask" "F.Paste")
			(net "FANTACH_B_F1")
		)
		(pad "5" smd rect
			(at -0.32512 2.8194 270)
			(size 0.3556 1.524)
			(layers "F.Cu" "F.Mask" "F.Paste")
			(net "FANTACH_B_R1")
		)
		(pad "6" smd rect
			(at 0.32512 2.8194 270)
			(size 0.3556 1.524)
			(layers "F.Cu" "F.Mask" "F.Paste")
			(net "FANTACH_B_F2")
		)
		(pad "7" smd rect
			(at 0.97536 2.8194 270)
			(size 0.3556 1.524)
			(layers "F.Cu" "F.Mask" "F.Paste")
			(net "FANTACH_B_R2")
		)
		(pad "8" smd rect
			(at 1.6256 2.8194 270)
			(size 0.3556 1.524)
			(layers "F.Cu" "F.Mask" "F.Paste")
			(net "FANTACH_B_F3")
		)
		(pad "9" smd rect
			(at 2.27584 2.8194 270)
			(size 0.3556 1.524)
			(layers "F.Cu" "F.Mask" "F.Paste")
			(net "FANTACH_B_R3")
		)
		(pad "10" smd rect
			(at 2.92608 2.8194 270)
			(size 0.3556 1.524)
			(layers "F.Cu" "F.Mask" "F.Paste")
			(net "GND")
		)
		(pad "11" smd rect
			(at 2.92608 -2.8194 270)
			(size 0.3556 1.524)
			(layers "F.Cu" "F.Mask" "F.Paste")
			(net "FANTACH_R3")
		)
		(pad "12" smd rect
			(at 2.27584 -2.8194 270)
			(size 0.3556 1.524)
			(layers "F.Cu" "F.Mask" "F.Paste")
			(net "FANTACH_F3")
		)
		(pad "13" smd rect
			(at 1.6256 -2.8194 270)
			(size 0.3556 1.524)
			(layers "F.Cu" "F.Mask" "F.Paste")
			(net "FANTACH_R2")
		)
		(pad "14" smd rect
			(at 0.97536 -2.8194 270)
			(size 0.3556 1.524)
			(layers "F.Cu" "F.Mask" "F.Paste")
			(net "FANTACH_F2")
		)
		(pad "15" smd rect
			(at 0.32512 -2.8194 270)
			(size 0.3556 1.524)
			(layers "F.Cu" "F.Mask" "F.Paste")
			(net "FANTACH_R1")
		)
		(pad "16" smd rect
			(at -0.32512 -2.8194 270)
			(size 0.3556 1.524)
			(layers "F.Cu" "F.Mask" "F.Paste")
			(net "FANTACH_F1")
		)
		(pad "17" smd rect
			(at -0.97536 -2.8194 270)
			(size 0.3556 1.524)
			(layers "F.Cu" "F.Mask" "F.Paste")
			(net "FANTACH_R0")
		)
		(pad "18" smd rect
			(at -1.6256 -2.8194 270)
			(size 0.3556 1.524)
			(layers "F.Cu" "F.Mask" "F.Paste")
			(net "FANTACH_F0")
		)
		(pad "19" smd rect
			(at -2.27584 -2.8194 270)
			(size 0.3556 1.524)
			(layers "F.Cu" "F.Mask" "F.Paste")
			(net "FANTACH_B_OE_N")
		)
		(pad "20" smd rect
			(at -2.92608 -2.8194 270)
			(size 0.3556 1.524)
			(layers "F.Cu" "F.Mask" "F.Paste")
			(net "P3V3_IN")
		)
	)
	(footprint ""
		(layer "F.Cu")
		(at 37.940996 -364.998 180)
		(property "Reference" "R927"
			(at 0 0 180)
			(layer "F.SilkS")
			(hide yes)
			(effects
				(font
					(size 1.27 1.27)
				)
			)
		)
		(property "Value" "4K7R2F-GP"
			(at 0.064008 -3.993896 180)
			(unlocked yes)
			(layer "F.Fab")
			(hide yes)
			(effects
				(font
					(size 1.016 1.016)
					(thickness 0.1524)
				)
			)
		)
		(property "Device Type" "R402H16"
			(at 0.064008 -5.517896 180)
			(unlocked yes)
			(layer "F.Fab")
			(hide yes)
			(effects
				(font
					(size 1.016 1.016)
					(thickness 0.1524)
				)
			)
		)
		(duplicate_pad_numbers_are_jumpers no)
		(fp_line
			(start 0.508 -0.9398)
			(end -0.508 -0.9398)
			(stroke
				(width 0.1524)
				(type default)
			)
			(layer "F.SilkS")
		)
		(fp_line
			(start -0.508 -0.9398)
			(end -0.508 0.9398)
			(stroke
				(width 0.1524)
				(type default)
			)
			(layer "F.SilkS")
		)
		(fp_rect
			(start -0.508 0.9398)
			(end 0.508 -0.9398)
			(stroke
				(width 0)
				(type default)
			)
			(fill no)
			(layer "F.CrtYd")
		)
		(fp_rect
			(start -0.508 0.9398)
			(end 0.508 -0.9398)
			(stroke
				(width 0)
				(type default)
			)
			(fill no)
			(layer "F.Fab")
		)
		(pad "1" smd custom
			(at 0 -0.4445 180)
			(size 0.1397 0.1397)
			(layers "F.Cu" "F.Mask" "F.Paste")
			(net "P12V_IN")
			(options
				(clearance outline)
				(anchor circle)
			)
			(primitives
				(gr_poly
					(pts
						(arc
							(start -0.1778 -0.2794)
							(mid -0.249642 -0.249642)
							(end -0.2794 -0.1778)
						)
						(arc
							(start -0.2794 0.1778)
							(mid -0.249642 0.249642)
							(end -0.1778 0.2794)
						)
						(arc
							(start 0.1778 0.2794)
							(mid 0.249642 0.249642)
							(end 0.2794 0.1778)
						)
						(arc
							(start 0.2794 -0.1778)
							(mid 0.249642 -0.249642)
							(end 0.1778 -0.2794)
						)
					)
					(width 0)
					(fill yes)
				)
			)
		)
		(pad "2" smd custom
			(at 0 0.4445 180)
			(size 0.1397 0.1397)
			(layers "F.Cu" "F.Mask" "F.Paste")
			(net "FAN_0_TACH1")
			(options
				(clearance outline)
				(anchor circle)
			)
			(primitives
				(gr_poly
					(pts
						(arc
							(start -0.1778 -0.2794)
							(mid -0.249642 -0.249642)
							(end -0.2794 -0.1778)
						)
						(arc
							(start -0.2794 0.1778)
							(mid -0.249642 0.249642)
							(end -0.1778 0.2794)
						)
						(arc
							(start 0.1778 0.2794)
							(mid 0.249642 0.249642)
							(end 0.2794 0.1778)
						)
						(arc
							(start 0.2794 -0.1778)
							(mid 0.249642 -0.249642)
							(end 0.1778 -0.2794)
						)
					)
					(width 0)
					(fill yes)
				)
			)
		)
	)
	(footprint ""
		(layer "F.Cu")
		(at 388.649972 -143.91005 -90)
		(property "Reference" "HDDSAS20"
			(at 0 0 270)
			(layer "F.SilkS")
			(hide yes)
			(effects
				(font
					(size 1.27 1.27)
				)
			)
		)
		(property "Value" "SKT-SAS15P-14P-45-GP"
			(at -20.7645 -8.9789 270)
			(unlocked yes)
			(layer "F.Fab")
			(hide yes)
			(effects
				(font
					(size 1.016 1.016)
					(thickness 0.1524)
				)
			)
		)
		(property "Device Type" "10120818-001C-TRLF"
			(at -20.7645 -10.5029 270)
			(unlocked yes)
			(layer "F.Fab")
			(hide yes)
			(effects
				(font
					(size 1.016 1.016)
					(thickness 0.1524)
				)
			)
		)
		(duplicate_pad_numbers_are_jumpers no)
		(fp_line
			(start 1.651 4.2926)
			(end 1.651 3.0099)
			(stroke
				(width 0.1524)
				(type default)
			)
			(layer "F.SilkS")
		)
		(fp_line
			(start 8.509 4.2926)
			(end 1.651 4.2926)
			(stroke
				(width 0.1524)
				(type default)
			)
			(layer "F.SilkS")
		)
		(fp_line
			(start -23.4188 3.0099)
			(end -23.4188 -3.2512)
			(stroke
				(width 0.1524)
				(type default)
			)
			(layer "F.SilkS")
		)
		(fp_line
			(start 1.651 3.0099)
			(end -23.4188 3.0099)
			(stroke
				(width 0.1524)
				(type default)
			)
			(layer "F.SilkS")
		)
		(fp_line
			(start 8.509 3.0099)
			(end 8.509 4.2926)
			(stroke
				(width 0.1524)
				(type default)
			)
			(layer "F.SilkS")
		)
		(fp_line
			(start 23.4188 3.0099)
			(end 8.509 3.0099)
			(stroke
				(width 0.1524)
				(type default)
			)
			(layer "F.SilkS")
		)
		(fp_line
			(start -23.4188 -3.2512)
			(end 23.4188 -3.2512)
			(stroke
				(width 0.1524)
				(type default)
			)
			(layer "F.SilkS")
		)
		(fp_line
			(start 23.4188 -3.2512)
			(end 23.4188 3.0099)
			(stroke
				(width 0.1524)
				(type default)
			)
			(layer "F.SilkS")
		)
		(fp_line
			(start 15.5067 -3.3401)
			(end 16.2687 -3.3401)
			(stroke
				(width 0.3302)
				(type default)
			)
			(layer "F.SilkS")
		)
		(fp_poly
			(pts
				(xy 15.868904 -3.230372) (xy 16.503904 -3.865372) (xy 15.233904 -3.865372)
			)
			(stroke
				(width 0)
				(type default)
			)
			(fill yes)
			(layer "F.SilkS")
		)
		(fp_poly
			(pts
				(xy -22.8727 -2.7559) (xy 22.8727 -2.7559) (xy 22.8727 2.7559) (xy 8.255 2.7559) (xy 8.255 3.5179)
				(xy 1.905 3.5179) (xy 1.905 2.7559) (xy -22.8727 2.7559)
			)
			(stroke
				(width 0)
				(type default)
			)
			(fill no)
			(layer "F.CrtYd")
		)
		(fp_poly
			(pts
				(xy 1.397 4.5466) (xy 1.397 3.2639) (xy -23.6728 3.2639) (xy -23.6728 -3.5052) (xy 23.6728 -3.5052)
				(xy 23.6728 -0.00635) (xy 22.8727 -0.00635) (xy 22.8727 -2.7559) (xy -22.8727 -2.7559) (xy -22.8727 2.7559)
				(xy 1.905 2.7559) (xy 1.905 3.5179) (xy 8.255 3.5179) (xy 8.255 2.7559) (xy 22.8727 2.7559) (xy 22.8727 0.00635)
				(xy 23.6728 0.00635) (xy 23.6728 3.2639) (xy 8.763 3.2639) (xy 8.763 4.5466)
			)
			(stroke
				(width 0)
				(type default)
			)
			(fill no)
			(layer "F.CrtYd")
		)
		(fp_poly
			(pts
				(xy 1.397 4.5466) (xy 1.397 3.2639) (xy -23.6728 3.2639) (xy -23.6728 -3.5052) (xy 23.6728 -3.5052)
				(xy 23.6728 3.2639) (xy 8.763 3.2639) (xy 8.763 4.5466)
			)
			(stroke
				(width 0)
				(type default)
			)
			(fill no)
			(layer "F.Fab")
		)
		(pad "" np_thru_hole circle
			(at -18.874994 0 270)
			(size 0.254 0.254)
			(drill 1.3462)
			(layers "*.Cu" "*.Mask")
			(clearance 0.9017)
			(thermal_gap 0.9017)
		)
		(pad "" np_thru_hole circle
			(at 18.874994 0 270)
			(size 0.254 0.254)
			(drill 0.9398)
			(layers "*.Cu" "*.Mask")
			(clearance 0.6985)
			(thermal_gap 0.6985)
		)
		(pad "G1" smd rect
			(at 21.874988 0 270)
			(size 2.5908 2.5908)
			(layers "F.Cu" "F.Mask" "F.Paste")
			(net "GND")
		)
		(pad "G2" smd rect
			(at -21.874988 0 270)
			(size 2.5908 2.5908)
			(layers "F.Cu" "F.Mask" "F.Paste")
			(net "GND")
		)
		(pad "P1" smd rect
			(at 1.905 -1.82499 270)
			(size 0.6096 2.3622)
			(layers "F.Cu" "F.Mask" "F.Paste")
			(net "Net_1699")
		)
		(pad "P2" smd rect
			(at 0.635 -1.82499 270)
			(size 0.6096 2.3622)
			(layers "F.Cu" "F.Mask" "F.Paste")
			(net "Net_1700")
		)
		(pad "P3" smd rect
			(at -0.635 -1.82499 270)
			(size 0.6096 2.3622)
			(layers "F.Cu" "F.Mask" "F.Paste")
			(net "Net_1701")
		)
		(pad "P4" smd rect
			(at -1.905 -1.82499 270)
			(size 0.6096 2.3622)
			(layers "F.Cu" "F.Mask" "F.Paste")
			(net "GND")
		)
		(pad "P5" smd rect
			(at -3.175 -1.82499 270)
			(size 0.6096 2.3622)
			(layers "F.Cu" "F.Mask" "F.Paste")
			(net "HDD_PRSNT_20")
		)
		(pad "P6" smd rect
			(at -4.445 -1.82499 270)
			(size 0.6096 2.3622)
			(layers "F.Cu" "F.Mask" "F.Paste")
			(net "GND")
		)
		(pad "P7" smd rect
			(at -5.715 -1.82499 270)
			(size 0.6096 2.3622)
			(layers "F.Cu" "F.Mask" "F.Paste")
			(net "5V_PRE_20")
		)
		(pad "P8" smd rect
			(at -6.985 -1.82499 270)
			(size 0.6096 2.3622)
			(layers "F.Cu" "F.Mask" "F.Paste")
			(net "P5V_HDD20")
		)
		(pad "P9" smd rect
			(at -8.255 -1.82499 270)
			(size 0.6096 2.3622)
			(layers "F.Cu" "F.Mask" "F.Paste")
			(net "P5V_HDD20")
		)
		(pad "P10" smd rect
			(at -9.525 -1.82499 270)
			(size 0.6096 2.3622)
			(layers "F.Cu" "F.Mask" "F.Paste")
			(net "GND")
		)
		(pad "P11" smd rect
			(at -10.795 -1.82499 270)
			(size 0.6096 2.3622)
			(layers "F.Cu" "F.Mask" "F.Paste")
			(net "ACT_HDD_20")
		)
		(pad "P12" smd rect
			(at -12.065 -1.82499 270)
			(size 0.6096 2.3622)
			(layers "F.Cu" "F.Mask" "F.Paste")
			(net "GND")
		)
		(pad "P13" smd rect
			(at -13.335 -1.82499 270)
			(size 0.6096 2.3622)
			(layers "F.Cu" "F.Mask" "F.Paste")
			(net "12V_PRE_20")
		)
		(pad "P14" smd rect
			(at -14.605 -1.82499 270)
			(size 0.6096 2.3622)
			(layers "F.Cu" "F.Mask" "F.Paste")
			(net "P12V_HDD20")
		)
		(pad "P15" smd rect
			(at -15.875 -1.82499 270)
			(size 0.6096 2.3622)
			(layers "F.Cu" "F.Mask" "F.Paste")
			(net "P12V_HDD20")
		)
		(pad "S1" smd rect
			(at 15.875 -1.82499 270)
			(size 0.6096 2.3622)
			(layers "F.Cu" "F.Mask" "F.Paste")
			(net "GND")
		)
		(pad "S2" smd rect
			(at 14.605 -1.82499 270)
			(size 0.6096 2.3622)
			(layers "F.Cu" "F.Mask" "F.Paste")
			(net "SAS_HDD_RX_P20")
		)
		(pad "S3" smd rect
			(at 13.335 -1.82499 270)
			(size 0.6096 2.3622)
			(layers "F.Cu" "F.Mask" "F.Paste")
			(net "SAS_HDD_RX_N20")
		)
		(pad "S4" smd rect
			(at 12.065 -1.82499 270)
			(size 0.6096 2.3622)
			(layers "F.Cu" "F.Mask" "F.Paste")
			(net "GND")
		)
		(pad "S5" smd rect
			(at 10.795 -1.82499 270)
			(size 0.6096 2.3622)
			(layers "F.Cu" "F.Mask" "F.Paste")
			(net "PHY_DRV_B_TO_SCC_B_20_DN")
		)
		(pad "S6" smd rect
			(at 9.525 -1.82499 270)
			(size 0.6096 2.3622)
			(layers "F.Cu" "F.Mask" "F.Paste")
			(net "PHY_DRV_B_TO_SCC_B_20_DP")
		)
		(pad "S7" smd rect
			(at 8.255 -1.82499 270)
			(size 0.6096 2.3622)
			(layers "F.Cu" "F.Mask" "F.Paste")
			(net "GND")
		)
		(pad "S8" smd rect
			(at 7.480046 2.845054 270)
			(size 0.508 2.3622)
			(layers "F.Cu" "F.Mask" "F.Paste")
			(net "GND")
		)
		(pad "S9" smd rect
			(at 6.679946 2.845054 270)
			(size 0.508 2.3622)
			(layers "F.Cu" "F.Mask" "F.Paste")
			(net "Net_444")
		)
		(pad "S10" smd rect
			(at 5.8801 2.845054 270)
			(size 0.508 2.3622)
			(layers "F.Cu" "F.Mask" "F.Paste")
			(net "Net_336")
		)
		(pad "S11" smd rect
			(at 5.08 2.845054 270)
			(size 0.508 2.3622)
			(layers "F.Cu" "F.Mask" "F.Paste")
			(net "GND")
		)
		(pad "S12" smd rect
			(at 4.2799 2.845054 270)
			(size 0.508 2.3622)
			(layers "F.Cu" "F.Mask" "F.Paste")
			(net "Net_372")
		)
		(pad "S13" smd rect
			(at 3.480054 2.845054 270)
			(size 0.508 2.3622)
			(layers "F.Cu" "F.Mask" "F.Paste")
			(net "Net_408")
		)
		(pad "S14" smd rect
			(at 2.679954 2.845054 270)
			(size 0.508 2.3622)
			(layers "F.Cu" "F.Mask" "F.Paste")
			(net "GND")
		)
		(zone
			(layer "F.Cu")
			(hatch none 0.5)
			(connect_pads
				(clearance 0)
			)
			(min_thickness 0.25)
			(keepout
				(tracks not_allowed)
				(vias allowed)
				(pads allowed)
				(copperpour not_allowed)
				(footprints allowed)
			)
			(placement
				(enabled no)
				(sheetname "")
			)
			(fill
				(thermal_gap 0.5)
				(thermal_bridge_width 0.5)
				(island_removal_mode 0)
			)
			(polygon
				(pts
					(xy 392.307572 -160.64865) (xy 385.233672 -160.64865) (xy 385.233672 -167.58285) (xy 386.338572 -167.58285)
					(xy 386.338572 -163.46805) (xy 390.961372 -163.46805) (xy 390.961372 -167.58285) (xy 392.307572 -167.58285)
				)
			)
		)
		(zone
			(layer "F.Cu")
			(hatch none 0.5)
			(connect_pads
				(clearance 0)
			)
			(min_thickness 0.25)
			(keepout
				(tracks allowed)
				(vias not_allowed)
				(pads allowed)
				(copperpour not_allowed)
				(footprints allowed)
			)
			(placement
				(enabled no)
				(sheetname "")
			)
			(fill
				(thermal_gap 0.5)
				(thermal_bridge_width 0.5)
				(island_removal_mode 0)
			)
			(polygon
				(pts
					(xy 392.307572 -160.64865) (xy 385.233672 -160.64865) (xy 385.233672 -167.58285) (xy 386.338572 -167.58285)
					(xy 386.338572 -163.46805) (xy 390.961372 -163.46805) (xy 390.961372 -167.58285) (xy 392.307572 -167.58285)
				)
			)
		)
		(zone
			(layer "F.Cu")
			(hatch none 0.5)
			(connect_pads
				(clearance 0)
			)
			(min_thickness 0.25)
			(keepout
				(tracks allowed)
				(vias not_allowed)
				(pads allowed)
				(copperpour not_allowed)
				(footprints allowed)
			)
			(placement
				(enabled no)
				(sheetname "")
			)
			(fill
				(thermal_gap 0.5)
				(thermal_bridge_width 0.5)
				(island_removal_mode 0)
			)
			(polygon
				(pts
					(xy 392.307572 -127.17145) (xy 385.233672 -127.17145) (xy 385.233672 -120.23725) (xy 386.338572 -120.23725)
					(xy 386.338572 -124.35205) (xy 390.961372 -124.35205) (xy 390.961372 -120.23725) (xy 392.307572 -120.23725)
				)
			)
		)
		(zone
			(layer "F.Cu")
			(hatch none 0.5)
			(connect_pads
				(clearance 0)
			)
			(min_thickness 0.25)
			(keepout
				(tracks not_allowed)
				(vias allowed)
				(pads allowed)
				(copperpour not_allowed)
				(footprints allowed)
			)
			(placement
				(enabled no)
				(sheetname "")
			)
			(fill
				(thermal_gap 0.5)
				(thermal_bridge_width 0.5)
				(island_removal_mode 0)
			)
			(polygon
				(pts
					(xy 392.307572 -127.17145) (xy 385.233672 -127.17145) (xy 385.233672 -120.23725) (xy 386.338572 -120.23725)
					(xy 386.338572 -124.35205) (xy 390.961372 -124.35205) (xy 390.961372 -120.23725) (xy 392.307572 -120.23725)
				)
			)
		)
		(zone
			(layers "F.Cu" "B.Cu" "In1.Cu" "In2.Cu" "In3.Cu" "In4.Cu" "In5.Cu" "In6.Cu")
			(hatch none 0.5)
			(connect_pads
				(clearance 0)
			)
			(min_thickness 0.25)
			(keepout
				(tracks not_allowed)
				(vias allowed)
				(pads allowed)
				(copperpour not_allowed)
				(footprints allowed)
			)
			(placement
				(enabled no)
				(sheetname "")
			)
			(fill
				(thermal_gap 0.5)
				(thermal_bridge_width 0.5)
				(island_removal_mode 0)
			)
			(polygon
				(pts
					(arc
						(start 389.424672 -125.035056)
						(mid 387.875272 -125.035056)
						(end 389.424672 -125.035056)
					)
				)
			)
		)
		(zone
			(layers "F.Cu" "B.Cu" "In1.Cu" "In2.Cu" "In3.Cu" "In4.Cu" "In5.Cu" "In6.Cu")
			(hatch none 0.5)
			(connect_pads
				(clearance 0)
			)
			(min_thickness 0.25)
			(keepout
				(tracks not_allowed)
				(vias allowed)
				(pads allowed)
				(copperpour not_allowed)
				(footprints allowed)
			)
			(placement
				(enabled no)
				(sheetname "")
			)
			(fill
				(thermal_gap 0.5)
				(thermal_bridge_width 0.5)
				(island_removal_mode 0)
			)
			(polygon
				(pts
					(arc
						(start 389.627872 -162.785044)
						(mid 387.672072 -162.785044)
						(end 389.627872 -162.785044)
					)
				)
			)
		)
	)
	(footprint ""
		(layer "F.Cu")
		(at 20.7518 -229.50932 180)
		(property "Reference" "R1114"
			(at 0 0 180)
			(layer "F.SilkS")
			(hide yes)
			(effects
				(font
					(size 1.27 1.27)
				)
			)
		)
		(property "Value" "0R2J-2-GP"
			(at 0.064008 -3.993896 180)
			(unlocked yes)
			(layer "F.Fab")
			(hide yes)
			(effects
				(font
					(size 1.016 1.016)
					(thickness 0.1524)
				)
			)
		)
		(property "Device Type" "R402H16"
			(at 0.064008 -5.517896 180)
			(unlocked yes)
			(layer "F.Fab")
			(hide yes)
			(effects
				(font
					(size 1.016 1.016)
					(thickness 0.1524)
				)
			)
		)
		(duplicate_pad_numbers_are_jumpers no)
		(fp_line
			(start 0.508 -0.9398)
			(end -0.508 -0.9398)
			(stroke
				(width 0.1524)
				(type default)
			)
			(layer "F.SilkS")
		)
		(fp_line
			(start -0.508 -0.9398)
			(end -0.508 0.9398)
			(stroke
				(width 0.1524)
				(type default)
			)
			(layer "F.SilkS")
		)
		(fp_rect
			(start -0.508 0.9398)
			(end 0.508 -0.9398)
			(stroke
				(width 0)
				(type default)
			)
			(fill no)
			(layer "F.CrtYd")
		)
		(fp_rect
			(start -0.508 0.9398)
			(end 0.508 -0.9398)
			(stroke
				(width 0)
				(type default)
			)
			(fill no)
			(layer "F.Fab")
		)
		(pad "1" smd custom
			(at 0 -0.4445 180)
			(size 0.1397 0.1397)
			(layers "F.Cu" "F.Mask" "F.Paste")
			(net "P5V_B_1_ROVP")
			(options
				(clearance outline)
				(anchor circle)
			)
			(primitives
				(gr_poly
					(pts
						(arc
							(start -0.1778 -0.2794)
							(mid -0.249642 -0.249642)
							(end -0.2794 -0.1778)
						)
						(arc
							(start -0.2794 0.1778)
							(mid -0.249642 0.249642)
							(end -0.1778 0.2794)
						)
						(arc
							(start 0.1778 0.2794)
							(mid 0.249642 0.249642)
							(end 0.2794 0.1778)
						)
						(arc
							(start 0.2794 -0.1778)
							(mid 0.249642 -0.249642)
							(end 0.1778 -0.2794)
						)
					)
					(width 0)
					(fill yes)
				)
			)
		)
		(pad "2" smd custom
			(at 0 0.4445 180)
			(size 0.1397 0.1397)
			(layers "F.Cu" "F.Mask" "F.Paste")
			(net "AGND_P5V_B_1")
			(options
				(clearance outline)
				(anchor circle)
			)
			(primitives
				(gr_poly
					(pts
						(arc
							(start -0.1778 -0.2794)
							(mid -0.249642 -0.249642)
							(end -0.2794 -0.1778)
						)
						(arc
							(start -0.2794 0.1778)
							(mid -0.249642 0.249642)
							(end -0.1778 0.2794)
						)
						(arc
							(start 0.1778 0.2794)
							(mid 0.249642 0.249642)
							(end 0.2794 0.1778)
						)
						(arc
							(start 0.2794 -0.1778)
							(mid 0.249642 -0.249642)
							(end 0.1778 -0.2794)
						)
					)
					(width 0)
					(fill yes)
				)
			)
		)
	)
	(footprint ""
		(layer "F.Cu")
		(at 314.623196 -374.1928 90)
		(property "Reference" "R975"
			(at 0 0 90)
			(layer "F.SilkS")
			(hide yes)
			(effects
				(font
					(size 1.27 1.27)
				)
			)
		)
		(property "Value" "270R5J-2-GP"
			(at 0 -8.9535 90)
			(unlocked yes)
			(layer "F.Fab")
			(hide yes)
			(effects
				(font
					(size 1.27 1.016)
					(thickness 0.1524)
				)
			)
		)
		(property "Device Type" "R805H24"
			(at 0 -10.6299 90)
			(unlocked yes)
			(layer "F.Fab")
			(hide yes)
			(effects
				(font
					(size 1.27 1.016)
					(thickness 0.1524)
				)
			)
		)
		(duplicate_pad_numbers_are_jumpers no)
		(fp_line
			(start 0.889 -1.7018)
			(end -0.889 -1.7018)
			(stroke
				(width 0.1524)
				(type default)
			)
			(layer "F.SilkS")
		)
		(fp_line
			(start 0.889 -1.7018)
			(end 0.889 -0.381)
			(stroke
				(width 0.1524)
				(type default)
			)
			(layer "F.SilkS")
		)
		(fp_line
			(start -0.889 -1.7018)
			(end -0.889 0.2794)
			(stroke
				(width 0.1524)
				(type default)
			)
			(layer "F.SilkS")
		)
		(fp_line
			(start -0.889 0.0762)
			(end -0.889 1.7018)
			(stroke
				(width 0.1524)
				(type default)
			)
			(layer "F.SilkS")
		)
		(fp_line
			(start 0.889 1.7018)
			(end 0.889 -0.508)
			(stroke
				(width 0.1524)
				(type default)
			)
			(layer "F.SilkS")
		)
		(fp_line
			(start -0.889 1.7018)
			(end 0.889 1.7018)
			(stroke
				(width 0.1524)
				(type default)
			)
			(layer "F.SilkS")
		)
		(fp_poly
			(pts
				(xy 0.9652 -1.778) (xy 0.9652 1.778) (xy -0.9652 1.778) (xy -0.9652 -1.778)
			)
			(stroke
				(width 0)
				(type default)
			)
			(fill no)
			(layer "F.CrtYd")
		)
		(fp_rect
			(start -0.9652 1.778)
			(end 0.9652 -1.778)
			(stroke
				(width 0)
				(type default)
			)
			(fill no)
			(layer "F.Fab")
		)
		(pad "1" smd rect
			(at 0 -0.9652 90)
			(size 1.397 1.143)
			(layers "F.Cu" "F.Mask" "F.Paste")
			(net "FAN_LED_BLUE2")
		)
		(pad "2" smd rect
			(at 0 0.9652 90)
			(size 1.397 1.143)
			(layers "F.Cu" "F.Mask" "F.Paste")
			(net "FAN_BLUE2")
		)
	)
	(footprint ""
		(layer "F.Cu")
		(at 148.2217 -130.6957 180)
		(property "Reference" "R449"
			(at 0 0 180)
			(layer "F.SilkS")
			(hide yes)
			(effects
				(font
					(size 1.27 1.27)
				)
			)
		)
		(property "Value" "0R2J-2-GP"
			(at 0.064008 -3.993896 180)
			(unlocked yes)
			(layer "F.Fab")
			(hide yes)
			(effects
				(font
					(size 1.016 1.016)
					(thickness 0.1524)
				)
			)
		)
		(property "Device Type" "R402H16"
			(at 0.064008 -5.517896 180)
			(unlocked yes)
			(layer "F.Fab")
			(hide yes)
			(effects
				(font
					(size 1.016 1.016)
					(thickness 0.1524)
				)
			)
		)
		(duplicate_pad_numbers_are_jumpers no)
		(fp_line
			(start 0.508 -0.9398)
			(end -0.508 -0.9398)
			(stroke
				(width 0.1524)
				(type default)
			)
			(layer "F.SilkS")
		)
		(fp_line
			(start -0.508 -0.9398)
			(end -0.508 0.9398)
			(stroke
				(width 0.1524)
				(type default)
			)
			(layer "F.SilkS")
		)
		(fp_rect
			(start -0.508 0.9398)
			(end 0.508 -0.9398)
			(stroke
				(width 0)
				(type default)
			)
			(fill no)
			(layer "F.CrtYd")
		)
		(fp_rect
			(start -0.508 0.9398)
			(end 0.508 -0.9398)
			(stroke
				(width 0)
				(type default)
			)
			(fill no)
			(layer "F.Fab")
		)
		(pad "1" smd custom
			(at 0 -0.4445 180)
			(size 0.1397 0.1397)
			(layers "F.Cu" "F.Mask" "F.Paste")
			(net "DRIVE_B_16_PWR")
			(options
				(clearance outline)
				(anchor circle)
			)
			(primitives
				(gr_poly
					(pts
						(arc
							(start -0.1778 -0.2794)
							(mid -0.249642 -0.249642)
							(end -0.2794 -0.1778)
						)
						(arc
							(start -0.2794 0.1778)
							(mid -0.249642 0.249642)
							(end -0.1778 0.2794)
						)
						(arc
							(start 0.1778 0.2794)
							(mid 0.249642 0.249642)
							(end 0.2794 0.1778)
						)
						(arc
							(start 0.2794 -0.1778)
							(mid 0.249642 -0.249642)
							(end 0.1778 -0.2794)
						)
					)
					(width 0)
					(fill yes)
				)
			)
		)
		(pad "2" smd custom
			(at 0 0.4445 180)
			(size 0.1397 0.1397)
			(layers "F.Cu" "F.Mask" "F.Paste")
			(net "SW_PWR_R_HDD16")
			(options
				(clearance outline)
				(anchor circle)
			)
			(primitives
				(gr_poly
					(pts
						(arc
							(start -0.1778 -0.2794)
							(mid -0.249642 -0.249642)
							(end -0.2794 -0.1778)
						)
						(arc
							(start -0.2794 0.1778)
							(mid -0.249642 0.249642)
							(end -0.1778 0.2794)
						)
						(arc
							(start 0.1778 0.2794)
							(mid 0.249642 0.249642)
							(end 0.2794 0.1778)
						)
						(arc
							(start 0.2794 -0.1778)
							(mid 0.249642 -0.249642)
							(end 0.1778 -0.2794)
						)
					)
					(width 0)
					(fill yes)
				)
			)
		)
	)
	(footprint ""
		(layer "F.Cu")
		(at 473.964 -265.684 90)
		(property "Reference" "R336"
			(at 0 0 90)
			(layer "F.SilkS")
			(hide yes)
			(effects
				(font
					(size 1.27 1.27)
				)
			)
		)
		(property "Value" "2R6F-GP"
			(at -0.0508 -4.8514 90)
			(unlocked yes)
			(layer "F.Fab")
			(hide yes)
			(effects
				(font
					(size 1.016 1.016)
					(thickness 0.1524)
				)
			)
		)
		(property "Device Type" "R1206H26"
			(at 0 -6.3754 90)
			(unlocked yes)
			(layer "F.Fab")
			(hide yes)
			(effects
				(font
					(size 1.016 1.016)
					(thickness 0.1524)
				)
			)
		)
		(duplicate_pad_numbers_are_jumpers no)
		(fp_line
			(start 1.016 -2.2352)
			(end 1.016 2.2352)
			(stroke
				(width 0.1524)
				(type default)
			)
			(layer "F.SilkS")
		)
		(fp_line
			(start -1.016 -2.2352)
			(end 1.016 -2.2352)
			(stroke
				(width 0.1524)
				(type default)
			)
			(layer "F.SilkS")
		)
		(fp_line
			(start 1.016 2.2352)
			(end -1.016 2.2352)
			(stroke
				(width 0.1524)
				(type default)
			)
			(layer "F.SilkS")
		)
		(fp_line
			(start -1.016 2.2352)
			(end -1.016 -2.2352)
			(stroke
				(width 0.1524)
				(type default)
			)
			(layer "F.SilkS")
		)
		(fp_rect
			(start -1.0922 2.3114)
			(end 1.0922 -2.3114)
			(stroke
				(width 0)
				(type default)
			)
			(fill no)
			(layer "F.CrtYd")
		)
		(fp_poly
			(pts
				(xy -1.0922 -2.3114) (xy 1.0922 -2.3114) (xy 1.0922 2.3114) (xy -1.0922 2.3114)
			)
			(stroke
				(width 0)
				(type default)
			)
			(fill no)
			(layer "F.Fab")
		)
		(pad "1" smd rect
			(at 0 -1.397 90)
			(size 1.651 1.27)
			(layers "F.Cu" "F.Mask" "F.Paste")
			(net "P12V_HDD11")
		)
		(pad "2" smd rect
			(at 0 1.397 90)
			(size 1.651 1.27)
			(layers "F.Cu" "F.Mask" "F.Paste")
			(net "12V_PRE_11")
		)
	)
	(footprint ""
		(layer "F.Cu")
		(at 97.385632 -129.99085 90)
		(property "Reference" "VIA29"
			(at 0 0 90)
			(layer "F.SilkS")
			(hide yes)
			(effects
				(font
					(size 1.27 1.27)
				)
			)
		)
		(property "Value" "100OHM-8L-2D36MM-L18-GP"
			(at 3.8989 0.5715 90)
			(unlocked yes)
			(layer "F.Fab")
			(hide yes)
			(effects
				(font
					(size 1.016 1.016)
					(thickness 0.1524)
				)
			)
		)
		(property "Device Type" "VIA-PCIE-4P-414097"
			(at 3.8989 -0.9525 90)
			(unlocked yes)
			(layer "F.Fab")
			(hide yes)
			(effects
				(font
					(size 1.016 1.016)
					(thickness 0.1524)
				)
			)
		)
		(duplicate_pad_numbers_are_jumpers no)
		(fp_rect
			(start -2.0701 0.4826)
			(end 2.0701 -0.4826)
			(stroke
				(width 0)
				(type default)
			)
			(fill no)
			(layer "F.CrtYd")
		)
		(fp_rect
			(start -2.0701 0.4826)
			(end 2.0701 -0.4826)
			(stroke
				(width 0)
				(type default)
			)
			(fill no)
			(layer "F.Fab")
		)
		(pad "1" thru_hole circle
			(at -1.5875 0 90)
			(size 0.508 0.508)
			(drill 0.254)
			(layers "*.Cu" "*.Mask")
			(remove_unused_layers no)
			(net "GND")
			(clearance 0.2286)
			(thermal_gap 0.2286)
		)
		(pad "2" thru_hole circle
			(at -0.5715 0 90)
			(size 0.508 0.508)
			(drill 0.254)
			(layers "*.Cu" "*.Mask")
			(remove_unused_layers no)
			(net "PHY_SCC_B_TO_DRV_B_14_DP")
			(clearance 0.2286)
			(thermal_gap 0.2286)
		)
		(pad "3" thru_hole circle
			(at 0.5715 0 90)
			(size 0.508 0.508)
			(drill 0.254)
			(layers "*.Cu" "*.Mask")
			(remove_unused_layers no)
			(net "PHY_SCC_B_TO_DRV_B_14_DN")
			(clearance 0.2286)
			(thermal_gap 0.2286)
		)
		(pad "4" thru_hole circle
			(at 1.5875 0 90)
			(size 0.508 0.508)
			(drill 0.254)
			(layers "*.Cu" "*.Mask")
			(remove_unused_layers no)
			(net "GND")
			(clearance 0.2286)
			(thermal_gap 0.2286)
		)
	)
	(footprint ""
		(layer "F.Cu")
		(at 163.87953 -362.132626 90)
		(property "Reference" "R1010"
			(at 0 0 90)
			(layer "F.SilkS")
			(hide yes)
			(effects
				(font
					(size 1.27 1.27)
				)
			)
		)
		(property "Value" "49K9R2F-L-GP"
			(at 0.064008 -3.993896 90)
			(unlocked yes)
			(layer "F.Fab")
			(hide yes)
			(effects
				(font
					(size 1.016 1.016)
					(thickness 0.1524)
				)
			)
		)
		(property "Device Type" "R402H16"
			(at 0.064008 -5.517896 90)
			(unlocked yes)
			(layer "F.Fab")
			(hide yes)
			(effects
				(font
					(size 1.016 1.016)
					(thickness 0.1524)
				)
			)
		)
		(duplicate_pad_numbers_are_jumpers no)
		(fp_line
			(start 0.508 -0.9398)
			(end -0.508 -0.9398)
			(stroke
				(width 0.1524)
				(type default)
			)
			(layer "F.SilkS")
		)
		(fp_line
			(start -0.508 -0.9398)
			(end -0.508 0.9398)
			(stroke
				(width 0.1524)
				(type default)
			)
			(layer "F.SilkS")
		)
		(fp_rect
			(start -0.508 0.9398)
			(end 0.508 -0.9398)
			(stroke
				(width 0)
				(type default)
			)
			(fill no)
			(layer "F.CrtYd")
		)
		(fp_rect
			(start -0.508 0.9398)
			(end 0.508 -0.9398)
			(stroke
				(width 0)
				(type default)
			)
			(fill no)
			(layer "F.Fab")
		)
		(pad "1" smd custom
			(at 0 -0.4445 90)
			(size 0.1397 0.1397)
			(layers "F.Cu" "F.Mask" "F.Paste")
			(net "P12V_CLIP")
			(options
				(clearance outline)
				(anchor circle)
			)
			(primitives
				(gr_poly
					(pts
						(arc
							(start -0.1778 -0.2794)
							(mid -0.249642 -0.249642)
							(end -0.2794 -0.1778)
						)
						(arc
							(start -0.2794 0.1778)
							(mid -0.249642 0.249642)
							(end -0.1778 0.2794)
						)
						(arc
							(start 0.1778 0.2794)
							(mid 0.249642 0.249642)
							(end 0.2794 0.1778)
						)
						(arc
							(start 0.2794 -0.1778)
							(mid 0.249642 -0.249642)
							(end 0.1778 -0.2794)
						)
					)
					(width 0)
					(fill yes)
				)
			)
		)
		(pad "2" smd custom
			(at 0 0.4445 90)
			(size 0.1397 0.1397)
			(layers "F.Cu" "F.Mask" "F.Paste")
			(net "MB0_CM_OV_R")
			(options
				(clearance outline)
				(anchor circle)
			)
			(primitives
				(gr_poly
					(pts
						(arc
							(start -0.1778 -0.2794)
							(mid -0.249642 -0.249642)
							(end -0.2794 -0.1778)
						)
						(arc
							(start -0.2794 0.1778)
							(mid -0.249642 0.249642)
							(end -0.1778 0.2794)
						)
						(arc
							(start 0.1778 0.2794)
							(mid 0.249642 0.249642)
							(end 0.2794 0.1778)
						)
						(arc
							(start 0.2794 -0.1778)
							(mid 0.249642 -0.249642)
							(end 0.1778 -0.2794)
						)
					)
					(width 0)
					(fill yes)
				)
			)
		)
	)
	(footprint ""
		(layer "F.Cu")
		(at 279.4 -378.000006 180)
		(property "Reference" "LED25"
			(at 0 0 180)
			(layer "F.SilkS")
			(hide yes)
			(effects
				(font
					(size 1.27 1.27)
				)
			)
		)
		(property "Value" "LED-IR-43-GP"
			(at -3.7846 1.0668 180)
			(unlocked yes)
			(layer "F.Fab")
			(hide yes)
			(effects
				(font
					(size 1.016 1.016)
					(thickness 0.1524)
				)
			)
		)
		(property "Device Type" "LED4036-2A1KH168"
			(at -3.7846 -0.4572 180)
			(unlocked yes)
			(layer "F.Fab")
			(hide yes)
			(effects
				(font
					(size 1.016 1.016)
					(thickness 0.1524)
				)
			)
		)
		(duplicate_pad_numbers_are_jumpers no)
		(fp_line
			(start 2.6162 2.54)
			(end 2.6162 1.27)
			(stroke
				(width 0.508)
				(type default)
			)
			(layer "F.SilkS")
		)
		(fp_line
			(start 2.4384 2.3622)
			(end 2.4384 -2.3622)
			(stroke
				(width 0.1524)
				(type default)
			)
			(layer "F.SilkS")
		)
		(fp_line
			(start 2.4384 -2.3622)
			(end -2.2606 -2.3622)
			(stroke
				(width 0.1524)
				(type default)
			)
			(layer "F.SilkS")
		)
		(fp_line
			(start -2.2606 2.3622)
			(end 2.4384 2.3622)
			(stroke
				(width 0.1524)
				(type default)
			)
			(layer "F.SilkS")
		)
		(fp_line
			(start -2.2606 -2.3622)
			(end -2.2606 2.3622)
			(stroke
				(width 0.1524)
				(type default)
			)
			(layer "F.SilkS")
		)
		(fp_line
			(start -2.4384 2.54)
			(end 2.6162 2.54)
			(stroke
				(width 0.508)
				(type default)
			)
			(layer "F.SilkS")
		)
		(fp_line
			(start -2.4384 1.27)
			(end -2.4384 2.54)
			(stroke
				(width 0.508)
				(type default)
			)
			(layer "F.SilkS")
		)
		(fp_rect
			(start -1.4224 1.9939)
			(end 2.1844 -1.9939)
			(stroke
				(width 0)
				(type default)
			)
			(fill no)
			(layer "F.CrtYd")
		)
		(fp_poly
			(pts
				(xy -2.5146 2.4384) (xy -2.5146 -2.4384) (xy 2.6924 -2.4384) (xy 2.6924 -0.00635) (xy 2.1844 -0.00635)
				(xy 2.1844 -1.9939) (xy -1.4224 -1.9939) (xy -1.4224 1.9939) (xy 2.1844 1.9939) (xy 2.1844 0.00635)
				(xy 2.6924 0.00635) (xy 2.6924 2.4384)
			)
			(stroke
				(width 0)
				(type default)
			)
			(fill no)
			(layer "F.CrtYd")
		)
		(fp_rect
			(start -2.5146 2.4384)
			(end 2.6924 -2.4384)
			(stroke
				(width 0)
				(type default)
			)
			(fill no)
			(layer "F.Fab")
		)
		(pad "1K" smd rect
			(at 0 1.249934 180)
			(size 3.9878 1.7018)
			(layers "F.Cu" "F.Mask" "F.Paste")
			(net "EMITTER_K")
		)
		(pad "2A" smd rect
			(at 0 -1.249934 180)
			(size 3.9878 1.7018)
			(layers "F.Cu" "F.Mask" "F.Paste")
			(net "P3V3_IN")
		)
	)
	(footprint ""
		(layer "F.Cu")
		(at 248.285 -305.054 90)
		(property "Reference" "R1088"
			(at 0 0 90)
			(layer "F.SilkS")
			(hide yes)
			(effects
				(font
					(size 1.27 1.27)
				)
			)
		)
		(property "Value" "0R2J-2-GP"
			(at 0.064008 -3.993896 90)
			(unlocked yes)
			(layer "F.Fab")
			(hide yes)
			(effects
				(font
					(size 1.016 1.016)
					(thickness 0.1524)
				)
			)
		)
		(property "Device Type" "R402H16"
			(at 0.064008 -5.517896 90)
			(unlocked yes)
			(layer "F.Fab")
			(hide yes)
			(effects
				(font
					(size 1.016 1.016)
					(thickness 0.1524)
				)
			)
		)
		(duplicate_pad_numbers_are_jumpers no)
		(fp_line
			(start 0.508 -0.9398)
			(end -0.508 -0.9398)
			(stroke
				(width 0.1524)
				(type default)
			)
			(layer "F.SilkS")
		)
		(fp_line
			(start -0.508 -0.9398)
			(end -0.508 0.9398)
			(stroke
				(width 0.1524)
				(type default)
			)
			(layer "F.SilkS")
		)
		(fp_rect
			(start -0.508 0.9398)
			(end 0.508 -0.9398)
			(stroke
				(width 0)
				(type default)
			)
			(fill no)
			(layer "F.CrtYd")
		)
		(fp_rect
			(start -0.508 0.9398)
			(end 0.508 -0.9398)
			(stroke
				(width 0)
				(type default)
			)
			(fill no)
			(layer "F.Fab")
		)
		(pad "1" smd custom
			(at 0 -0.4445 90)
			(size 0.1397 0.1397)
			(layers "F.Cu" "F.Mask" "F.Paste")
			(net "MAX31790_A_SCL")
			(options
				(clearance outline)
				(anchor circle)
			)
			(primitives
				(gr_poly
					(pts
						(arc
							(start -0.1778 -0.2794)
							(mid -0.249642 -0.249642)
							(end -0.2794 -0.1778)
						)
						(arc
							(start -0.2794 0.1778)
							(mid -0.249642 0.249642)
							(end -0.1778 0.2794)
						)
						(arc
							(start 0.1778 0.2794)
							(mid 0.249642 0.249642)
							(end 0.2794 0.1778)
						)
						(arc
							(start 0.2794 -0.1778)
							(mid 0.249642 -0.249642)
							(end 0.1778 -0.2794)
						)
					)
					(width 0)
					(fill yes)
				)
			)
		)
		(pad "2" smd custom
			(at 0 0.4445 90)
			(size 0.1397 0.1397)
			(layers "F.Cu" "F.Mask" "F.Paste")
			(net "I2C_DPB_A_SCL_BUF")
			(options
				(clearance outline)
				(anchor circle)
			)
			(primitives
				(gr_poly
					(pts
						(arc
							(start -0.1778 -0.2794)
							(mid -0.249642 -0.249642)
							(end -0.2794 -0.1778)
						)
						(arc
							(start -0.2794 0.1778)
							(mid -0.249642 0.249642)
							(end -0.1778 0.2794)
						)
						(arc
							(start 0.1778 0.2794)
							(mid 0.249642 0.249642)
							(end 0.2794 0.1778)
						)
						(arc
							(start 0.2794 -0.1778)
							(mid 0.249642 -0.249642)
							(end 0.1778 -0.2794)
						)
					)
					(width 0)
					(fill yes)
				)
			)
		)
	)
	(footprint ""
		(layer "F.Cu")
		(at 159.324802 -178.799998)
		(property "Reference" ""
			(at 0 0 0)
			(layer "F.SilkS")
			(hide yes)
			(effects
				(font
					(size 1.27 1.27)
				)
			)
		)
		(property "Value" "*"
			(at -8.398764 -8.057642 0)
			(unlocked yes)
			(layer "F.Fab")
			(hide yes)
			(effects
				(font
					(size 1.016 1.016)
					(thickness 0.1524)
				)
			)
		)
		(duplicate_pad_numbers_are_jumpers no)
		(fp_poly
			(pts
				(arc
					(start 7.3152 0)
					(mid 0 7.3152)
					(end -7.3152 0)
				)
				(arc
					(start -7.3152 -5.9944)
					(mid 0 -13.3096)
					(end 7.3152 -5.9944)
				)
			)
			(stroke
				(width 0)
				(type default)
			)
			(fill no)
			(layer "B.CrtYd")
		)
		(fp_poly
			(pts
				(arc
					(start 7.3152 0)
					(mid 0 7.3152)
					(end -7.3152 0)
				)
				(arc
					(start -7.3152 -5.9944)
					(mid 0 -13.3096)
					(end 7.3152 -5.9944)
				)
			)
			(stroke
				(width 0)
				(type default)
			)
			(fill no)
			(layer "F.CrtYd")
		)
		(fp_poly
			(pts
				(arc
					(start 7.3152 0)
					(mid 0 7.3152)
					(end -7.3152 0)
				)
				(arc
					(start -7.3152 -5.9944)
					(mid 0 -13.3096)
					(end 7.3152 -5.9944)
				)
			)
			(stroke
				(width 0)
				(type default)
			)
			(fill no)
			(layer "B.Fab")
		)
		(fp_poly
			(pts
				(arc
					(start 7.3152 0)
					(mid 0 7.3152)
					(end -7.3152 0)
				)
				(arc
					(start -7.3152 -5.9944)
					(mid 0 -13.3096)
					(end 7.3152 -5.9944)
				)
			)
			(stroke
				(width 0)
				(type default)
			)
			(fill no)
			(layer "F.Fab")
		)
		(pad "1" thru_hole oval
			(at 0 0)
			(size 14.0208 20.0152)
			(drill 0.0254
				(offset 0 -2.9972)
			)
			(layers "*.Cu" "*.Mask")
			(remove_unused_layers no)
			(net "Net_45")
			(clearance -1.002284)
			(thermal_gap 0.1524)
			(padstack
				(mode front_inner_back)
				(layer "Inner"
					(shape custom)
					(size 2.928012 2.928012)
					(options
						(anchor circle)
					)
					(primitives
						(gr_poly
							(pts
								(arc
									(start 4.571746 -2.084324)
									(mid 0.000333 7.430372)
									(end -4.571492 -2.084324)
								)
								(arc
									(start -4.571492 -2.084324)
									(mid -3.570296 -3.611977)
									(end -2.875026 -5.30098)
								)
								(arc
									(start -2.875026 -5.30098)
									(mid 0.000217 -7.43089)
									(end 2.87528 -5.30098)
								)
								(arc
									(start 2.87528 -5.30098)
									(mid 3.570511 -3.611956)
									(end 4.571746 -2.084324)
								)
							)
							(width 0)
							(fill yes)
						)
					)
					(clearance 0.1524)
				)
				(layer "B.Cu"
					(shape oval)
					(size 14.0208 20.0152)
					(offset 0 -2.9972)
					(clearance -1.002284)
				)
			)
		)
		(zone
			(layers "F.Cu" "B.Cu" "In1.Cu" "In2.Cu" "In3.Cu" "In4.Cu" "In5.Cu" "In6.Cu")
			(hatch none 0.5)
			(connect_pads
				(clearance 0)
			)
			(min_thickness 0.25)
			(keepout
				(tracks not_allowed)
				(vias allowed)
				(pads allowed)
				(copperpour not_allowed)
				(footprints allowed)
			)
			(placement
				(enabled no)
				(sheetname "")
			)
			(fill
				(thermal_gap 0.5)
				(thermal_bridge_width 0.5)
				(island_removal_mode 0)
			)
			(polygon
				(pts
					(arc
						(start 152.314402 -184.794398)
						(mid 159.324802 -191.804798)
						(end 166.335202 -184.794398)
					)
					(arc
						(start 166.335202 -178.799998)
						(mid 159.324802 -171.789598)
						(end 152.314402 -178.799998)
					)
				)
			)
		)
	)
	(footprint ""
		(layer "F.Cu")
		(at 367.284 -243.586 180)
		(property "Reference" "R278"
			(at 0 0 180)
			(layer "F.SilkS")
			(hide yes)
			(effects
				(font
					(size 1.27 1.27)
				)
			)
		)
		(property "Value" "0R2J-2-GP"
			(at 0.064008 -3.993896 180)
			(unlocked yes)
			(layer "F.Fab")
			(hide yes)
			(effects
				(font
					(size 1.016 1.016)
					(thickness 0.1524)
				)
			)
		)
		(property "Device Type" "R402H16"
			(at 0.064008 -5.517896 180)
			(unlocked yes)
			(layer "F.Fab")
			(hide yes)
			(effects
				(font
					(size 1.016 1.016)
					(thickness 0.1524)
				)
			)
		)
		(duplicate_pad_numbers_are_jumpers no)
		(fp_line
			(start 0.508 -0.9398)
			(end -0.508 -0.9398)
			(stroke
				(width 0.1524)
				(type default)
			)
			(layer "F.SilkS")
		)
		(fp_line
			(start -0.508 -0.9398)
			(end -0.508 0.9398)
			(stroke
				(width 0.1524)
				(type default)
			)
			(layer "F.SilkS")
		)
		(fp_rect
			(start -0.508 0.9398)
			(end 0.508 -0.9398)
			(stroke
				(width 0)
				(type default)
			)
			(fill no)
			(layer "F.CrtYd")
		)
		(fp_rect
			(start -0.508 0.9398)
			(end 0.508 -0.9398)
			(stroke
				(width 0)
				(type default)
			)
			(fill no)
			(layer "F.Fab")
		)
		(pad "1" smd custom
			(at 0 -0.4445 180)
			(size 0.1397 0.1397)
			(layers "F.Cu" "F.Mask" "F.Paste")
			(net "DRIVE_B_7_PWR")
			(options
				(clearance outline)
				(anchor circle)
			)
			(primitives
				(gr_poly
					(pts
						(arc
							(start -0.1778 -0.2794)
							(mid -0.249642 -0.249642)
							(end -0.2794 -0.1778)
						)
						(arc
							(start -0.2794 0.1778)
							(mid -0.249642 0.249642)
							(end -0.1778 0.2794)
						)
						(arc
							(start 0.1778 0.2794)
							(mid 0.249642 0.249642)
							(end 0.2794 0.1778)
						)
						(arc
							(start 0.2794 -0.1778)
							(mid 0.249642 -0.249642)
							(end 0.1778 -0.2794)
						)
					)
					(width 0)
					(fill yes)
				)
			)
		)
		(pad "2" smd custom
			(at 0 0.4445 180)
			(size 0.1397 0.1397)
			(layers "F.Cu" "F.Mask" "F.Paste")
			(net "SW_PWR_R_HDD7")
			(options
				(clearance outline)
				(anchor circle)
			)
			(primitives
				(gr_poly
					(pts
						(arc
							(start -0.1778 -0.2794)
							(mid -0.249642 -0.249642)
							(end -0.2794 -0.1778)
						)
						(arc
							(start -0.2794 0.1778)
							(mid -0.249642 0.249642)
							(end -0.1778 0.2794)
						)
						(arc
							(start 0.1778 0.2794)
							(mid 0.249642 0.249642)
							(end 0.2794 0.1778)
						)
						(arc
							(start 0.2794 -0.1778)
							(mid 0.249642 -0.249642)
							(end 0.1778 -0.2794)
						)
					)
					(width 0)
					(fill yes)
				)
			)
		)
	)
	(footprint ""
		(layer "F.Cu")
		(at 209.92338 -247.88622)
		(property "Reference" "R43"
			(at 0 0 0)
			(layer "F.SilkS")
			(hide yes)
			(effects
				(font
					(size 1.27 1.27)
				)
			)
		)
		(property "Value" "4K7R2F-GP"
			(at 0.064008 -3.993896 0)
			(unlocked yes)
			(layer "F.Fab")
			(hide yes)
			(effects
				(font
					(size 1.016 1.016)
					(thickness 0.1524)
				)
			)
		)
		(property "Device Type" "R402H16"
			(at 0.064008 -5.517896 0)
			(unlocked yes)
			(layer "F.Fab")
			(hide yes)
			(effects
				(font
					(size 1.016 1.016)
					(thickness 0.1524)
				)
			)
		)
		(duplicate_pad_numbers_are_jumpers no)
		(fp_line
			(start -0.508 -0.9398)
			(end -0.508 0.9398)
			(stroke
				(width 0.1524)
				(type default)
			)
			(layer "F.SilkS")
		)
		(fp_line
			(start 0.508 -0.9398)
			(end -0.508 -0.9398)
			(stroke
				(width 0.1524)
				(type default)
			)
			(layer "F.SilkS")
		)
		(fp_rect
			(start -0.508 0.9398)
			(end 0.508 -0.9398)
			(stroke
				(width 0)
				(type default)
			)
			(fill no)
			(layer "F.CrtYd")
		)
		(fp_rect
			(start -0.508 0.9398)
			(end 0.508 -0.9398)
			(stroke
				(width 0)
				(type default)
			)
			(fill no)
			(layer "F.Fab")
		)
		(pad "1" smd custom
			(at 0 -0.4445)
			(size 0.1397 0.1397)
			(layers "F.Cu" "F.Mask" "F.Paste")
			(net "P3V3_STBY_B")
			(options
				(clearance outline)
				(anchor circle)
			)
			(primitives
				(gr_poly
					(pts
						(arc
							(start -0.1778 -0.2794)
							(mid -0.249642 -0.249642)
							(end -0.2794 -0.1778)
						)
						(arc
							(start -0.2794 0.1778)
							(mid -0.249642 0.249642)
							(end -0.1778 0.2794)
						)
						(arc
							(start 0.1778 0.2794)
							(mid 0.249642 0.249642)
							(end 0.2794 0.1778)
						)
						(arc
							(start 0.2794 -0.1778)
							(mid 0.249642 -0.249642)
							(end 0.1778 -0.2794)
						)
					)
					(width 0)
					(fill yes)
				)
			)
		)
		(pad "2" smd custom
			(at 0 0.4445)
			(size 0.1397 0.1397)
			(layers "F.Cu" "F.Mask" "F.Paste")
			(net "IO_EXP4_A2")
			(options
				(clearance outline)
				(anchor circle)
			)
			(primitives
				(gr_poly
					(pts
						(arc
							(start -0.1778 -0.2794)
							(mid -0.249642 -0.249642)
							(end -0.2794 -0.1778)
						)
						(arc
							(start -0.2794 0.1778)
							(mid -0.249642 0.249642)
							(end -0.1778 0.2794)
						)
						(arc
							(start 0.1778 0.2794)
							(mid 0.249642 0.249642)
							(end 0.2794 0.1778)
						)
						(arc
							(start 0.2794 -0.1778)
							(mid 0.249642 -0.249642)
							(end 0.1778 -0.2794)
						)
					)
					(width 0)
					(fill yes)
				)
			)
		)
	)
	(footprint ""
		(layer "F.Cu")
		(at 437.463184 -119.192548 180)
		(property "Reference" "R1170"
			(at 0 0 180)
			(layer "F.SilkS")
			(hide yes)
			(effects
				(font
					(size 1.27 1.27)
				)
			)
		)
		(property "Value" "0R2J-2-GP"
			(at 0.064008 -3.993896 180)
			(unlocked yes)
			(layer "F.Fab")
			(hide yes)
			(effects
				(font
					(size 1.016 1.016)
					(thickness 0.1524)
				)
			)
		)
		(property "Device Type" "R402H16"
			(at 0.064008 -5.517896 180)
			(unlocked yes)
			(layer "F.Fab")
			(hide yes)
			(effects
				(font
					(size 1.016 1.016)
					(thickness 0.1524)
				)
			)
		)
		(duplicate_pad_numbers_are_jumpers no)
		(fp_line
			(start 0.508 -0.9398)
			(end -0.508 -0.9398)
			(stroke
				(width 0.1524)
				(type default)
			)
			(layer "F.SilkS")
		)
		(fp_line
			(start -0.508 -0.9398)
			(end -0.508 0.9398)
			(stroke
				(width 0.1524)
				(type default)
			)
			(layer "F.SilkS")
		)
		(fp_rect
			(start -0.508 0.9398)
			(end 0.508 -0.9398)
			(stroke
				(width 0)
				(type default)
			)
			(fill no)
			(layer "F.CrtYd")
		)
		(fp_rect
			(start -0.508 0.9398)
			(end 0.508 -0.9398)
			(stroke
				(width 0)
				(type default)
			)
			(fill no)
			(layer "F.Fab")
		)
		(pad "1" smd custom
			(at 0 -0.4445 180)
			(size 0.1397 0.1397)
			(layers "F.Cu" "F.Mask" "F.Paste")
			(net "P5V_B_4_ROVP")
			(options
				(clearance outline)
				(anchor circle)
			)
			(primitives
				(gr_poly
					(pts
						(arc
							(start -0.1778 -0.2794)
							(mid -0.249642 -0.249642)
							(end -0.2794 -0.1778)
						)
						(arc
							(start -0.2794 0.1778)
							(mid -0.249642 0.249642)
							(end -0.1778 0.2794)
						)
						(arc
							(start 0.1778 0.2794)
							(mid 0.249642 0.249642)
							(end 0.2794 0.1778)
						)
						(arc
							(start 0.2794 -0.1778)
							(mid 0.249642 -0.249642)
							(end 0.1778 -0.2794)
						)
					)
					(width 0)
					(fill yes)
				)
			)
		)
		(pad "2" smd custom
			(at 0 0.4445 180)
			(size 0.1397 0.1397)
			(layers "F.Cu" "F.Mask" "F.Paste")
			(net "AGND_P5V_B_4")
			(options
				(clearance outline)
				(anchor circle)
			)
			(primitives
				(gr_poly
					(pts
						(arc
							(start -0.1778 -0.2794)
							(mid -0.249642 -0.249642)
							(end -0.2794 -0.1778)
						)
						(arc
							(start -0.2794 0.1778)
							(mid -0.249642 0.249642)
							(end -0.1778 0.2794)
						)
						(arc
							(start 0.1778 0.2794)
							(mid 0.249642 0.249642)
							(end 0.2794 0.1778)
						)
						(arc
							(start 0.2794 -0.1778)
							(mid 0.249642 -0.249642)
							(end 0.1778 -0.2794)
						)
					)
					(width 0)
					(fill yes)
				)
			)
		)
	)
	(footprint ""
		(layer "F.Cu")
		(at 336.804 -148.082)
		(property "Reference" "Q84"
			(at 0 0 0)
			(layer "F.SilkS")
			(hide yes)
			(effects
				(font
					(size 1.27 1.27)
				)
			)
		)
		(property "Value" "AO4407AL-GP"
			(at -3.707384 -1.5367 0)
			(unlocked yes)
			(layer "F.Fab")
			(hide yes)
			(effects
				(font
					(size 1.016 1.016)
					(thickness 0.1524)
				)
			)
		)
		(property "Device Type" "SOIC8H69"
			(at -3.707384 -3.0607 0)
			(unlocked yes)
			(layer "F.Fab")
			(hide yes)
			(effects
				(font
					(size 1.016 1.016)
					(thickness 0.1524)
				)
			)
		)
		(duplicate_pad_numbers_are_jumpers no)
		(fp_line
			(start -2.7432 -1.4224)
			(end -2.7432 1.4224)
			(stroke
				(width 0.1524)
				(type default)
			)
			(layer "F.SilkS")
		)
		(fp_line
			(start -2.7432 1.4224)
			(end -2.6416 1.4224)
			(stroke
				(width 0.1524)
				(type default)
			)
			(layer "F.SilkS")
		)
		(fp_line
			(start -2.7432 1.4224)
			(end 2.1336 1.4224)
			(stroke
				(width 0.1524)
				(type default)
			)
			(layer "F.SilkS")
		)
		(fp_line
			(start -2.7178 -0.508)
			(end -2.1844 -0.0508)
			(stroke
				(width 0.1524)
				(type default)
			)
			(layer "F.SilkS")
		)
		(fp_line
			(start -2.6289 3.4417)
			(end -2.6289 1.4732)
			(stroke
				(width 0.381)
				(type default)
			)
			(layer "F.SilkS")
		)
		(fp_line
			(start -2.1844 -0.0508)
			(end -2.7178 0.508)
			(stroke
				(width 0.1524)
				(type default)
			)
			(layer "F.SilkS")
		)
		(fp_line
			(start 2.1336 -1.4224)
			(end -2.7432 -1.4224)
			(stroke
				(width 0.1524)
				(type default)
			)
			(layer "F.SilkS")
		)
		(fp_line
			(start 2.1336 1.4224)
			(end 2.1336 -1.4224)
			(stroke
				(width 0.1524)
				(type default)
			)
			(layer "F.SilkS")
		)
		(fp_poly
			(pts
				(xy -2.2098 -1.4224) (xy -2.2098 1.4224) (xy 2.2098 1.4224) (xy 2.2098 -1.4224)
			)
			(stroke
				(width 0)
				(type default)
			)
			(fill yes)
			(layer "F.SilkS")
		)
		(fp_rect
			(start -2.450084 2.999994)
			(end 2.450084 -2.999994)
			(stroke
				(width 0)
				(type default)
			)
			(fill no)
			(layer "F.CrtYd")
		)
		(fp_poly
			(pts
				(xy -2.8194 3.6322) (xy -2.8194 -3.6322) (xy 2.8194 -3.6322) (xy 2.8194 1.18364) (xy 2.450084 1.18364)
				(xy 2.450084 -2.999994) (xy -2.450084 -2.999994) (xy -2.450084 2.999994) (xy 2.450084 2.999994)
				(xy 2.450084 1.18618) (xy 2.8194 1.18618) (xy 2.8194 3.6322)
			)
			(stroke
				(width 0)
				(type default)
			)
			(fill no)
			(layer "F.CrtYd")
		)
		(fp_rect
			(start -2.8194 3.6322)
			(end 2.8194 -3.6322)
			(stroke
				(width 0)
				(type default)
			)
			(fill no)
			(layer "F.Fab")
		)
		(pad "1" smd rect
			(at -1.905 2.54)
			(size 0.635 1.651)
			(layers "F.Cu" "F.Mask" "F.Paste")
			(net "P12V_B")
		)
		(pad "2" smd rect
			(at -0.635 2.54)
			(size 0.635 1.651)
			(layers "F.Cu" "F.Mask" "F.Paste")
			(net "P12V_B")
		)
		(pad "3" smd rect
			(at 0.635 2.54)
			(size 0.635 1.651)
			(layers "F.Cu" "F.Mask" "F.Paste")
			(net "P12V_B")
		)
		(pad "4" smd rect
			(at 1.905 2.54)
			(size 0.635 1.651)
			(layers "F.Cu" "F.Mask" "F.Paste")
			(net "SW_HDD_N18")
		)
		(pad "5" smd rect
			(at 1.905 -2.54)
			(size 0.635 1.651)
			(layers "F.Cu" "F.Mask" "F.Paste")
			(net "P12V_HDD18")
		)
		(pad "6" smd rect
			(at 0.635 -2.54)
			(size 0.635 1.651)
			(layers "F.Cu" "F.Mask" "F.Paste")
			(net "P12V_HDD18")
		)
		(pad "7" smd rect
			(at -0.635 -2.54)
			(size 0.635 1.651)
			(layers "F.Cu" "F.Mask" "F.Paste")
			(net "P12V_HDD18")
		)
		(pad "8" smd rect
			(at -1.905 -2.54)
			(size 0.635 1.651)
			(layers "F.Cu" "F.Mask" "F.Paste")
			(net "P12V_HDD18")
		)
	)
	(footprint ""
		(layer "F.Cu")
		(at 246.619522 -363.702346 90)
		(property "Reference" "R1026"
			(at 0 0 90)
			(layer "F.SilkS")
			(hide yes)
			(effects
				(font
					(size 1.27 1.27)
				)
			)
		)
		(property "Value" "10R2F-L-GP"
			(at 0.064008 -3.993896 90)
			(unlocked yes)
			(layer "F.Fab")
			(hide yes)
			(effects
				(font
					(size 1.016 1.016)
					(thickness 0.1524)
				)
			)
		)
		(property "Device Type" "R402H14"
			(at 0.064008 -5.517896 90)
			(unlocked yes)
			(layer "F.Fab")
			(hide yes)
			(effects
				(font
					(size 1.016 1.016)
					(thickness 0.1524)
				)
			)
		)
		(duplicate_pad_numbers_are_jumpers no)
		(fp_line
			(start 0.508 -0.9398)
			(end -0.508 -0.9398)
			(stroke
				(width 0.1524)
				(type default)
			)
			(layer "F.SilkS")
		)
		(fp_line
			(start -0.508 -0.9398)
			(end -0.508 0.9398)
			(stroke
				(width 0.1524)
				(type default)
			)
			(layer "F.SilkS")
		)
		(fp_rect
			(start -0.508 0.9398)
			(end 0.508 -0.9398)
			(stroke
				(width 0)
				(type default)
			)
			(fill no)
			(layer "F.CrtYd")
		)
		(fp_rect
			(start -0.508 0.9398)
			(end 0.508 -0.9398)
			(stroke
				(width 0)
				(type default)
			)
			(fill no)
			(layer "F.Fab")
		)
		(pad "1" smd custom
			(at 0 -0.4445 90)
			(size 0.1397 0.1397)
			(layers "F.Cu" "F.Mask" "F.Paste")
			(net "P12V_IN")
			(options
				(clearance outline)
				(anchor circle)
			)
			(primitives
				(gr_poly
					(pts
						(arc
							(start -0.1778 -0.2794)
							(mid -0.249642 -0.249642)
							(end -0.2794 -0.1778)
						)
						(arc
							(start -0.2794 0.1778)
							(mid -0.249642 0.249642)
							(end -0.1778 0.2794)
						)
						(arc
							(start 0.1778 0.2794)
							(mid 0.249642 0.249642)
							(end 0.2794 0.1778)
						)
						(arc
							(start 0.2794 -0.1778)
							(mid 0.249642 -0.249642)
							(end 0.1778 -0.2794)
						)
					)
					(width 0)
					(fill yes)
				)
			)
		)
		(pad "2" smd custom
			(at 0 0.4445 90)
			(size 0.1397 0.1397)
			(layers "F.Cu" "F.Mask" "F.Paste")
			(net "MB3_P12V_HS")
			(options
				(clearance outline)
				(anchor circle)
			)
			(primitives
				(gr_poly
					(pts
						(arc
							(start -0.1778 -0.2794)
							(mid -0.249642 -0.249642)
							(end -0.2794 -0.1778)
						)
						(arc
							(start -0.2794 0.1778)
							(mid -0.249642 0.249642)
							(end -0.1778 0.2794)
						)
						(arc
							(start 0.1778 0.2794)
							(mid 0.249642 0.249642)
							(end 0.2794 0.1778)
						)
						(arc
							(start 0.2794 -0.1778)
							(mid 0.249642 -0.249642)
							(end 0.1778 -0.2794)
						)
					)
					(width 0)
					(fill yes)
				)
			)
		)
	)
	(footprint ""
		(layer "F.Cu")
		(at 96.324928 -63.799974)
		(property "Reference" ""
			(at 0 0 0)
			(layer "F.SilkS")
			(hide yes)
			(effects
				(font
					(size 1.27 1.27)
				)
			)
		)
		(property "Value" "*"
			(at -8.398764 -8.057642 0)
			(unlocked yes)
			(layer "F.Fab")
			(hide yes)
			(effects
				(font
					(size 1.016 1.016)
					(thickness 0.1524)
				)
			)
		)
		(duplicate_pad_numbers_are_jumpers no)
		(fp_poly
			(pts
				(arc
					(start 7.3152 0)
					(mid 0 7.3152)
					(end -7.3152 0)
				)
				(arc
					(start -7.3152 -5.9944)
					(mid 0 -13.3096)
					(end 7.3152 -5.9944)
				)
			)
			(stroke
				(width 0)
				(type default)
			)
			(fill no)
			(layer "B.CrtYd")
		)
		(fp_poly
			(pts
				(arc
					(start 7.3152 0)
					(mid 0 7.3152)
					(end -7.3152 0)
				)
				(arc
					(start -7.3152 -5.9944)
					(mid 0 -13.3096)
					(end 7.3152 -5.9944)
				)
			)
			(stroke
				(width 0)
				(type default)
			)
			(fill no)
			(layer "F.CrtYd")
		)
		(fp_poly
			(pts
				(arc
					(start 7.3152 0)
					(mid 0 7.3152)
					(end -7.3152 0)
				)
				(arc
					(start -7.3152 -5.9944)
					(mid 0 -13.3096)
					(end 7.3152 -5.9944)
				)
			)
			(stroke
				(width 0)
				(type default)
			)
			(fill no)
			(layer "B.Fab")
		)
		(fp_poly
			(pts
				(arc
					(start 7.3152 0)
					(mid 0 7.3152)
					(end -7.3152 0)
				)
				(arc
					(start -7.3152 -5.9944)
					(mid 0 -13.3096)
					(end 7.3152 -5.9944)
				)
			)
			(stroke
				(width 0)
				(type default)
			)
			(fill no)
			(layer "F.Fab")
		)
		(pad "1" thru_hole oval
			(at 0 0)
			(size 14.0208 20.0152)
			(drill 0.0254
				(offset 0 -2.9972)
			)
			(layers "*.Cu" "*.Mask")
			(remove_unused_layers no)
			(net "Net_48")
			(clearance -1.002284)
			(thermal_gap 0.1524)
			(padstack
				(mode front_inner_back)
				(layer "Inner"
					(shape custom)
					(size 2.928012 2.928012)
					(options
						(anchor circle)
					)
					(primitives
						(gr_poly
							(pts
								(arc
									(start 4.571746 -2.084324)
									(mid 0.000333 7.430372)
									(end -4.571492 -2.084324)
								)
								(arc
									(start -4.571492 -2.084324)
									(mid -3.570296 -3.611977)
									(end -2.875026 -5.30098)
								)
								(arc
									(start -2.875026 -5.30098)
									(mid 0.000217 -7.43089)
									(end 2.87528 -5.30098)
								)
								(arc
									(start 2.87528 -5.30098)
									(mid 3.570511 -3.611956)
									(end 4.571746 -2.084324)
								)
							)
							(width 0)
							(fill yes)
						)
					)
					(clearance 0.1524)
				)
				(layer "B.Cu"
					(shape oval)
					(size 14.0208 20.0152)
					(offset 0 -2.9972)
					(clearance -1.002284)
				)
			)
		)
		(zone
			(layers "F.Cu" "B.Cu" "In1.Cu" "In2.Cu" "In3.Cu" "In4.Cu" "In5.Cu" "In6.Cu")
			(hatch none 0.5)
			(connect_pads
				(clearance 0)
			)
			(min_thickness 0.25)
			(keepout
				(tracks not_allowed)
				(vias allowed)
				(pads allowed)
				(copperpour not_allowed)
				(footprints allowed)
			)
			(placement
				(enabled no)
				(sheetname "")
			)
			(fill
				(thermal_gap 0.5)
				(thermal_bridge_width 0.5)
				(island_removal_mode 0)
			)
			(polygon
				(pts
					(arc
						(start 89.314528 -69.794374)
						(mid 96.324928 -76.804774)
						(end 103.335328 -69.794374)
					)
					(arc
						(start 103.335328 -63.799974)
						(mid 96.324928 -56.789574)
						(end 89.314528 -63.799974)
					)
				)
			)
		)
	)
	(footprint ""
		(layer "F.Cu")
		(at 353.314 -261.6454)
		(property "Reference" "C123"
			(at 0 0 0)
			(layer "F.SilkS")
			(hide yes)
			(effects
				(font
					(size 1.27 1.27)
				)
			)
		)
		(property "Value" "SCD01U50V2KX-1GP"
			(at 1.1811 -2.7051 0)
			(unlocked yes)
			(layer "F.Fab")
			(hide yes)
			(effects
				(font
					(size 1.016 1.016)
					(thickness 0.1524)
				)
			)
		)
		(property "Device Type" "C402H22"
			(at 1.1811 -4.2291 0)
			(unlocked yes)
			(layer "F.Fab")
			(hide yes)
			(effects
				(font
					(size 1.016 1.016)
					(thickness 0.1524)
				)
			)
		)
		(duplicate_pad_numbers_are_jumpers no)
		(fp_rect
			(start -0.4318 0.9525)
			(end 0.4318 -0.9525)
			(stroke
				(width 0)
				(type default)
			)
			(fill no)
			(layer "F.CrtYd")
		)
		(fp_rect
			(start -0.4318 0.9525)
			(end 0.4318 -0.9525)
			(stroke
				(width 0)
				(type default)
			)
			(fill no)
			(layer "F.Fab")
		)
		(pad "1" smd custom
			(at 0 -0.4445)
			(size 0.1524 0.1524)
			(layers "F.Cu" "F.Mask" "F.Paste")
			(net "HDD_PRSNT_7")
			(options
				(clearance outline)
				(anchor circle)
			)
			(primitives
				(gr_poly
					(pts
						(arc
							(start 0.3048 -0.2032)
							(mid 0.275042 -0.275042)
							(end 0.2032 -0.3048)
						)
						(arc
							(start -0.2032 -0.3048)
							(mid -0.275042 -0.275042)
							(end -0.3048 -0.2032)
						)
						(arc
							(start -0.3048 0.2032)
							(mid -0.275042 0.275042)
							(end -0.2032 0.3048)
						)
						(arc
							(start 0.2032 0.3048)
							(mid 0.275042 0.275042)
							(end 0.3048 0.2032)
						)
					)
					(width 0)
					(fill yes)
				)
			)
		)
		(pad "2" smd custom
			(at 0 0.4445)
			(size 0.1524 0.1524)
			(layers "F.Cu" "F.Mask" "F.Paste")
			(net "GND")
			(options
				(clearance outline)
				(anchor circle)
			)
			(primitives
				(gr_poly
					(pts
						(arc
							(start 0.3048 -0.2032)
							(mid 0.275042 -0.275042)
							(end 0.2032 -0.3048)
						)
						(arc
							(start -0.2032 -0.3048)
							(mid -0.275042 -0.275042)
							(end -0.3048 -0.2032)
						)
						(arc
							(start -0.3048 0.2032)
							(mid -0.275042 0.275042)
							(end -0.2032 0.3048)
						)
						(arc
							(start 0.2032 0.3048)
							(mid 0.275042 0.275042)
							(end 0.3048 0.2032)
						)
					)
					(width 0)
					(fill yes)
				)
			)
		)
	)
	(footprint ""
		(layer "F.Cu")
		(at 331.978 -23.368 180)
		(property "Reference" "Q154"
			(at 0 0 180)
			(layer "F.SilkS")
			(hide yes)
			(effects
				(font
					(size 1.27 1.27)
				)
			)
		)
		(property "Value" "AO4406AL-GP"
			(at -3.707384 -1.5367 180)
			(unlocked yes)
			(layer "F.Fab")
			(hide yes)
			(effects
				(font
					(size 1.016 1.016)
					(thickness 0.1524)
				)
			)
		)
		(property "Device Type" "SOIC8H69"
			(at -3.707384 -3.0607 180)
			(unlocked yes)
			(layer "F.Fab")
			(hide yes)
			(effects
				(font
					(size 1.016 1.016)
					(thickness 0.1524)
				)
			)
		)
		(duplicate_pad_numbers_are_jumpers no)
		(fp_line
			(start 2.1336 1.4224)
			(end 2.1336 -1.4224)
			(stroke
				(width 0.1524)
				(type default)
			)
			(layer "F.SilkS")
		)
		(fp_line
			(start 2.1336 -1.4224)
			(end -2.7432 -1.4224)
			(stroke
				(width 0.1524)
				(type default)
			)
			(layer "F.SilkS")
		)
		(fp_line
			(start -2.1844 -0.0508)
			(end -2.7178 0.508)
			(stroke
				(width 0.1524)
				(type default)
			)
			(layer "F.SilkS")
		)
		(fp_line
			(start -2.6289 3.4417)
			(end -2.6289 1.4732)
			(stroke
				(width 0.381)
				(type default)
			)
			(layer "F.SilkS")
		)
		(fp_line
			(start -2.7178 -0.508)
			(end -2.1844 -0.0508)
			(stroke
				(width 0.1524)
				(type default)
			)
			(layer "F.SilkS")
		)
		(fp_line
			(start -2.7432 1.4224)
			(end 2.1336 1.4224)
			(stroke
				(width 0.1524)
				(type default)
			)
			(layer "F.SilkS")
		)
		(fp_line
			(start -2.7432 1.4224)
			(end -2.6416 1.4224)
			(stroke
				(width 0.1524)
				(type default)
			)
			(layer "F.SilkS")
		)
		(fp_line
			(start -2.7432 -1.4224)
			(end -2.7432 1.4224)
			(stroke
				(width 0.1524)
				(type default)
			)
			(layer "F.SilkS")
		)
		(fp_poly
			(pts
				(xy -2.2098 -1.4224) (xy -2.2098 1.4224) (xy 2.2098 1.4224) (xy 2.2098 -1.4224)
			)
			(stroke
				(width 0)
				(type default)
			)
			(fill yes)
			(layer "F.SilkS")
		)
		(fp_rect
			(start -2.450084 2.999994)
			(end 2.450084 -2.999994)
			(stroke
				(width 0)
				(type default)
			)
			(fill no)
			(layer "F.CrtYd")
		)
		(fp_poly
			(pts
				(xy -2.8194 3.6322) (xy -2.8194 -3.6322) (xy 2.8194 -3.6322) (xy 2.8194 1.18364) (xy 2.450084 1.18364)
				(xy 2.450084 -2.999994) (xy -2.450084 -2.999994) (xy -2.450084 2.999994) (xy 2.450084 2.999994)
				(xy 2.450084 1.18618) (xy 2.8194 1.18618) (xy 2.8194 3.6322)
			)
			(stroke
				(width 0)
				(type default)
			)
			(fill no)
			(layer "F.CrtYd")
		)
		(fp_rect
			(start -2.8194 3.6322)
			(end 2.8194 -3.6322)
			(stroke
				(width 0)
				(type default)
			)
			(fill no)
			(layer "F.Fab")
		)
		(pad "1" smd rect
			(at -1.905 2.54 180)
			(size 0.635 1.651)
			(layers "F.Cu" "F.Mask" "F.Paste")
			(net "P5V_HDD30")
		)
		(pad "2" smd rect
			(at -0.635 2.54 180)
			(size 0.635 1.651)
			(layers "F.Cu" "F.Mask" "F.Paste")
			(net "P5V_HDD30")
		)
		(pad "3" smd rect
			(at 0.635 2.54 180)
			(size 0.635 1.651)
			(layers "F.Cu" "F.Mask" "F.Paste")
			(net "P5V_HDD30")
		)
		(pad "4" smd rect
			(at 1.905 2.54 180)
			(size 0.635 1.651)
			(layers "F.Cu" "F.Mask" "F.Paste")
			(net "SW_HDD_P30")
		)
		(pad "5" smd rect
			(at 1.905 -2.54 180)
			(size 0.635 1.651)
			(layers "F.Cu" "F.Mask" "F.Paste")
			(net "P5V_B_4")
		)
		(pad "6" smd rect
			(at 0.635 -2.54 180)
			(size 0.635 1.651)
			(layers "F.Cu" "F.Mask" "F.Paste")
			(net "P5V_B_4")
		)
		(pad "7" smd rect
			(at -0.635 -2.54 180)
			(size 0.635 1.651)
			(layers "F.Cu" "F.Mask" "F.Paste")
			(net "P5V_B_4")
		)
		(pad "8" smd rect
			(at -1.905 -2.54 180)
			(size 0.635 1.651)
			(layers "F.Cu" "F.Mask" "F.Paste")
			(net "P5V_B_4")
		)
	)
	(footprint ""
		(layer "F.Cu")
		(at 425.863004 -364.998 180)
		(property "Reference" "R958"
			(at 0 0 180)
			(layer "F.SilkS")
			(hide yes)
			(effects
				(font
					(size 1.27 1.27)
				)
			)
		)
		(property "Value" "4K7R2F-GP"
			(at 0.064008 -3.993896 180)
			(unlocked yes)
			(layer "F.Fab")
			(hide yes)
			(effects
				(font
					(size 1.016 1.016)
					(thickness 0.1524)
				)
			)
		)
		(property "Device Type" "R402H16"
			(at 0.064008 -5.517896 180)
			(unlocked yes)
			(layer "F.Fab")
			(hide yes)
			(effects
				(font
					(size 1.016 1.016)
					(thickness 0.1524)
				)
			)
		)
		(duplicate_pad_numbers_are_jumpers no)
		(fp_line
			(start 0.508 -0.9398)
			(end -0.508 -0.9398)
			(stroke
				(width 0.1524)
				(type default)
			)
			(layer "F.SilkS")
		)
		(fp_line
			(start -0.508 -0.9398)
			(end -0.508 0.9398)
			(stroke
				(width 0.1524)
				(type default)
			)
			(layer "F.SilkS")
		)
		(fp_rect
			(start -0.508 0.9398)
			(end 0.508 -0.9398)
			(stroke
				(width 0)
				(type default)
			)
			(fill no)
			(layer "F.CrtYd")
		)
		(fp_rect
			(start -0.508 0.9398)
			(end 0.508 -0.9398)
			(stroke
				(width 0)
				(type default)
			)
			(fill no)
			(layer "F.Fab")
		)
		(pad "1" smd custom
			(at 0 -0.4445 180)
			(size 0.1397 0.1397)
			(layers "F.Cu" "F.Mask" "F.Paste")
			(net "P12V_IN")
			(options
				(clearance outline)
				(anchor circle)
			)
			(primitives
				(gr_poly
					(pts
						(arc
							(start -0.1778 -0.2794)
							(mid -0.249642 -0.249642)
							(end -0.2794 -0.1778)
						)
						(arc
							(start -0.2794 0.1778)
							(mid -0.249642 0.249642)
							(end -0.1778 0.2794)
						)
						(arc
							(start 0.1778 0.2794)
							(mid 0.249642 0.249642)
							(end 0.2794 0.1778)
						)
						(arc
							(start 0.2794 -0.1778)
							(mid 0.249642 -0.249642)
							(end 0.1778 -0.2794)
						)
					)
					(width 0)
					(fill yes)
				)
			)
		)
		(pad "2" smd custom
			(at 0 0.4445 180)
			(size 0.1397 0.1397)
			(layers "F.Cu" "F.Mask" "F.Paste")
			(net "FAN_3_TACH1")
			(options
				(clearance outline)
				(anchor circle)
			)
			(primitives
				(gr_poly
					(pts
						(arc
							(start -0.1778 -0.2794)
							(mid -0.249642 -0.249642)
							(end -0.2794 -0.1778)
						)
						(arc
							(start -0.2794 0.1778)
							(mid -0.249642 0.249642)
							(end -0.1778 0.2794)
						)
						(arc
							(start 0.1778 0.2794)
							(mid 0.249642 0.249642)
							(end 0.2794 0.1778)
						)
						(arc
							(start 0.2794 -0.1778)
							(mid 0.249642 -0.249642)
							(end 0.1778 -0.2794)
						)
					)
					(width 0)
					(fill yes)
				)
			)
		)
	)
	(footprint ""
		(layer "F.Cu")
		(at 426.085 -160.02 180)
		(property "Reference" "C307"
			(at 0 0 180)
			(layer "F.SilkS")
			(hide yes)
			(effects
				(font
					(size 1.27 1.27)
				)
			)
		)
		(property "Value" "SC4D7U25V5KX-1-GP"
			(at -0.0762 -6.1214 180)
			(unlocked yes)
			(layer "F.Fab")
			(hide yes)
			(effects
				(font
					(size 1.016 1.016)
					(thickness 0.1524)
				)
			)
		)
		(property "Device Type" "C805H58"
			(at -0.0762 -8.1534 180)
			(unlocked yes)
			(layer "F.Fab")
			(hide yes)
			(effects
				(font
					(size 1.016 1.016)
					(thickness 0.1524)
				)
			)
		)
		(duplicate_pad_numbers_are_jumpers no)
		(fp_line
			(start 0.635 0)
			(end -0.635 0)
			(stroke
				(width 0.508)
				(type default)
			)
			(layer "F.SilkS")
		)
		(fp_rect
			(start -0.9652 1.778)
			(end 0.9652 -1.778)
			(stroke
				(width 0)
				(type default)
			)
			(fill no)
			(layer "F.CrtYd")
		)
		(fp_poly
			(pts
				(xy -0.9652 -1.778) (xy 0.9652 -1.778) (xy 0.9652 1.778) (xy -0.9652 1.778)
			)
			(stroke
				(width 0)
				(type default)
			)
			(fill no)
			(layer "F.Fab")
		)
		(pad "1" smd rect
			(at 0 -0.9652 180)
			(size 1.397 1.143)
			(layers "F.Cu" "F.Mask" "F.Paste")
			(net "P12V_HDD21")
		)
		(pad "2" smd rect
			(at 0 0.9652 180)
			(size 1.397 1.143)
			(layers "F.Cu" "F.Mask" "F.Paste")
			(net "GND")
		)
	)
	(footprint ""
		(layer "F.Cu")
		(at 45.974 -24.384)
		(property "Reference" "Q126"
			(at 0 0 0)
			(layer "F.SilkS")
			(hide yes)
			(effects
				(font
					(size 1.27 1.27)
				)
			)
		)
		(property "Value" "AO4407AL-GP"
			(at -3.707384 -1.5367 0)
			(unlocked yes)
			(layer "F.Fab")
			(hide yes)
			(effects
				(font
					(size 1.016 1.016)
					(thickness 0.1524)
				)
			)
		)
		(property "Device Type" "SOIC8H69"
			(at -3.707384 -3.0607 0)
			(unlocked yes)
			(layer "F.Fab")
			(hide yes)
			(effects
				(font
					(size 1.016 1.016)
					(thickness 0.1524)
				)
			)
		)
		(duplicate_pad_numbers_are_jumpers no)
		(fp_line
			(start -2.7432 -1.4224)
			(end -2.7432 1.4224)
			(stroke
				(width 0.1524)
				(type default)
			)
			(layer "F.SilkS")
		)
		(fp_line
			(start -2.7432 1.4224)
			(end -2.6416 1.4224)
			(stroke
				(width 0.1524)
				(type default)
			)
			(layer "F.SilkS")
		)
		(fp_line
			(start -2.7432 1.4224)
			(end 2.1336 1.4224)
			(stroke
				(width 0.1524)
				(type default)
			)
			(layer "F.SilkS")
		)
		(fp_line
			(start -2.7178 -0.508)
			(end -2.1844 -0.0508)
			(stroke
				(width 0.1524)
				(type default)
			)
			(layer "F.SilkS")
		)
		(fp_line
			(start -2.6289 3.4417)
			(end -2.6289 1.4732)
			(stroke
				(width 0.381)
				(type default)
			)
			(layer "F.SilkS")
		)
		(fp_line
			(start -2.1844 -0.0508)
			(end -2.7178 0.508)
			(stroke
				(width 0.1524)
				(type default)
			)
			(layer "F.SilkS")
		)
		(fp_line
			(start 2.1336 -1.4224)
			(end -2.7432 -1.4224)
			(stroke
				(width 0.1524)
				(type default)
			)
			(layer "F.SilkS")
		)
		(fp_line
			(start 2.1336 1.4224)
			(end 2.1336 -1.4224)
			(stroke
				(width 0.1524)
				(type default)
			)
			(layer "F.SilkS")
		)
		(fp_poly
			(pts
				(xy -2.2098 -1.4224) (xy -2.2098 1.4224) (xy 2.2098 1.4224) (xy 2.2098 -1.4224)
			)
			(stroke
				(width 0)
				(type default)
			)
			(fill yes)
			(layer "F.SilkS")
		)
		(fp_rect
			(start -2.450084 2.999994)
			(end 2.450084 -2.999994)
			(stroke
				(width 0)
				(type default)
			)
			(fill no)
			(layer "F.CrtYd")
		)
		(fp_poly
			(pts
				(xy -2.8194 3.6322) (xy -2.8194 -3.6322) (xy 2.8194 -3.6322) (xy 2.8194 1.18364) (xy 2.450084 1.18364)
				(xy 2.450084 -2.999994) (xy -2.450084 -2.999994) (xy -2.450084 2.999994) (xy 2.450084 2.999994)
				(xy 2.450084 1.18618) (xy 2.8194 1.18618) (xy 2.8194 3.6322)
			)
			(stroke
				(width 0)
				(type default)
			)
			(fill no)
			(layer "F.CrtYd")
		)
		(fp_rect
			(start -2.8194 3.6322)
			(end 2.8194 -3.6322)
			(stroke
				(width 0)
				(type default)
			)
			(fill no)
			(layer "F.Fab")
		)
		(pad "1" smd rect
			(at -1.905 2.54)
			(size 0.635 1.651)
			(layers "F.Cu" "F.Mask" "F.Paste")
			(net "P12V_B")
		)
		(pad "2" smd rect
			(at -0.635 2.54)
			(size 0.635 1.651)
			(layers "F.Cu" "F.Mask" "F.Paste")
			(net "P12V_B")
		)
		(pad "3" smd rect
			(at 0.635 2.54)
			(size 0.635 1.651)
			(layers "F.Cu" "F.Mask" "F.Paste")
			(net "P12V_B")
		)
		(pad "4" smd rect
			(at 1.905 2.54)
			(size 0.635 1.651)
			(layers "F.Cu" "F.Mask" "F.Paste")
			(net "SW_HDD_N25")
		)
		(pad "5" smd rect
			(at 1.905 -2.54)
			(size 0.635 1.651)
			(layers "F.Cu" "F.Mask" "F.Paste")
			(net "P12V_HDD25")
		)
		(pad "6" smd rect
			(at 0.635 -2.54)
			(size 0.635 1.651)
			(layers "F.Cu" "F.Mask" "F.Paste")
			(net "P12V_HDD25")
		)
		(pad "7" smd rect
			(at -0.635 -2.54)
			(size 0.635 1.651)
			(layers "F.Cu" "F.Mask" "F.Paste")
			(net "P12V_HDD25")
		)
		(pad "8" smd rect
			(at -1.905 -2.54)
			(size 0.635 1.651)
			(layers "F.Cu" "F.Mask" "F.Paste")
			(net "P12V_HDD25")
		)
	)
	(footprint ""
		(layer "F.Cu")
		(at 395.478 -266.827 180)
		(property "Reference" "C135"
			(at 0 0 180)
			(layer "F.SilkS")
			(hide yes)
			(effects
				(font
					(size 1.27 1.27)
				)
			)
		)
		(property "Value" "SC10U16V6KX-2GP"
			(at -0.0762 -5.1308 180)
			(unlocked yes)
			(layer "F.Fab")
			(hide yes)
			(effects
				(font
					(size 1.016 1.016)
					(thickness 0.1524)
				)
			)
		)
		(property "Device Type" "C1206H71"
			(at -0.127 -6.6548 180)
			(unlocked yes)
			(layer "F.Fab")
			(hide yes)
			(effects
				(font
					(size 1.016 1.016)
					(thickness 0.1524)
				)
			)
		)
		(duplicate_pad_numbers_are_jumpers no)
		(fp_line
			(start 1.016 2.2352)
			(end -1.016 2.2352)
			(stroke
				(width 0.1524)
				(type default)
			)
			(layer "F.SilkS")
		)
		(fp_line
			(start 1.016 0.8382)
			(end 1.016 2.2352)
			(stroke
				(width 0.1524)
				(type default)
			)
			(layer "F.SilkS")
		)
		(fp_line
			(start 1.016 -2.2352)
			(end 1.016 -0.8382)
			(stroke
				(width 0.1524)
				(type default)
			)
			(layer "F.SilkS")
		)
		(fp_line
			(start -1.016 2.2352)
			(end -1.016 0.8382)
			(stroke
				(width 0.1524)
				(type default)
			)
			(layer "F.SilkS")
		)
		(fp_line
			(start -1.016 -0.8382)
			(end -1.016 -2.2352)
			(stroke
				(width 0.1524)
				(type default)
			)
			(layer "F.SilkS")
		)
		(fp_line
			(start -1.016 -2.2352)
			(end 1.016 -2.2352)
			(stroke
				(width 0.1524)
				(type default)
			)
			(layer "F.SilkS")
		)
		(fp_rect
			(start -1.0922 2.3114)
			(end 1.0922 -2.3114)
			(stroke
				(width 0)
				(type default)
			)
			(fill no)
			(layer "F.CrtYd")
		)
		(fp_poly
			(pts
				(xy 1.0922 -2.3114) (xy 1.0922 2.3114) (xy -1.0922 2.3114) (xy -1.0922 -2.3114)
			)
			(stroke
				(width 0)
				(type default)
			)
			(fill no)
			(layer "F.Fab")
		)
		(pad "1" smd rect
			(at 0 -1.397 180)
			(size 1.651 1.27)
			(layers "F.Cu" "F.Mask" "F.Paste")
			(net "P5V_HDD8")
		)
		(pad "2" smd rect
			(at 0 1.397 180)
			(size 1.651 1.27)
			(layers "F.Cu" "F.Mask" "F.Paste")
			(net "GND")
		)
	)
	(footprint ""
		(layer "F.Cu")
		(at 214.4522 -192.786 -90)
		(property "Reference" "U4"
			(at 0 0 270)
			(layer "F.SilkS")
			(hide yes)
			(effects
				(font
					(size 1.27 1.27)
				)
			)
		)
		(property "Value" "TCA9555PWR-GP"
			(at 0 -6.9342 270)
			(unlocked yes)
			(layer "F.Fab")
			(hide yes)
			(effects
				(font
					(size 1.016 1.016)
					(thickness 0.1524)
				)
			)
		)
		(property "Device Type" "TSOIC24H48"
			(at 0 -8.5852 270)
			(unlocked yes)
			(layer "F.Fab")
			(hide yes)
			(effects
				(font
					(size 1.016 1.016)
					(thickness 0.1524)
				)
			)
		)
		(duplicate_pad_numbers_are_jumpers no)
		(fp_line
			(start -4.2291 3.937)
			(end -4.2291 -1.397)
			(stroke
				(width 0.1524)
				(type default)
			)
			(layer "F.SilkS")
		)
		(fp_line
			(start -4.22656 3.81)
			(end -4.2291 1.397)
			(stroke
				(width 0.508)
				(type default)
			)
			(layer "F.SilkS")
		)
		(fp_line
			(start 3.81 1.397)
			(end -4.2291 1.397)
			(stroke
				(width 0.1524)
				(type default)
			)
			(layer "F.SilkS")
		)
		(fp_line
			(start -3.429 0)
			(end -4.2291 0.8001)
			(stroke
				(width 0.1524)
				(type default)
			)
			(layer "F.SilkS")
		)
		(fp_line
			(start -4.2291 -0.8001)
			(end -3.429 0)
			(stroke
				(width 0.1524)
				(type default)
			)
			(layer "F.SilkS")
		)
		(fp_line
			(start -4.2291 -1.397)
			(end 3.81 -1.397)
			(stroke
				(width 0.1524)
				(type default)
			)
			(layer "F.SilkS")
		)
		(fp_line
			(start 3.81 -1.397)
			(end 3.81 1.397)
			(stroke
				(width 0.1524)
				(type default)
			)
			(layer "F.SilkS")
		)
		(fp_poly
			(pts
				(xy -3.90652 -1.8542) (xy 3.90652 -1.8542) (xy 3.90652 1.8542) (xy -3.90652 1.8542)
			)
			(stroke
				(width 0)
				(type default)
			)
			(fill yes)
			(layer "F.SilkS")
		)
		(fp_poly
			(pts
				(xy -4.2164 3.81) (xy 4.2164 3.81) (xy 4.22656 -3.81) (xy -4.2164 -3.81)
			)
			(stroke
				(width 0)
				(type default)
			)
			(fill no)
			(layer "F.CrtYd")
		)
		(fp_poly
			(pts
				(xy -4.22656 -3.81) (xy 4.22656 -3.81) (xy 4.22656 3.81) (xy -4.22656 3.81)
			)
			(stroke
				(width 0)
				(type default)
			)
			(fill no)
			(layer "F.Fab")
		)
		(pad "1" smd rect
			(at -3.57632 2.8194 270)
			(size 0.3556 1.524)
			(layers "F.Cu" "F.Mask" "F.Paste")
			(net "IO_EXP2_HDD_FAULT_INT_N")
		)
		(pad "2" smd rect
			(at -2.92608 2.8194 270)
			(size 0.3556 1.524)
			(layers "F.Cu" "F.Mask" "F.Paste")
			(net "IO_EXP2_HDD_FAULT_A1")
		)
		(pad "3" smd rect
			(at -2.27584 2.8194 270)
			(size 0.3556 1.524)
			(layers "F.Cu" "F.Mask" "F.Paste")
			(net "IO_EXP2_HDD_FAULT_A2")
		)
		(pad "4" smd rect
			(at -1.6256 2.8194 270)
			(size 0.3556 1.524)
			(layers "F.Cu" "F.Mask" "F.Paste")
			(net "DRIVE_B_16_FLT_LED")
		)
		(pad "5" smd rect
			(at -0.97536 2.8194 270)
			(size 0.3556 1.524)
			(layers "F.Cu" "F.Mask" "F.Paste")
			(net "DRIVE_B_17_FLT_LED")
		)
		(pad "6" smd rect
			(at -0.32512 2.8194 270)
			(size 0.3556 1.524)
			(layers "F.Cu" "F.Mask" "F.Paste")
			(net "DRIVE_B_18_FLT_LED")
		)
		(pad "7" smd rect
			(at 0.32512 2.8194 270)
			(size 0.3556 1.524)
			(layers "F.Cu" "F.Mask" "F.Paste")
			(net "DRIVE_B_19_FLT_LED")
		)
		(pad "8" smd rect
			(at 0.97536 2.8194 270)
			(size 0.3556 1.524)
			(layers "F.Cu" "F.Mask" "F.Paste")
			(net "DRIVE_B_20_FLT_LED")
		)
		(pad "9" smd rect
			(at 1.6256 2.8194 270)
			(size 0.3556 1.524)
			(layers "F.Cu" "F.Mask" "F.Paste")
			(net "DRIVE_B_21_FLT_LED")
		)
		(pad "10" smd rect
			(at 2.27584 2.8194 270)
			(size 0.3556 1.524)
			(layers "F.Cu" "F.Mask" "F.Paste")
			(net "DRIVE_B_22_FLT_LED")
		)
		(pad "11" smd rect
			(at 2.92608 2.8194 270)
			(size 0.3556 1.524)
			(layers "F.Cu" "F.Mask" "F.Paste")
			(net "DRIVE_B_23_FLT_LED")
		)
		(pad "12" smd rect
			(at 3.57632 2.8194 270)
			(size 0.3556 1.524)
			(layers "F.Cu" "F.Mask" "F.Paste")
			(net "GND")
		)
		(pad "13" smd rect
			(at 3.57632 -2.8194 270)
			(size 0.3556 1.524)
			(layers "F.Cu" "F.Mask" "F.Paste")
			(net "RDPB_FAN_LED0")
		)
		(pad "14" smd rect
			(at 2.92608 -2.8194 270)
			(size 0.3556 1.524)
			(layers "F.Cu" "F.Mask" "F.Paste")
			(net "RDPB_FAN_LED1")
		)
		(pad "15" smd rect
			(at 2.27584 -2.8194 270)
			(size 0.3556 1.524)
			(layers "F.Cu" "F.Mask" "F.Paste")
			(net "RDPB_FAN_LED2")
		)
		(pad "16" smd rect
			(at 1.6256 -2.8194 270)
			(size 0.3556 1.524)
			(layers "F.Cu" "F.Mask" "F.Paste")
			(net "RDPB_FAN_LED3")
		)
		(pad "17" smd rect
			(at 0.97536 -2.8194 270)
			(size 0.3556 1.524)
			(layers "F.Cu" "F.Mask" "F.Paste")
			(net "Net_203")
		)
		(pad "18" smd rect
			(at 0.32512 -2.8194 270)
			(size 0.3556 1.524)
			(layers "F.Cu" "F.Mask" "F.Paste")
			(net "Net_204")
		)
		(pad "19" smd rect
			(at -0.32512 -2.8194 270)
			(size 0.3556 1.524)
			(layers "F.Cu" "F.Mask" "F.Paste")
			(net "Net_205")
		)
		(pad "20" smd rect
			(at -0.97536 -2.8194 270)
			(size 0.3556 1.524)
			(layers "F.Cu" "F.Mask" "F.Paste")
			(net "Net_206")
		)
		(pad "21" smd rect
			(at -1.6256 -2.8194 270)
			(size 0.3556 1.524)
			(layers "F.Cu" "F.Mask" "F.Paste")
			(net "IO_EXP2_HDD_FAULT_A0")
		)
		(pad "22" smd rect
			(at -2.27584 -2.8194 270)
			(size 0.3556 1.524)
			(layers "F.Cu" "F.Mask" "F.Paste")
			(net "IO_EXP2_LED_SCL")
		)
		(pad "23" smd rect
			(at -2.92608 -2.8194 270)
			(size 0.3556 1.524)
			(layers "F.Cu" "F.Mask" "F.Paste")
			(net "IO_EXP2_LED_SDA")
		)
		(pad "24" smd rect
			(at -3.57632 -2.8194 270)
			(size 0.3556 1.524)
			(layers "F.Cu" "F.Mask" "F.Paste")
			(net "P3V3_STBY_B")
		)
	)
	(footprint ""
		(layer "F.Cu")
		(at 214.237824 -355.736144 -90)
		(property "Reference" "R1022"
			(at 0 0 270)
			(layer "F.SilkS")
			(hide yes)
			(effects
				(font
					(size 1.27 1.27)
				)
			)
		)
		(property "Value" "0R5J-5-GP"
			(at 0 -8.9535 270)
			(unlocked yes)
			(layer "F.Fab")
			(hide yes)
			(effects
				(font
					(size 1.27 1.016)
					(thickness 0.1524)
				)
			)
		)
		(property "Device Type" "R805H24"
			(at 0 -10.6299 270)
			(unlocked yes)
			(layer "F.Fab")
			(hide yes)
			(effects
				(font
					(size 1.27 1.016)
					(thickness 0.1524)
				)
			)
		)
		(duplicate_pad_numbers_are_jumpers no)
		(fp_line
			(start -0.889 1.7018)
			(end 0.889 1.7018)
			(stroke
				(width 0.1524)
				(type default)
			)
			(layer "F.SilkS")
		)
		(fp_line
			(start 0.889 1.7018)
			(end 0.889 -0.508)
			(stroke
				(width 0.1524)
				(type default)
			)
			(layer "F.SilkS")
		)
		(fp_line
			(start -0.889 0.0762)
			(end -0.889 1.7018)
			(stroke
				(width 0.1524)
				(type default)
			)
			(layer "F.SilkS")
		)
		(fp_line
			(start -0.889 -1.7018)
			(end -0.889 0.2794)
			(stroke
				(width 0.1524)
				(type default)
			)
			(layer "F.SilkS")
		)
		(fp_line
			(start 0.889 -1.7018)
			(end 0.889 -0.381)
			(stroke
				(width 0.1524)
				(type default)
			)
			(layer "F.SilkS")
		)
		(fp_line
			(start 0.889 -1.7018)
			(end -0.889 -1.7018)
			(stroke
				(width 0.1524)
				(type default)
			)
			(layer "F.SilkS")
		)
		(fp_poly
			(pts
				(xy 0.9652 -1.778) (xy 0.9652 1.778) (xy -0.9652 1.778) (xy -0.9652 -1.778)
			)
			(stroke
				(width 0)
				(type default)
			)
			(fill no)
			(layer "F.CrtYd")
		)
		(fp_rect
			(start -0.9652 1.778)
			(end 0.9652 -1.778)
			(stroke
				(width 0)
				(type default)
			)
			(fill no)
			(layer "F.Fab")
		)
		(pad "1" smd rect
			(at 0 -0.9652 270)
			(size 1.397 1.143)
			(layers "F.Cu" "F.Mask" "F.Paste")
			(net "MB0_CM_GATE")
		)
		(pad "2" smd rect
			(at 0 0.9652 270)
			(size 1.397 1.143)
			(layers "F.Cu" "F.Mask" "F.Paste")
			(net "MB0_CM_GATE_R")
		)
	)
	(footprint ""
		(layer "F.Cu")
		(at 320.7004 -31.6484 180)
		(property "Reference" "R760"
			(at 0 0 180)
			(layer "F.SilkS")
			(hide yes)
			(effects
				(font
					(size 1.27 1.27)
				)
			)
		)
		(property "Value" "10KR2F-2-GP"
			(at 0.064008 -3.993896 180)
			(unlocked yes)
			(layer "F.Fab")
			(hide yes)
			(effects
				(font
					(size 1.016 1.016)
					(thickness 0.1524)
				)
			)
		)
		(property "Device Type" "R402H16"
			(at 0.064008 -5.517896 180)
			(unlocked yes)
			(layer "F.Fab")
			(hide yes)
			(effects
				(font
					(size 1.016 1.016)
					(thickness 0.1524)
				)
			)
		)
		(duplicate_pad_numbers_are_jumpers no)
		(fp_line
			(start 0.508 -0.9398)
			(end -0.508 -0.9398)
			(stroke
				(width 0.1524)
				(type default)
			)
			(layer "F.SilkS")
		)
		(fp_line
			(start -0.508 -0.9398)
			(end -0.508 0.9398)
			(stroke
				(width 0.1524)
				(type default)
			)
			(layer "F.SilkS")
		)
		(fp_rect
			(start -0.508 0.9398)
			(end 0.508 -0.9398)
			(stroke
				(width 0)
				(type default)
			)
			(fill no)
			(layer "F.CrtYd")
		)
		(fp_rect
			(start -0.508 0.9398)
			(end 0.508 -0.9398)
			(stroke
				(width 0)
				(type default)
			)
			(fill no)
			(layer "F.Fab")
		)
		(pad "1" smd custom
			(at 0 -0.4445 180)
			(size 0.1397 0.1397)
			(layers "F.Cu" "F.Mask" "F.Paste")
			(net "P3V3_STBY_B")
			(options
				(clearance outline)
				(anchor circle)
			)
			(primitives
				(gr_poly
					(pts
						(arc
							(start -0.1778 -0.2794)
							(mid -0.249642 -0.249642)
							(end -0.2794 -0.1778)
						)
						(arc
							(start -0.2794 0.1778)
							(mid -0.249642 0.249642)
							(end -0.1778 0.2794)
						)
						(arc
							(start 0.1778 0.2794)
							(mid 0.249642 0.249642)
							(end 0.2794 0.1778)
						)
						(arc
							(start 0.2794 -0.1778)
							(mid 0.249642 -0.249642)
							(end 0.1778 -0.2794)
						)
					)
					(width 0)
					(fill yes)
				)
			)
		)
		(pad "2" smd custom
			(at 0 0.4445 180)
			(size 0.1397 0.1397)
			(layers "F.Cu" "F.Mask" "F.Paste")
			(net "HDD_PRSNT_30")
			(options
				(clearance outline)
				(anchor circle)
			)
			(primitives
				(gr_poly
					(pts
						(arc
							(start -0.1778 -0.2794)
							(mid -0.249642 -0.249642)
							(end -0.2794 -0.1778)
						)
						(arc
							(start -0.2794 0.1778)
							(mid -0.249642 0.249642)
							(end -0.1778 0.2794)
						)
						(arc
							(start 0.1778 0.2794)
							(mid 0.249642 0.249642)
							(end 0.2794 0.1778)
						)
						(arc
							(start 0.2794 -0.1778)
							(mid 0.249642 -0.249642)
							(end 0.1778 -0.2794)
						)
					)
					(width 0)
					(fill yes)
				)
			)
		)
	)
	(footprint ""
		(layer "F.Cu")
		(at 50.038 -20.955 90)
		(property "Reference" "C363"
			(at 0 0 90)
			(layer "F.SilkS")
			(hide yes)
			(effects
				(font
					(size 1.27 1.27)
				)
			)
		)
		(property "Value" "SCD033U25V2KX-GP"
			(at 1.1811 -2.7051 90)
			(unlocked yes)
			(layer "F.Fab")
			(hide yes)
			(effects
				(font
					(size 1.016 1.016)
					(thickness 0.1524)
				)
			)
		)
		(property "Device Type" "C402H22"
			(at 1.1811 -4.2291 90)
			(unlocked yes)
			(layer "F.Fab")
			(hide yes)
			(effects
				(font
					(size 1.016 1.016)
					(thickness 0.1524)
				)
			)
		)
		(duplicate_pad_numbers_are_jumpers no)
		(fp_rect
			(start -0.4318 0.9525)
			(end 0.4318 -0.9525)
			(stroke
				(width 0)
				(type default)
			)
			(fill no)
			(layer "F.CrtYd")
		)
		(fp_rect
			(start -0.4318 0.9525)
			(end 0.4318 -0.9525)
			(stroke
				(width 0)
				(type default)
			)
			(fill no)
			(layer "F.Fab")
		)
		(pad "1" smd custom
			(at 0 -0.4445 90)
			(size 0.1524 0.1524)
			(layers "F.Cu" "F.Mask" "F.Paste")
			(net "SW_HDD_P25")
			(options
				(clearance outline)
				(anchor circle)
			)
			(primitives
				(gr_poly
					(pts
						(arc
							(start 0.3048 -0.2032)
							(mid 0.275042 -0.275042)
							(end 0.2032 -0.3048)
						)
						(arc
							(start -0.2032 -0.3048)
							(mid -0.275042 -0.275042)
							(end -0.3048 -0.2032)
						)
						(arc
							(start -0.3048 0.2032)
							(mid -0.275042 0.275042)
							(end -0.2032 0.3048)
						)
						(arc
							(start 0.2032 0.3048)
							(mid 0.275042 0.275042)
							(end 0.3048 0.2032)
						)
					)
					(width 0)
					(fill yes)
				)
			)
		)
		(pad "2" smd custom
			(at 0 0.4445 90)
			(size 0.1524 0.1524)
			(layers "F.Cu" "F.Mask" "F.Paste")
			(net "GND")
			(options
				(clearance outline)
				(anchor circle)
			)
			(primitives
				(gr_poly
					(pts
						(arc
							(start 0.3048 -0.2032)
							(mid 0.275042 -0.275042)
							(end 0.2032 -0.3048)
						)
						(arc
							(start -0.2032 -0.3048)
							(mid -0.275042 -0.275042)
							(end -0.3048 -0.2032)
						)
						(arc
							(start -0.3048 0.2032)
							(mid -0.275042 0.275042)
							(end -0.2032 0.3048)
						)
						(arc
							(start 0.2032 0.3048)
							(mid 0.275042 0.275042)
							(end 0.3048 0.2032)
						)
					)
					(width 0)
					(fill yes)
				)
			)
		)
	)
	(footprint ""
		(layer "F.Cu")
		(at 95.608902 -18.750026 -90)
		(property "Reference" "VIA54"
			(at 0 0 270)
			(layer "F.SilkS")
			(hide yes)
			(effects
				(font
					(size 1.27 1.27)
				)
			)
		)
		(property "Value" "100OHM-8L-2D36MM-L16-GP"
			(at -3.4036 -0.4572 270)
			(unlocked yes)
			(layer "F.Fab")
			(hide yes)
			(effects
				(font
					(size 1.016 1.016)
					(thickness 0.1524)
				)
			)
		)
		(property "Device Type" "VIA-PCIE-4P-427097"
			(at -3.4036 -1.9812 270)
			(unlocked yes)
			(layer "F.Fab")
			(hide yes)
			(effects
				(font
					(size 1.016 1.016)
					(thickness 0.1524)
				)
			)
		)
		(duplicate_pad_numbers_are_jumpers no)
		(fp_rect
			(start -2.1336 0.4826)
			(end 2.1336 -0.4826)
			(stroke
				(width 0)
				(type default)
			)
			(fill no)
			(layer "F.CrtYd")
		)
		(fp_rect
			(start -2.1336 0.4826)
			(end 2.1336 -0.4826)
			(stroke
				(width 0)
				(type default)
			)
			(fill no)
			(layer "F.Fab")
		)
		(pad "1" thru_hole circle
			(at -1.651 0 270)
			(size 0.508 0.508)
			(drill 0.254)
			(layers "*.Cu" "*.Mask")
			(remove_unused_layers no)
			(net "GND")
			(clearance 0.2286)
			(thermal_gap 0.2286)
		)
		(pad "2" thru_hole circle
			(at -0.635 0 270)
			(size 0.508 0.508)
			(drill 0.254)
			(layers "*.Cu" "*.Mask")
			(remove_unused_layers no)
			(net "PHY_DRV_B_TO_SCC_B_26_DP")
			(clearance 0.2286)
			(thermal_gap 0.2286)
		)
		(pad "3" thru_hole circle
			(at 0.635 0 270)
			(size 0.508 0.508)
			(drill 0.254)
			(layers "*.Cu" "*.Mask")
			(remove_unused_layers no)
			(net "PHY_DRV_B_TO_SCC_B_26_DN")
			(clearance 0.2286)
			(thermal_gap 0.2286)
		)
		(pad "4" thru_hole circle
			(at 1.651 0 270)
			(size 0.508 0.508)
			(drill 0.254)
			(layers "*.Cu" "*.Mask")
			(remove_unused_layers no)
			(net "GND")
			(clearance 0.2286)
			(thermal_gap 0.2286)
		)
	)
	(footprint ""
		(layer "F.Cu")
		(at 350.766126 -269.705074)
		(property "Reference" "TP56"
			(at 0 0 0)
			(layer "F.SilkS")
			(hide yes)
			(effects
				(font
					(size 1.27 1.27)
				)
			)
		)
		(property "Value" "*"
			(at -0.0508 -1.6764 0)
			(unlocked yes)
			(layer "F.Fab")
			(hide yes)
			(effects
				(font
					(size 1.016 1.016)
					(thickness 0.1524)
				)
			)
		)
		(property "Device Type" "TPAD32"
			(at -0.0508 -3.2004 0)
			(unlocked yes)
			(layer "F.Fab")
			(hide yes)
			(effects
				(font
					(size 1.016 1.016)
					(thickness 0.1524)
				)
			)
		)
		(duplicate_pad_numbers_are_jumpers no)
		(fp_poly
			(pts
				(arc
					(start 0.4064 0)
					(mid -0.4064 0)
					(end 0.4064 0)
				)
			)
			(stroke
				(width 0)
				(type default)
			)
			(fill no)
			(layer "F.CrtYd")
		)
		(fp_poly
			(pts
				(arc
					(start 0.7112 0)
					(mid -0.7112 0)
					(end 0.7112 0)
				)
			)
			(stroke
				(width 0)
				(type default)
			)
			(fill no)
			(layer "F.Fab")
		)
		(pad "1" smd circle
			(at 0 0)
			(size 0.8128 0.8128)
			(layers "F.Cu" "F.Mask" "F.Paste")
			(net "ACT_HDD_7")
		)
	)
	(footprint ""
		(layer "F.Cu")
		(at 368.808 -248.793 90)
		(property "Reference" "D7"
			(at 0 0 90)
			(layer "F.SilkS")
			(hide yes)
			(effects
				(font
					(size 1.27 1.27)
				)
			)
		)
		(property "Value" "RB551V30-GP"
			(at 0 -6.7818 90)
			(unlocked yes)
			(layer "F.Fab")
			(hide yes)
			(effects
				(font
					(size 1.016 1.016)
					(thickness 0.1524)
				)
			)
		)
		(property "Device Type" "SOD323AKH38"
			(at 0 -8.6868 90)
			(unlocked yes)
			(layer "F.Fab")
			(hide yes)
			(effects
				(font
					(size 1.016 1.016)
					(thickness 0.1524)
				)
			)
		)
		(duplicate_pad_numbers_are_jumpers no)
		(fp_line
			(start 0.889 -1.9304)
			(end 0.889 2.159)
			(stroke
				(width 0.1524)
				(type default)
			)
			(layer "F.SilkS")
		)
		(fp_line
			(start -0.889 -1.9304)
			(end 0.889 -1.9304)
			(stroke
				(width 0.1524)
				(type default)
			)
			(layer "F.SilkS")
		)
		(fp_line
			(start 0.762 2.0574)
			(end -0.762 2.0574)
			(stroke
				(width 0.508)
				(type default)
			)
			(layer "F.SilkS")
		)
		(fp_line
			(start 0.889 2.159)
			(end -0.889 2.159)
			(stroke
				(width 0.1524)
				(type default)
			)
			(layer "F.SilkS")
		)
		(fp_line
			(start -0.889 2.159)
			(end -0.889 -1.9304)
			(stroke
				(width 0.1524)
				(type default)
			)
			(layer "F.SilkS")
		)
		(fp_rect
			(start -1.016 2.3114)
			(end 1.016 -2.0066)
			(stroke
				(width 0)
				(type default)
			)
			(fill no)
			(layer "F.CrtYd")
		)
		(fp_poly
			(pts
				(xy -1.016 -2.0066) (xy 1.016 -2.0066) (xy 1.016 2.3114) (xy -1.016 2.3114)
			)
			(stroke
				(width 0)
				(type default)
			)
			(fill no)
			(layer "F.Fab")
		)
		(pad "A" smd rect
			(at 0 -1.143 90)
			(size 0.5588 1.016)
			(layers "F.Cu" "F.Mask" "F.Paste")
			(net "SW_HDD_R7")
		)
		(pad "K" smd rect
			(at 0 1.143 90)
			(size 0.5588 1.016)
			(layers "F.Cu" "F.Mask" "F.Paste")
			(net "SW_HDD_N7")
		)
	)
	(footprint ""
		(layer "F.Cu")
		(at 81.534 -16.637)
		(property "Reference" "R685"
			(at 0 0 0)
			(layer "F.SilkS")
			(hide yes)
			(effects
				(font
					(size 1.27 1.27)
				)
			)
		)
		(property "Value" "0R2J-2-GP"
			(at 0.064008 -3.993896 0)
			(unlocked yes)
			(layer "F.Fab")
			(hide yes)
			(effects
				(font
					(size 1.016 1.016)
					(thickness 0.1524)
				)
			)
		)
		(property "Device Type" "R402H16"
			(at 0.064008 -5.517896 0)
			(unlocked yes)
			(layer "F.Fab")
			(hide yes)
			(effects
				(font
					(size 1.016 1.016)
					(thickness 0.1524)
				)
			)
		)
		(duplicate_pad_numbers_are_jumpers no)
		(fp_line
			(start -0.508 -0.9398)
			(end -0.508 0.9398)
			(stroke
				(width 0.1524)
				(type default)
			)
			(layer "F.SilkS")
		)
		(fp_line
			(start 0.508 -0.9398)
			(end -0.508 -0.9398)
			(stroke
				(width 0.1524)
				(type default)
			)
			(layer "F.SilkS")
		)
		(fp_rect
			(start -0.508 0.9398)
			(end 0.508 -0.9398)
			(stroke
				(width 0)
				(type default)
			)
			(fill no)
			(layer "F.CrtYd")
		)
		(fp_rect
			(start -0.508 0.9398)
			(end 0.508 -0.9398)
			(stroke
				(width 0)
				(type default)
			)
			(fill no)
			(layer "F.Fab")
		)
		(pad "1" smd custom
			(at 0 -0.4445)
			(size 0.1397 0.1397)
			(layers "F.Cu" "F.Mask" "F.Paste")
			(net "SW_HDD_G26")
			(options
				(clearance outline)
				(anchor circle)
			)
			(primitives
				(gr_poly
					(pts
						(arc
							(start -0.1778 -0.2794)
							(mid -0.249642 -0.249642)
							(end -0.2794 -0.1778)
						)
						(arc
							(start -0.2794 0.1778)
							(mid -0.249642 0.249642)
							(end -0.1778 0.2794)
						)
						(arc
							(start 0.1778 0.2794)
							(mid 0.249642 0.249642)
							(end 0.2794 0.1778)
						)
						(arc
							(start 0.2794 -0.1778)
							(mid 0.249642 -0.249642)
							(end 0.1778 -0.2794)
						)
					)
					(width 0)
					(fill yes)
				)
			)
		)
		(pad "2" smd custom
			(at 0 0.4445)
			(size 0.1397 0.1397)
			(layers "F.Cu" "F.Mask" "F.Paste")
			(net "SW_HDD_R26")
			(options
				(clearance outline)
				(anchor circle)
			)
			(primitives
				(gr_poly
					(pts
						(arc
							(start -0.1778 -0.2794)
							(mid -0.249642 -0.249642)
							(end -0.2794 -0.1778)
						)
						(arc
							(start -0.2794 0.1778)
							(mid -0.249642 0.249642)
							(end -0.1778 0.2794)
						)
						(arc
							(start 0.1778 0.2794)
							(mid 0.249642 0.249642)
							(end 0.2794 0.1778)
						)
						(arc
							(start 0.2794 -0.1778)
							(mid 0.249642 -0.249642)
							(end 0.1778 -0.2794)
						)
					)
					(width 0)
					(fill yes)
				)
			)
		)
	)
	(footprint ""
		(layer "F.Cu")
		(at 54.1528 -99.314)
		(property "Reference" "R390"
			(at 0 0 0)
			(layer "F.SilkS")
			(hide yes)
			(effects
				(font
					(size 1.27 1.27)
				)
			)
		)
		(property "Value" "130R3F-GP"
			(at -0.0254 -2.5146 0)
			(unlocked yes)
			(layer "F.Fab")
			(hide yes)
			(effects
				(font
					(size 1.016 1.016)
					(thickness 0.1524)
				)
			)
		)
		(property "Device Type" "R603H22"
			(at -0.0254 -4.0386 0)
			(unlocked yes)
			(layer "F.Fab")
			(hide yes)
			(effects
				(font
					(size 1.016 1.016)
					(thickness 0.1524)
				)
			)
		)
		(duplicate_pad_numbers_are_jumpers no)
		(fp_line
			(start -0.4826 0)
			(end -0.2032 0)
			(stroke
				(width 0.2032)
				(type default)
			)
			(layer "F.SilkS")
		)
		(fp_line
			(start 0.2032 0)
			(end 0.4826 0)
			(stroke
				(width 0.2032)
				(type default)
			)
			(layer "F.SilkS")
		)
		(fp_rect
			(start -0.5842 1.3335)
			(end 0.5842 -1.3335)
			(stroke
				(width 0)
				(type default)
			)
			(fill no)
			(layer "F.CrtYd")
		)
		(fp_rect
			(start -0.5842 1.3335)
			(end 0.5842 -1.3335)
			(stroke
				(width 0)
				(type default)
			)
			(fill no)
			(layer "F.Fab")
		)
		(pad "1" smd custom
			(at 0 -0.762)
			(size 0.2159 0.2159)
			(layers "F.Cu" "F.Mask" "F.Paste")
			(net "P5V_B_1")
			(options
				(clearance outline)
				(anchor circle)
			)
			(primitives
				(gr_poly
					(pts
						(arc
							(start -0.3302 -0.4318)
							(mid -0.402042 -0.402042)
							(end -0.4318 -0.3302)
						)
						(arc
							(start -0.4318 0.3302)
							(mid -0.402042 0.402042)
							(end -0.3302 0.4318)
						)
						(arc
							(start 0.3302 0.4318)
							(mid 0.402042 0.402042)
							(end 0.4318 0.3302)
						)
						(arc
							(start 0.4318 -0.3302)
							(mid 0.402042 -0.402042)
							(end 0.3302 -0.4318)
						)
					)
					(width 0)
					(fill yes)
				)
			)
		)
		(pad "2" smd custom
			(at 0 0.762)
			(size 0.2159 0.2159)
			(layers "F.Cu" "F.Mask" "F.Paste")
			(net "FLT_HDD13")
			(options
				(clearance outline)
				(anchor circle)
			)
			(primitives
				(gr_poly
					(pts
						(arc
							(start -0.3302 -0.4318)
							(mid -0.402042 -0.402042)
							(end -0.4318 -0.3302)
						)
						(arc
							(start -0.4318 0.3302)
							(mid -0.402042 0.402042)
							(end -0.3302 0.4318)
						)
						(arc
							(start 0.3302 0.4318)
							(mid 0.402042 0.402042)
							(end 0.4318 0.3302)
						)
						(arc
							(start 0.4318 -0.3302)
							(mid 0.402042 -0.402042)
							(end 0.3302 -0.4318)
						)
					)
					(width 0)
					(fill yes)
				)
			)
		)
	)
	(footprint ""
		(layer "F.Cu")
		(at 455.93 -45.339 180)
		(property "Reference" "C479"
			(at 0 0 180)
			(layer "F.SilkS")
			(hide yes)
			(effects
				(font
					(size 1.27 1.27)
				)
			)
		)
		(property "Value" "SC1U25V3KX-GP"
			(at 0 -2.8194 180)
			(unlocked yes)
			(layer "F.Fab")
			(hide yes)
			(effects
				(font
					(size 1.016 1.016)
					(thickness 0.1524)
				)
			)
		)
		(property "Device Type" "C603H36"
			(at 0 -4.3434 180)
			(unlocked yes)
			(layer "F.Fab")
			(hide yes)
			(effects
				(font
					(size 1.016 1.016)
					(thickness 0.1524)
				)
			)
		)
		(duplicate_pad_numbers_are_jumpers no)
		(fp_line
			(start 0.508 0)
			(end -0.508 0)
			(stroke
				(width 0.2032)
				(type default)
			)
			(layer "F.SilkS")
		)
		(fp_rect
			(start -0.5842 1.3335)
			(end 0.5842 -1.3335)
			(stroke
				(width 0)
				(type default)
			)
			(fill no)
			(layer "F.CrtYd")
		)
		(fp_rect
			(start -0.5842 1.3335)
			(end 0.5842 -1.3335)
			(stroke
				(width 0)
				(type default)
			)
			(fill no)
			(layer "F.Fab")
		)
		(pad "1" smd custom
			(at 0 -0.762 180)
			(size 0.2159 0.2159)
			(layers "F.Cu" "F.Mask" "F.Paste")
			(net "P12V_HDD34")
			(options
				(clearance outline)
				(anchor circle)
			)
			(primitives
				(gr_poly
					(pts
						(arc
							(start -0.3302 -0.4318)
							(mid -0.402042 -0.402042)
							(end -0.4318 -0.3302)
						)
						(arc
							(start -0.4318 0.3302)
							(mid -0.402042 0.402042)
							(end -0.3302 0.4318)
						)
						(arc
							(start 0.3302 0.4318)
							(mid 0.402042 0.402042)
							(end 0.4318 0.3302)
						)
						(arc
							(start 0.4318 -0.3302)
							(mid 0.402042 -0.402042)
							(end 0.3302 -0.4318)
						)
					)
					(width 0)
					(fill yes)
				)
			)
		)
		(pad "2" smd custom
			(at 0 0.762 180)
			(size 0.2159 0.2159)
			(layers "F.Cu" "F.Mask" "F.Paste")
			(net "GND")
			(options
				(clearance outline)
				(anchor circle)
			)
			(primitives
				(gr_poly
					(pts
						(arc
							(start -0.3302 -0.4318)
							(mid -0.402042 -0.402042)
							(end -0.4318 -0.3302)
						)
						(arc
							(start -0.4318 0.3302)
							(mid -0.402042 0.402042)
							(end -0.3302 0.4318)
						)
						(arc
							(start 0.3302 0.4318)
							(mid 0.402042 0.402042)
							(end 0.4318 0.3302)
						)
						(arc
							(start 0.4318 -0.3302)
							(mid 0.402042 -0.402042)
							(end 0.3302 -0.4318)
						)
					)
					(width 0)
					(fill yes)
				)
			)
		)
	)
	(footprint ""
		(layer "F.Cu")
		(at 172.593 -139.446 -90)
		(property "Reference" "R476"
			(at 0 0 270)
			(layer "F.SilkS")
			(hide yes)
			(effects
				(font
					(size 1.27 1.27)
				)
			)
		)
		(property "Value" "300KR2F-GP"
			(at 0.064008 -3.993896 270)
			(unlocked yes)
			(layer "F.Fab")
			(hide yes)
			(effects
				(font
					(size 1.016 1.016)
					(thickness 0.1524)
				)
			)
		)
		(property "Device Type" "R402H16"
			(at 0.064008 -5.517896 270)
			(unlocked yes)
			(layer "F.Fab")
			(hide yes)
			(effects
				(font
					(size 1.016 1.016)
					(thickness 0.1524)
				)
			)
		)
		(duplicate_pad_numbers_are_jumpers no)
		(fp_line
			(start -0.508 -0.9398)
			(end -0.508 0.9398)
			(stroke
				(width 0.1524)
				(type default)
			)
			(layer "F.SilkS")
		)
		(fp_line
			(start 0.508 -0.9398)
			(end -0.508 -0.9398)
			(stroke
				(width 0.1524)
				(type default)
			)
			(layer "F.SilkS")
		)
		(fp_rect
			(start -0.508 0.9398)
			(end 0.508 -0.9398)
			(stroke
				(width 0)
				(type default)
			)
			(fill no)
			(layer "F.CrtYd")
		)
		(fp_rect
			(start -0.508 0.9398)
			(end 0.508 -0.9398)
			(stroke
				(width 0)
				(type default)
			)
			(fill no)
			(layer "F.Fab")
		)
		(pad "1" smd custom
			(at 0 -0.4445 270)
			(size 0.1397 0.1397)
			(layers "F.Cu" "F.Mask" "F.Paste")
			(net "SW_HDD_N17")
			(options
				(clearance outline)
				(anchor circle)
			)
			(primitives
				(gr_poly
					(pts
						(arc
							(start -0.1778 -0.2794)
							(mid -0.249642 -0.249642)
							(end -0.2794 -0.1778)
						)
						(arc
							(start -0.2794 0.1778)
							(mid -0.249642 0.249642)
							(end -0.1778 0.2794)
						)
						(arc
							(start 0.1778 0.2794)
							(mid 0.249642 0.249642)
							(end 0.2794 0.1778)
						)
						(arc
							(start 0.2794 -0.1778)
							(mid 0.249642 -0.249642)
							(end 0.1778 -0.2794)
						)
					)
					(width 0)
					(fill yes)
				)
			)
		)
		(pad "2" smd custom
			(at 0 0.4445 270)
			(size 0.1397 0.1397)
			(layers "F.Cu" "F.Mask" "F.Paste")
			(net "P12V_B")
			(options
				(clearance outline)
				(anchor circle)
			)
			(primitives
				(gr_poly
					(pts
						(arc
							(start -0.1778 -0.2794)
							(mid -0.249642 -0.249642)
							(end -0.2794 -0.1778)
						)
						(arc
							(start -0.2794 0.1778)
							(mid -0.249642 0.249642)
							(end -0.1778 0.2794)
						)
						(arc
							(start 0.1778 0.2794)
							(mid 0.249642 0.249642)
							(end 0.2794 0.1778)
						)
						(arc
							(start 0.2794 -0.1778)
							(mid 0.249642 -0.249642)
							(end 0.1778 -0.2794)
						)
					)
					(width 0)
					(fill yes)
				)
			)
		)
	)
	(footprint ""
		(layer "F.Cu")
		(at 246.155972 -135.665718 -90)
		(property "Reference" "C37"
			(at 0 0 270)
			(layer "F.SilkS")
			(hide yes)
			(effects
				(font
					(size 1.27 1.27)
				)
			)
		)
		(property "Value" "SC1U16V3KX-5GP"
			(at 0 -2.8194 270)
			(unlocked yes)
			(layer "F.Fab")
			(hide yes)
			(effects
				(font
					(size 1.016 1.016)
					(thickness 0.1524)
				)
			)
		)
		(property "Device Type" "C603H36"
			(at 0 -4.3434 270)
			(unlocked yes)
			(layer "F.Fab")
			(hide yes)
			(effects
				(font
					(size 1.016 1.016)
					(thickness 0.1524)
				)
			)
		)
		(duplicate_pad_numbers_are_jumpers no)
		(fp_line
			(start 0.508 0)
			(end -0.508 0)
			(stroke
				(width 0.2032)
				(type default)
			)
			(layer "F.SilkS")
		)
		(fp_rect
			(start -0.5842 1.3335)
			(end 0.5842 -1.3335)
			(stroke
				(width 0)
				(type default)
			)
			(fill no)
			(layer "F.CrtYd")
		)
		(fp_rect
			(start -0.5842 1.3335)
			(end 0.5842 -1.3335)
			(stroke
				(width 0)
				(type default)
			)
			(fill no)
			(layer "F.Fab")
		)
		(pad "1" smd custom
			(at 0 -0.762 270)
			(size 0.2159 0.2159)
			(layers "F.Cu" "F.Mask" "F.Paste")
			(net "P3V3_STBY_B")
			(options
				(clearance outline)
				(anchor circle)
			)
			(primitives
				(gr_poly
					(pts
						(arc
							(start -0.3302 -0.4318)
							(mid -0.402042 -0.402042)
							(end -0.4318 -0.3302)
						)
						(arc
							(start -0.4318 0.3302)
							(mid -0.402042 0.402042)
							(end -0.3302 0.4318)
						)
						(arc
							(start 0.3302 0.4318)
							(mid 0.402042 0.402042)
							(end 0.4318 0.3302)
						)
						(arc
							(start 0.4318 -0.3302)
							(mid 0.402042 -0.402042)
							(end 0.3302 -0.4318)
						)
					)
					(width 0)
					(fill yes)
				)
			)
		)
		(pad "2" smd custom
			(at 0 0.762 270)
			(size 0.2159 0.2159)
			(layers "F.Cu" "F.Mask" "F.Paste")
			(net "GND")
			(options
				(clearance outline)
				(anchor circle)
			)
			(primitives
				(gr_poly
					(pts
						(arc
							(start -0.3302 -0.4318)
							(mid -0.402042 -0.402042)
							(end -0.4318 -0.3302)
						)
						(arc
							(start -0.4318 0.3302)
							(mid -0.402042 0.402042)
							(end -0.3302 0.4318)
						)
						(arc
							(start 0.3302 0.4318)
							(mid 0.402042 0.402042)
							(end 0.4318 0.3302)
						)
						(arc
							(start 0.4318 -0.3302)
							(mid 0.402042 -0.402042)
							(end 0.3302 -0.4318)
						)
					)
					(width 0)
					(fill yes)
				)
			)
		)
	)
	(footprint ""
		(layer "F.Cu")
		(at 191.135 -267.081 180)
		(property "Reference" "R241"
			(at 0 0 180)
			(layer "F.SilkS")
			(hide yes)
			(effects
				(font
					(size 1.27 1.27)
				)
			)
		)
		(property "Value" "220R3F-1-GP"
			(at -0.0254 -2.5146 180)
			(unlocked yes)
			(layer "F.Fab")
			(hide yes)
			(effects
				(font
					(size 1.016 1.016)
					(thickness 0.1524)
				)
			)
		)
		(property "Device Type" "R603H22"
			(at -0.0254 -4.0386 180)
			(unlocked yes)
			(layer "F.Fab")
			(hide yes)
			(effects
				(font
					(size 1.016 1.016)
					(thickness 0.1524)
				)
			)
		)
		(duplicate_pad_numbers_are_jumpers no)
		(fp_line
			(start 0.2032 0)
			(end 0.4826 0)
			(stroke
				(width 0.2032)
				(type default)
			)
			(layer "F.SilkS")
		)
		(fp_line
			(start -0.4826 0)
			(end -0.2032 0)
			(stroke
				(width 0.2032)
				(type default)
			)
			(layer "F.SilkS")
		)
		(fp_rect
			(start -0.5842 1.3335)
			(end 0.5842 -1.3335)
			(stroke
				(width 0)
				(type default)
			)
			(fill no)
			(layer "F.CrtYd")
		)
		(fp_rect
			(start -0.5842 1.3335)
			(end 0.5842 -1.3335)
			(stroke
				(width 0)
				(type default)
			)
			(fill no)
			(layer "F.Fab")
		)
		(pad "1" smd custom
			(at 0 -0.762 180)
			(size 0.2159 0.2159)
			(layers "F.Cu" "F.Mask" "F.Paste")
			(net "HDD_PRSNT_5")
			(options
				(clearance outline)
				(anchor circle)
			)
			(primitives
				(gr_poly
					(pts
						(arc
							(start -0.3302 -0.4318)
							(mid -0.402042 -0.402042)
							(end -0.4318 -0.3302)
						)
						(arc
							(start -0.4318 0.3302)
							(mid -0.402042 0.402042)
							(end -0.3302 0.4318)
						)
						(arc
							(start 0.3302 0.4318)
							(mid 0.402042 0.402042)
							(end 0.4318 0.3302)
						)
						(arc
							(start 0.4318 -0.3302)
							(mid 0.402042 -0.402042)
							(end 0.3302 -0.4318)
						)
					)
					(width 0)
					(fill yes)
				)
			)
		)
		(pad "2" smd custom
			(at 0 0.762 180)
			(size 0.2159 0.2159)
			(layers "F.Cu" "F.Mask" "F.Paste")
			(net "DRIVE_B_5_INS")
			(options
				(clearance outline)
				(anchor circle)
			)
			(primitives
				(gr_poly
					(pts
						(arc
							(start -0.3302 -0.4318)
							(mid -0.402042 -0.402042)
							(end -0.4318 -0.3302)
						)
						(arc
							(start -0.4318 0.3302)
							(mid -0.402042 0.402042)
							(end -0.3302 0.4318)
						)
						(arc
							(start 0.3302 0.4318)
							(mid 0.402042 0.402042)
							(end 0.4318 0.3302)
						)
						(arc
							(start 0.4318 -0.3302)
							(mid 0.402042 -0.402042)
							(end 0.3302 -0.4318)
						)
					)
					(width 0)
					(fill yes)
				)
			)
		)
	)
	(footprint ""
		(layer "F.Cu")
		(at 80.137 -99.314)
		(property "Reference" "R402"
			(at 0 0 0)
			(layer "F.SilkS")
			(hide yes)
			(effects
				(font
					(size 1.27 1.27)
				)
			)
		)
		(property "Value" "130R3F-GP"
			(at -0.0254 -2.5146 0)
			(unlocked yes)
			(layer "F.Fab")
			(hide yes)
			(effects
				(font
					(size 1.016 1.016)
					(thickness 0.1524)
				)
			)
		)
		(property "Device Type" "R603H22"
			(at -0.0254 -4.0386 0)
			(unlocked yes)
			(layer "F.Fab")
			(hide yes)
			(effects
				(font
					(size 1.016 1.016)
					(thickness 0.1524)
				)
			)
		)
		(duplicate_pad_numbers_are_jumpers no)
		(fp_line
			(start -0.4826 0)
			(end -0.2032 0)
			(stroke
				(width 0.2032)
				(type default)
			)
			(layer "F.SilkS")
		)
		(fp_line
			(start 0.2032 0)
			(end 0.4826 0)
			(stroke
				(width 0.2032)
				(type default)
			)
			(layer "F.SilkS")
		)
		(fp_rect
			(start -0.5842 1.3335)
			(end 0.5842 -1.3335)
			(stroke
				(width 0)
				(type default)
			)
			(fill no)
			(layer "F.CrtYd")
		)
		(fp_rect
			(start -0.5842 1.3335)
			(end 0.5842 -1.3335)
			(stroke
				(width 0)
				(type default)
			)
			(fill no)
			(layer "F.Fab")
		)
		(pad "1" smd custom
			(at 0 -0.762)
			(size 0.2159 0.2159)
			(layers "F.Cu" "F.Mask" "F.Paste")
			(net "P5V_B_1")
			(options
				(clearance outline)
				(anchor circle)
			)
			(primitives
				(gr_poly
					(pts
						(arc
							(start -0.3302 -0.4318)
							(mid -0.402042 -0.402042)
							(end -0.4318 -0.3302)
						)
						(arc
							(start -0.4318 0.3302)
							(mid -0.402042 0.402042)
							(end -0.3302 0.4318)
						)
						(arc
							(start 0.3302 0.4318)
							(mid 0.402042 0.402042)
							(end 0.4318 0.3302)
						)
						(arc
							(start 0.4318 -0.3302)
							(mid 0.402042 -0.402042)
							(end 0.3302 -0.4318)
						)
					)
					(width 0)
					(fill yes)
				)
			)
		)
		(pad "2" smd custom
			(at 0 0.762)
			(size 0.2159 0.2159)
			(layers "F.Cu" "F.Mask" "F.Paste")
			(net "FLT_HDD14")
			(options
				(clearance outline)
				(anchor circle)
			)
			(primitives
				(gr_poly
					(pts
						(arc
							(start -0.3302 -0.4318)
							(mid -0.402042 -0.402042)
							(end -0.4318 -0.3302)
						)
						(arc
							(start -0.4318 0.3302)
							(mid -0.402042 0.402042)
							(end -0.3302 0.4318)
						)
						(arc
							(start 0.3302 0.4318)
							(mid 0.402042 0.402042)
							(end 0.4318 0.3302)
						)
						(arc
							(start 0.4318 -0.3302)
							(mid 0.402042 -0.402042)
							(end 0.3302 -0.4318)
						)
					)
					(width 0)
					(fill yes)
				)
			)
		)
	)
	(footprint ""
		(layer "F.Cu")
		(at 201.836274 -333.39659 90)
		(property "Reference" "Q195"
			(at 0 0 90)
			(layer "F.SilkS")
			(hide yes)
			(effects
				(font
					(size 1.27 1.27)
				)
			)
		)
		(property "Value" "IRFH8201TRPBF-GP"
			(at -4.2164 -4.3688 90)
			(unlocked yes)
			(layer "F.Fab")
			(hide yes)
			(effects
				(font
					(size 1.016 1.016)
					(thickness 0.1524)
				)
			)
		)
		(property "Device Type" "PPAK-5PH42"
			(at -4.2164 -5.8928 90)
			(unlocked yes)
			(layer "F.Fab")
			(hide yes)
			(effects
				(font
					(size 1.016 1.016)
					(thickness 0.1524)
				)
			)
		)
		(duplicate_pad_numbers_are_jumpers no)
		(fp_line
			(start 2.8956 -2.794)
			(end 2.8956 4.826)
			(stroke
				(width 0.1524)
				(type default)
			)
			(layer "F.SilkS")
		)
		(fp_line
			(start -2.8956 -2.794)
			(end 2.8956 -2.794)
			(stroke
				(width 0.1524)
				(type default)
			)
			(layer "F.SilkS")
		)
		(fp_line
			(start 2.8956 4.826)
			(end -2.8956 4.826)
			(stroke
				(width 0.1524)
				(type default)
			)
			(layer "F.SilkS")
		)
		(fp_line
			(start -2.8956 4.826)
			(end -2.8956 -2.794)
			(stroke
				(width 0.1524)
				(type default)
			)
			(layer "F.SilkS")
		)
		(fp_line
			(start -1.9431 4.9276)
			(end -3.0353 4.9276)
			(stroke
				(width 0.3302)
				(type default)
			)
			(layer "F.SilkS")
		)
		(fp_line
			(start -3.0353 4.9276)
			(end -3.0353 3.9624)
			(stroke
				(width 0.3302)
				(type default)
			)
			(layer "F.SilkS")
		)
		(fp_poly
			(pts
				(xy -2.3622 5.334) (xy -1.4986 5.334) (xy -1.9304 4.9022)
			)
			(stroke
				(width 0)
				(type default)
			)
			(fill yes)
			(layer "F.SilkS")
		)
		(fp_poly
			(pts
				(xy 0.3556 -0.3556) (xy 2.6416 -0.3556) (xy 2.6416 -2.54) (xy 0.3556 -2.54)
			)
			(stroke
				(width 0)
				(type default)
			)
			(fill yes)
			(layer "F.Paste")
		)
		(fp_poly
			(pts
				(xy -2.6416 -0.3556) (xy -0.3556 -0.3556) (xy -0.3556 -2.54) (xy -2.6416 -2.54)
			)
			(stroke
				(width 0)
				(type default)
			)
			(fill yes)
			(layer "F.Paste")
		)
		(fp_poly
			(pts
				(xy 0.3556 2.54) (xy 2.6416 2.54) (xy 2.6416 0.3556) (xy 0.3556 0.3556)
			)
			(stroke
				(width 0)
				(type default)
			)
			(fill yes)
			(layer "F.Paste")
		)
		(fp_poly
			(pts
				(xy -2.6416 2.54) (xy -0.3556 2.54) (xy -0.3556 0.3556) (xy -2.6416 0.3556)
			)
			(stroke
				(width 0)
				(type default)
			)
			(fill yes)
			(layer "F.Paste")
		)
		(fp_rect
			(start -2.5781 3.9878)
			(end 2.5781 -2.1082)
			(stroke
				(width 0)
				(type default)
			)
			(fill no)
			(layer "F.CrtYd")
		)
		(fp_poly
			(pts
				(xy -3.1496 5.08) (xy -3.1496 -3.048) (xy 3.1496 -3.048) (xy 3.1496 3.9751) (xy 2.5781 3.9751) (xy 2.5781 -2.1082)
				(xy -2.5781 -2.1082) (xy -2.5781 3.9878) (xy 3.1496 3.9878) (xy 3.1496 5.08)
			)
			(stroke
				(width 0)
				(type default)
			)
			(fill no)
			(layer "F.CrtYd")
		)
		(fp_rect
			(start -3.1496 5.08)
			(end 3.1496 -3.048)
			(stroke
				(width 0)
				(type default)
			)
			(fill no)
			(layer "F.Fab")
		)
		(pad "1" smd rect
			(at -1.905 3.81 90)
			(size 0.762 1.524)
			(layers "F.Cu" "F.Mask" "F.Paste")
			(net "P12V_IN")
		)
		(pad "2" smd rect
			(at -0.635 3.81 90)
			(size 0.762 1.524)
			(layers "F.Cu" "F.Mask" "F.Paste")
			(net "P12V_IN")
		)
		(pad "3" smd rect
			(at 0.635 3.81 90)
			(size 0.762 1.524)
			(layers "F.Cu" "F.Mask" "F.Paste")
			(net "P12V_IN")
		)
		(pad "4" smd rect
			(at 1.905 3.81 90)
			(size 0.762 1.524)
			(layers "F.Cu" "F.Mask" "F.Paste")
			(net "MB0_12V_CTRL_GATE2")
		)
		(pad "5" smd rect
			(at 0 0 90)
			(size 5.2832 5.08)
			(layers "F.Cu" "F.Mask" "F.Paste")
			(net "MB0_P12V_IN_R")
		)
		(pad "6" smd rect
			(at 0.635 -2.032 90)
			(size 0.0254 0.0254)
			(layers "F.Cu" "F.Mask" "F.Paste")
			(net "MB0_P12V_IN_R")
		)
		(pad "7" smd rect
			(at -0.635 -2.032 90)
			(size 0.0254 0.0254)
			(layers "F.Cu" "F.Mask" "F.Paste")
			(net "MB0_P12V_IN_R")
		)
		(pad "8" smd rect
			(at -1.905 -2.032 90)
			(size 0.0254 0.0254)
			(layers "F.Cu" "F.Mask" "F.Paste")
			(net "MB0_P12V_IN_R")
		)
	)
	(footprint ""
		(layer "F.Cu")
		(at 409.800044 -65.39992)
		(property "Reference" "LED22"
			(at 0 0 0)
			(layer "F.SilkS")
			(hide yes)
			(effects
				(font
					(size 1.27 1.27)
				)
			)
		)
		(property "Value" "LED-BY-19-GP"
			(at -2.132076 1.414018 0)
			(unlocked yes)
			(layer "F.Fab")
			(hide yes)
			(effects
				(font
					(size 1.016 1.016)
					(thickness 0.1524)
				)
			)
		)
		(property "Device Type" "LED-1615-4PH26"
			(at -2.132076 -0.109982 0)
			(unlocked yes)
			(layer "F.Fab")
			(hide yes)
			(effects
				(font
					(size 1.016 1.016)
					(thickness 0.1524)
				)
			)
		)
		(duplicate_pad_numbers_are_jumpers no)
		(fp_line
			(start -1.2954 0.254)
			(end -1.2954 1.6002)
			(stroke
				(width 0.508)
				(type default)
			)
			(layer "F.SilkS")
		)
		(fp_line
			(start -1.2954 1.6002)
			(end 1.2954 1.6002)
			(stroke
				(width 0.508)
				(type default)
			)
			(layer "F.SilkS")
		)
		(fp_line
			(start -1.1176 -1.4224)
			(end 1.1176 -1.4224)
			(stroke
				(width 0.1524)
				(type default)
			)
			(layer "F.SilkS")
		)
		(fp_line
			(start -1.1176 1.4224)
			(end -1.1176 -1.4224)
			(stroke
				(width 0.1524)
				(type default)
			)
			(layer "F.SilkS")
		)
		(fp_line
			(start 1.1176 -1.4224)
			(end 1.1176 1.4224)
			(stroke
				(width 0.1524)
				(type default)
			)
			(layer "F.SilkS")
		)
		(fp_line
			(start 1.1176 1.4224)
			(end -1.1176 1.4224)
			(stroke
				(width 0.1524)
				(type default)
			)
			(layer "F.SilkS")
		)
		(fp_line
			(start 1.2954 1.6002)
			(end 1.2954 0.254)
			(stroke
				(width 0.508)
				(type default)
			)
			(layer "F.SilkS")
		)
		(fp_rect
			(start -0.7493 0.8001)
			(end 0.7493 -0.8001)
			(stroke
				(width 0)
				(type default)
			)
			(fill no)
			(layer "F.CrtYd")
		)
		(fp_poly
			(pts
				(xy -1.3716 1.6764) (xy -1.3716 -1.6764) (xy 1.3716 -1.6764) (xy 1.3716 0.0635) (xy 0.7493 0.0635)
				(xy 0.7493 -0.8001) (xy -0.7493 -0.8001) (xy -0.7493 0.8001) (xy 0.7493 0.8001) (xy 0.7493 0.0762)
				(xy 1.3716 0.0762) (xy 1.3716 1.6764)
			)
			(stroke
				(width 0)
				(type default)
			)
			(fill no)
			(layer "F.CrtYd")
		)
		(fp_rect
			(start -1.3716 1.6764)
			(end 1.3716 -1.6764)
			(stroke
				(width 0)
				(type default)
			)
			(fill no)
			(layer "F.Fab")
		)
		(pad "1" smd rect
			(at 0.50038 -0.73025)
			(size 0.7112 0.8636)
			(layers "F.Cu" "F.Mask" "F.Paste")
			(net "DRV_ACT_21")
		)
		(pad "2" smd rect
			(at -0.50038 -0.73025)
			(size 0.7112 0.8636)
			(layers "F.Cu" "F.Mask" "F.Paste")
			(net "FLT_HDD21")
		)
		(pad "3" smd rect
			(at 0.50038 0.73025)
			(size 0.7112 0.8636)
			(layers "F.Cu" "F.Mask" "F.Paste")
			(net "DRV_ACT_21_N")
		)
		(pad "4" smd rect
			(at -0.50038 0.73025)
			(size 0.7112 0.8636)
			(layers "F.Cu" "F.Mask" "F.Paste")
			(net "FLT_HDD21_N")
		)
	)
	(footprint ""
		(layer "F.Cu")
		(at 367.284 -16.764 180)
		(property "Reference" "R800"
			(at 0 0 180)
			(layer "F.SilkS")
			(hide yes)
			(effects
				(font
					(size 1.27 1.27)
				)
			)
		)
		(property "Value" "0R2J-2-GP"
			(at 0.064008 -3.993896 180)
			(unlocked yes)
			(layer "F.Fab")
			(hide yes)
			(effects
				(font
					(size 1.016 1.016)
					(thickness 0.1524)
				)
			)
		)
		(property "Device Type" "R402H16"
			(at 0.064008 -5.517896 180)
			(unlocked yes)
			(layer "F.Fab")
			(hide yes)
			(effects
				(font
					(size 1.016 1.016)
					(thickness 0.1524)
				)
			)
		)
		(duplicate_pad_numbers_are_jumpers no)
		(fp_line
			(start 0.508 -0.9398)
			(end -0.508 -0.9398)
			(stroke
				(width 0.1524)
				(type default)
			)
			(layer "F.SilkS")
		)
		(fp_line
			(start -0.508 -0.9398)
			(end -0.508 0.9398)
			(stroke
				(width 0.1524)
				(type default)
			)
			(layer "F.SilkS")
		)
		(fp_rect
			(start -0.508 0.9398)
			(end 0.508 -0.9398)
			(stroke
				(width 0)
				(type default)
			)
			(fill no)
			(layer "F.CrtYd")
		)
		(fp_rect
			(start -0.508 0.9398)
			(end 0.508 -0.9398)
			(stroke
				(width 0)
				(type default)
			)
			(fill no)
			(layer "F.Fab")
		)
		(pad "1" smd custom
			(at 0 -0.4445 180)
			(size 0.1397 0.1397)
			(layers "F.Cu" "F.Mask" "F.Paste")
			(net "SW_HDD_G31")
			(options
				(clearance outline)
				(anchor circle)
			)
			(primitives
				(gr_poly
					(pts
						(arc
							(start -0.1778 -0.2794)
							(mid -0.249642 -0.249642)
							(end -0.2794 -0.1778)
						)
						(arc
							(start -0.2794 0.1778)
							(mid -0.249642 0.249642)
							(end -0.1778 0.2794)
						)
						(arc
							(start 0.1778 0.2794)
							(mid 0.249642 0.249642)
							(end 0.2794 0.1778)
						)
						(arc
							(start 0.2794 -0.1778)
							(mid 0.249642 -0.249642)
							(end 0.1778 -0.2794)
						)
					)
					(width 0)
					(fill yes)
				)
			)
		)
		(pad "2" smd custom
			(at 0 0.4445 180)
			(size 0.1397 0.1397)
			(layers "F.Cu" "F.Mask" "F.Paste")
			(net "SW_HDD_R31")
			(options
				(clearance outline)
				(anchor circle)
			)
			(primitives
				(gr_poly
					(pts
						(arc
							(start -0.1778 -0.2794)
							(mid -0.249642 -0.249642)
							(end -0.2794 -0.1778)
						)
						(arc
							(start -0.2794 0.1778)
							(mid -0.249642 0.249642)
							(end -0.1778 0.2794)
						)
						(arc
							(start 0.1778 0.2794)
							(mid 0.249642 0.249642)
							(end 0.2794 0.1778)
						)
						(arc
							(start 0.2794 -0.1778)
							(mid 0.249642 -0.249642)
							(end 0.1778 -0.2794)
						)
					)
					(width 0)
					(fill yes)
				)
			)
		)
	)
	(footprint ""
		(layer "F.Cu")
		(at 311.904126 -214.757 180)
		(property "Reference" "Q225"
			(at 0 0 180)
			(layer "F.SilkS")
			(hide yes)
			(effects
				(font
					(size 1.27 1.27)
				)
			)
		)
		(property "Value" "2N7002K-2-GP"
			(at 0.127 -8.9662 180)
			(unlocked yes)
			(layer "F.Fab")
			(hide yes)
			(effects
				(font
					(size 1.016 1.016)
					(thickness 0.1524)
				)
			)
		)
		(property "Device Type" "SOT23DGS2D4H44"
			(at 0.127 -10.4902 180)
			(unlocked yes)
			(layer "F.Fab")
			(hide yes)
			(effects
				(font
					(size 1.016 1.016)
					(thickness 0.1524)
				)
			)
		)
		(duplicate_pad_numbers_are_jumpers no)
		(fp_line
			(start 1.651 1.778)
			(end 1.651 -1.778)
			(stroke
				(width 0.1524)
				(type default)
			)
			(layer "F.SilkS")
		)
		(fp_line
			(start 1.651 -1.778)
			(end -1.651 -1.778)
			(stroke
				(width 0.1524)
				(type default)
			)
			(layer "F.SilkS")
		)
		(fp_line
			(start -1.651 1.778)
			(end 1.651 1.778)
			(stroke
				(width 0.1524)
				(type default)
			)
			(layer "F.SilkS")
		)
		(fp_line
			(start -1.651 -1.778)
			(end -1.651 1.778)
			(stroke
				(width 0.1524)
				(type default)
			)
			(layer "F.SilkS")
		)
		(fp_poly
			(pts
				(xy -1.778 1.8796) (xy -1.778 -1.8796) (xy 1.778 -1.8796) (xy 1.778 1.8796)
			)
			(stroke
				(width 0)
				(type default)
			)
			(fill no)
			(layer "F.CrtYd")
		)
		(fp_poly
			(pts
				(xy -1.778 1.8796) (xy -1.778 -1.8796) (xy 1.778 -1.8796) (xy 1.778 1.8796)
			)
			(stroke
				(width 0)
				(type default)
			)
			(fill no)
			(layer "F.Fab")
		)
		(pad "D" smd custom
			(at 0 -0.9525 180)
			(size 0.1905 0.1905)
			(layers "F.Cu" "F.Mask" "F.Paste")
			(net "FLT_HDD6_N")
			(options
				(clearance outline)
				(anchor circle)
			)
			(primitives
				(gr_poly
					(pts
						(arc
							(start -0.1778 0.5715)
							(mid -0.321484 0.511984)
							(end -0.381 0.3683)
						)
						(arc
							(start -0.381 -0.3683)
							(mid -0.321484 -0.511984)
							(end -0.1778 -0.5715)
						)
						(arc
							(start 0.1778 -0.5715)
							(mid 0.321484 -0.511984)
							(end 0.381 -0.3683)
						)
						(arc
							(start 0.381 0.3683)
							(mid 0.321484 0.511984)
							(end 0.1778 0.5715)
						)
					)
					(width 0)
					(fill yes)
				)
			)
		)
		(pad "G" smd custom
			(at -0.98425 0.9525 180)
			(size 0.1905 0.1905)
			(layers "F.Cu" "F.Mask" "F.Paste")
			(net "DRIVE_B_6_FLT_LED")
			(options
				(clearance outline)
				(anchor circle)
			)
			(primitives
				(gr_poly
					(pts
						(arc
							(start -0.1778 0.5715)
							(mid -0.321484 0.511984)
							(end -0.381 0.3683)
						)
						(arc
							(start -0.381 -0.3683)
							(mid -0.321484 -0.511984)
							(end -0.1778 -0.5715)
						)
						(arc
							(start 0.1778 -0.5715)
							(mid 0.321484 -0.511984)
							(end 0.381 -0.3683)
						)
						(arc
							(start 0.381 0.3683)
							(mid 0.321484 0.511984)
							(end 0.1778 0.5715)
						)
					)
					(width 0)
					(fill yes)
				)
			)
		)
		(pad "S" smd custom
			(at 0.98425 0.9525 180)
			(size 0.1905 0.1905)
			(layers "F.Cu" "F.Mask" "F.Paste")
			(net "GND")
			(options
				(clearance outline)
				(anchor circle)
			)
			(primitives
				(gr_poly
					(pts
						(arc
							(start -0.1778 0.5715)
							(mid -0.321484 0.511984)
							(end -0.381 0.3683)
						)
						(arc
							(start -0.381 -0.3683)
							(mid -0.321484 -0.511984)
							(end -0.1778 -0.5715)
						)
						(arc
							(start 0.1778 -0.5715)
							(mid 0.321484 -0.511984)
							(end 0.381 -0.3683)
						)
						(arc
							(start 0.381 0.3683)
							(mid 0.321484 0.511984)
							(end 0.1778 0.5715)
						)
					)
					(width 0)
					(fill yes)
				)
			)
		)
	)
	(footprint ""
		(layer "F.Cu")
		(at 323.3166 -17.4371)
		(property "Reference" "VIA62"
			(at 0 0 0)
			(layer "F.SilkS")
			(hide yes)
			(effects
				(font
					(size 1.27 1.27)
				)
			)
		)
		(property "Value" "100OHM-8L-2D36MM-L16-GP"
			(at -3.4036 -0.4572 0)
			(unlocked yes)
			(layer "F.Fab")
			(hide yes)
			(effects
				(font
					(size 1.016 1.016)
					(thickness 0.1524)
				)
			)
		)
		(property "Device Type" "VIA-PCIE-4P-427097"
			(at -3.4036 -1.9812 0)
			(unlocked yes)
			(layer "F.Fab")
			(hide yes)
			(effects
				(font
					(size 1.016 1.016)
					(thickness 0.1524)
				)
			)
		)
		(duplicate_pad_numbers_are_jumpers no)
		(fp_rect
			(start -2.1336 0.4826)
			(end 2.1336 -0.4826)
			(stroke
				(width 0)
				(type default)
			)
			(fill no)
			(layer "F.CrtYd")
		)
		(fp_rect
			(start -2.1336 0.4826)
			(end 2.1336 -0.4826)
			(stroke
				(width 0)
				(type default)
			)
			(fill no)
			(layer "F.Fab")
		)
		(pad "1" thru_hole circle
			(at -1.651 0)
			(size 0.508 0.508)
			(drill 0.254)
			(layers "*.Cu" "*.Mask")
			(remove_unused_layers no)
			(net "GND")
			(clearance 0.2286)
			(thermal_gap 0.2286)
		)
		(pad "2" thru_hole circle
			(at -0.635 0)
			(size 0.508 0.508)
			(drill 0.254)
			(layers "*.Cu" "*.Mask")
			(remove_unused_layers no)
			(net "PHY_DRV_B_TO_SCC_B_30_DP")
			(clearance 0.2286)
			(thermal_gap 0.2286)
		)
		(pad "3" thru_hole circle
			(at 0.635 0)
			(size 0.508 0.508)
			(drill 0.254)
			(layers "*.Cu" "*.Mask")
			(remove_unused_layers no)
			(net "PHY_DRV_B_TO_SCC_B_30_DN")
			(clearance 0.2286)
			(thermal_gap 0.2286)
		)
		(pad "4" thru_hole circle
			(at 1.651 0)
			(size 0.508 0.508)
			(drill 0.254)
			(layers "*.Cu" "*.Mask")
			(remove_unused_layers no)
			(net "GND")
			(clearance 0.2286)
			(thermal_gap 0.2286)
		)
	)
	(footprint ""
		(layer "F.Cu")
		(at 335.153 -360.299)
		(property "Reference" "R968"
			(at 0 0 0)
			(layer "F.SilkS")
			(hide yes)
			(effects
				(font
					(size 1.27 1.27)
				)
			)
		)
		(property "Value" "4K7R2J-2-GP"
			(at 0.064008 -3.993896 0)
			(unlocked yes)
			(layer "F.Fab")
			(hide yes)
			(effects
				(font
					(size 1.016 1.016)
					(thickness 0.1524)
				)
			)
		)
		(property "Device Type" "R402H16"
			(at 0.064008 -5.517896 0)
			(unlocked yes)
			(layer "F.Fab")
			(hide yes)
			(effects
				(font
					(size 1.016 1.016)
					(thickness 0.1524)
				)
			)
		)
		(duplicate_pad_numbers_are_jumpers no)
		(fp_line
			(start -0.508 -0.9398)
			(end -0.508 0.9398)
			(stroke
				(width 0.1524)
				(type default)
			)
			(layer "F.SilkS")
		)
		(fp_line
			(start 0.508 -0.9398)
			(end -0.508 -0.9398)
			(stroke
				(width 0.1524)
				(type default)
			)
			(layer "F.SilkS")
		)
		(fp_rect
			(start -0.508 0.9398)
			(end 0.508 -0.9398)
			(stroke
				(width 0)
				(type default)
			)
			(fill no)
			(layer "F.CrtYd")
		)
		(fp_rect
			(start -0.508 0.9398)
			(end 0.508 -0.9398)
			(stroke
				(width 0)
				(type default)
			)
			(fill no)
			(layer "F.Fab")
		)
		(pad "1" smd custom
			(at 0 -0.4445)
			(size 0.1397 0.1397)
			(layers "F.Cu" "F.Mask" "F.Paste")
			(net "P12V_IN")
			(options
				(clearance outline)
				(anchor circle)
			)
			(primitives
				(gr_poly
					(pts
						(arc
							(start -0.1778 -0.2794)
							(mid -0.249642 -0.249642)
							(end -0.2794 -0.1778)
						)
						(arc
							(start -0.2794 0.1778)
							(mid -0.249642 0.249642)
							(end -0.1778 0.2794)
						)
						(arc
							(start 0.1778 0.2794)
							(mid 0.249642 0.249642)
							(end 0.2794 0.1778)
						)
						(arc
							(start 0.2794 -0.1778)
							(mid 0.249642 -0.249642)
							(end 0.1778 -0.2794)
						)
					)
					(width 0)
					(fill yes)
				)
			)
		)
		(pad "2" smd custom
			(at 0 0.4445)
			(size 0.1397 0.1397)
			(layers "F.Cu" "F.Mask" "F.Paste")
			(net "GATE_FAN2")
			(options
				(clearance outline)
				(anchor circle)
			)
			(primitives
				(gr_poly
					(pts
						(arc
							(start -0.1778 -0.2794)
							(mid -0.249642 -0.249642)
							(end -0.2794 -0.1778)
						)
						(arc
							(start -0.2794 0.1778)
							(mid -0.249642 0.249642)
							(end -0.1778 0.2794)
						)
						(arc
							(start 0.1778 0.2794)
							(mid 0.249642 0.249642)
							(end 0.2794 0.1778)
						)
						(arc
							(start 0.2794 -0.1778)
							(mid 0.249642 -0.249642)
							(end 0.1778 -0.2794)
						)
					)
					(width 0)
					(fill yes)
				)
			)
		)
	)
	(footprint ""
		(layer "F.Cu")
		(at 47.960534 -110.398306 -90)
		(property "Reference" "R1123"
			(at 0 0 270)
			(layer "F.SilkS")
			(hide yes)
			(effects
				(font
					(size 1.27 1.27)
				)
			)
		)
		(property "Value" "3D01R5F-GP"
			(at 0 -8.9535 270)
			(unlocked yes)
			(layer "F.Fab")
			(hide yes)
			(effects
				(font
					(size 1.27 1.016)
					(thickness 0.1524)
				)
			)
		)
		(property "Device Type" "R805H24"
			(at 0 -10.6299 270)
			(unlocked yes)
			(layer "F.Fab")
			(hide yes)
			(effects
				(font
					(size 1.27 1.016)
					(thickness 0.1524)
				)
			)
		)
		(duplicate_pad_numbers_are_jumpers no)
		(fp_line
			(start -0.889 1.7018)
			(end 0.889 1.7018)
			(stroke
				(width 0.1524)
				(type default)
			)
			(layer "F.SilkS")
		)
		(fp_line
			(start 0.889 1.7018)
			(end 0.889 -0.508)
			(stroke
				(width 0.1524)
				(type default)
			)
			(layer "F.SilkS")
		)
		(fp_line
			(start -0.889 0.0762)
			(end -0.889 1.7018)
			(stroke
				(width 0.1524)
				(type default)
			)
			(layer "F.SilkS")
		)
		(fp_line
			(start -0.889 -1.7018)
			(end -0.889 0.2794)
			(stroke
				(width 0.1524)
				(type default)
			)
			(layer "F.SilkS")
		)
		(fp_line
			(start 0.889 -1.7018)
			(end 0.889 -0.381)
			(stroke
				(width 0.1524)
				(type default)
			)
			(layer "F.SilkS")
		)
		(fp_line
			(start 0.889 -1.7018)
			(end -0.889 -1.7018)
			(stroke
				(width 0.1524)
				(type default)
			)
			(layer "F.SilkS")
		)
		(fp_poly
			(pts
				(xy 0.9652 -1.778) (xy 0.9652 1.778) (xy -0.9652 1.778) (xy -0.9652 -1.778)
			)
			(stroke
				(width 0)
				(type default)
			)
			(fill no)
			(layer "F.CrtYd")
		)
		(fp_rect
			(start -0.9652 1.778)
			(end 0.9652 -1.778)
			(stroke
				(width 0)
				(type default)
			)
			(fill no)
			(layer "F.Fab")
		)
		(pad "1" smd rect
			(at 0 -0.9652 270)
			(size 1.397 1.143)
			(layers "F.Cu" "F.Mask" "F.Paste")
			(net "P5V_B_2_SNB")
		)
		(pad "2" smd rect
			(at 0 0.9652 270)
			(size 1.397 1.143)
			(layers "F.Cu" "F.Mask" "F.Paste")
			(net "GND")
		)
	)
	(footprint ""
		(layer "F.Cu")
		(at 231.013 -306.705 90)
		(property "Reference" "U18"
			(at 0 0 90)
			(layer "F.SilkS")
			(hide yes)
			(effects
				(font
					(size 1.27 1.27)
				)
			)
		)
		(property "Value" "SN74CBTLV3245APWR-GP"
			(at -0.889 -6.2738 90)
			(unlocked yes)
			(layer "F.Fab")
			(hide yes)
			(effects
				(font
					(size 1.016 1.016)
					(thickness 0.1524)
				)
			)
		)
		(property "Device Type" "TSOIC20H48"
			(at -0.9144 -7.8994 90)
			(unlocked yes)
			(layer "F.Fab")
			(hide yes)
			(effects
				(font
					(size 1.016 1.016)
					(thickness 0.1524)
				)
			)
		)
		(duplicate_pad_numbers_are_jumpers no)
		(fp_line
			(start 3.175 -1.397)
			(end 3.175 1.397)
			(stroke
				(width 0.2032)
				(type default)
			)
			(layer "F.SilkS")
		)
		(fp_line
			(start -3.556 -1.397)
			(end 3.175 -1.397)
			(stroke
				(width 0.2032)
				(type default)
			)
			(layer "F.SilkS")
		)
		(fp_line
			(start -3.556 -1.397)
			(end -3.556 4.064)
			(stroke
				(width 0.2032)
				(type default)
			)
			(layer "F.SilkS")
		)
		(fp_line
			(start -2.667 0)
			(end -3.556 -0.889)
			(stroke
				(width 0.2032)
				(type default)
			)
			(layer "F.SilkS")
		)
		(fp_line
			(start -2.667 0)
			(end -3.556 0.889)
			(stroke
				(width 0.2032)
				(type default)
			)
			(layer "F.SilkS")
		)
		(fp_line
			(start 3.175 1.397)
			(end -3.556 1.397)
			(stroke
				(width 0.2032)
				(type default)
			)
			(layer "F.SilkS")
		)
		(fp_line
			(start -3.556 1.397)
			(end -3.556 1.778)
			(stroke
				(width 0.2032)
				(type default)
			)
			(layer "F.SilkS")
		)
		(fp_line
			(start -3.556 4.064)
			(end -3.556 1.778)
			(stroke
				(width 0.508)
				(type default)
			)
			(layer "F.SilkS")
		)
		(fp_poly
			(pts
				(xy -3.25628 -1.8542) (xy 3.25628 -1.8542) (xy 3.25628 1.8542) (xy -3.25628 1.8542)
			)
			(stroke
				(width 0)
				(type default)
			)
			(fill yes)
			(layer "F.SilkS")
		)
		(fp_rect
			(start -3.556 3.81)
			(end 3.556 -3.81)
			(stroke
				(width 0)
				(type default)
			)
			(fill no)
			(layer "F.CrtYd")
		)
		(fp_poly
			(pts
				(xy -3.556 -3.81) (xy 3.556 -3.81) (xy 3.556 3.81) (xy -3.556 3.81)
			)
			(stroke
				(width 0)
				(type default)
			)
			(fill no)
			(layer "F.Fab")
		)
		(pad "1" smd rect
			(at -2.92608 2.8194 90)
			(size 0.3556 1.524)
			(layers "F.Cu" "F.Mask" "F.Paste")
			(net "Net_105")
		)
		(pad "2" smd rect
			(at -2.27584 2.8194 90)
			(size 0.3556 1.524)
			(layers "F.Cu" "F.Mask" "F.Paste")
			(net "FANTACH_A_F0")
		)
		(pad "3" smd rect
			(at -1.6256 2.8194 90)
			(size 0.3556 1.524)
			(layers "F.Cu" "F.Mask" "F.Paste")
			(net "FANTACH_A_R0")
		)
		(pad "4" smd rect
			(at -0.97536 2.8194 90)
			(size 0.3556 1.524)
			(layers "F.Cu" "F.Mask" "F.Paste")
			(net "FANTACH_A_F1")
		)
		(pad "5" smd rect
			(at -0.32512 2.8194 90)
			(size 0.3556 1.524)
			(layers "F.Cu" "F.Mask" "F.Paste")
			(net "FANTACH_A_R1")
		)
		(pad "6" smd rect
			(at 0.32512 2.8194 90)
			(size 0.3556 1.524)
			(layers "F.Cu" "F.Mask" "F.Paste")
			(net "FANTACH_A_F2")
		)
		(pad "7" smd rect
			(at 0.97536 2.8194 90)
			(size 0.3556 1.524)
			(layers "F.Cu" "F.Mask" "F.Paste")
			(net "FANTACH_A_R2")
		)
		(pad "8" smd rect
			(at 1.6256 2.8194 90)
			(size 0.3556 1.524)
			(layers "F.Cu" "F.Mask" "F.Paste")
			(net "FANTACH_A_F3")
		)
		(pad "9" smd rect
			(at 2.27584 2.8194 90)
			(size 0.3556 1.524)
			(layers "F.Cu" "F.Mask" "F.Paste")
			(net "FANTACH_A_R3")
		)
		(pad "10" smd rect
			(at 2.92608 2.8194 90)
			(size 0.3556 1.524)
			(layers "F.Cu" "F.Mask" "F.Paste")
			(net "GND")
		)
		(pad "11" smd rect
			(at 2.92608 -2.8194 90)
			(size 0.3556 1.524)
			(layers "F.Cu" "F.Mask" "F.Paste")
			(net "FANTACH_R3")
		)
		(pad "12" smd rect
			(at 2.27584 -2.8194 90)
			(size 0.3556 1.524)
			(layers "F.Cu" "F.Mask" "F.Paste")
			(net "FANTACH_F3")
		)
		(pad "13" smd rect
			(at 1.6256 -2.8194 90)
			(size 0.3556 1.524)
			(layers "F.Cu" "F.Mask" "F.Paste")
			(net "FANTACH_R2")
		)
		(pad "14" smd rect
			(at 0.97536 -2.8194 90)
			(size 0.3556 1.524)
			(layers "F.Cu" "F.Mask" "F.Paste")
			(net "FANTACH_F2")
		)
		(pad "15" smd rect
			(at 0.32512 -2.8194 90)
			(size 0.3556 1.524)
			(layers "F.Cu" "F.Mask" "F.Paste")
			(net "FANTACH_R1")
		)
		(pad "16" smd rect
			(at -0.32512 -2.8194 90)
			(size 0.3556 1.524)
			(layers "F.Cu" "F.Mask" "F.Paste")
			(net "FANTACH_F1")
		)
		(pad "17" smd rect
			(at -0.97536 -2.8194 90)
			(size 0.3556 1.524)
			(layers "F.Cu" "F.Mask" "F.Paste")
			(net "FANTACH_R0")
		)
		(pad "18" smd rect
			(at -1.6256 -2.8194 90)
			(size 0.3556 1.524)
			(layers "F.Cu" "F.Mask" "F.Paste")
			(net "FANTACH_F0")
		)
		(pad "19" smd rect
			(at -2.27584 -2.8194 90)
			(size 0.3556 1.524)
			(layers "F.Cu" "F.Mask" "F.Paste")
			(net "FANTACH_A_OE_N")
		)
		(pad "20" smd rect
			(at -2.92608 -2.8194 90)
			(size 0.3556 1.524)
			(layers "F.Cu" "F.Mask" "F.Paste")
			(net "P3V3_IN")
		)
	)
	(footprint ""
		(layer "F.Cu")
		(at 221.73946 -164.38626 90)
		(property "Reference" "R58"
			(at 0 0 90)
			(layer "F.SilkS")
			(hide yes)
			(effects
				(font
					(size 1.27 1.27)
				)
			)
		)
		(property "Value" "4K7R2F-GP"
			(at 0.064008 -3.993896 90)
			(unlocked yes)
			(layer "F.Fab")
			(hide yes)
			(effects
				(font
					(size 1.016 1.016)
					(thickness 0.1524)
				)
			)
		)
		(property "Device Type" "R402H16"
			(at 0.064008 -5.517896 90)
			(unlocked yes)
			(layer "F.Fab")
			(hide yes)
			(effects
				(font
					(size 1.016 1.016)
					(thickness 0.1524)
				)
			)
		)
		(duplicate_pad_numbers_are_jumpers no)
		(fp_line
			(start 0.508 -0.9398)
			(end -0.508 -0.9398)
			(stroke
				(width 0.1524)
				(type default)
			)
			(layer "F.SilkS")
		)
		(fp_line
			(start -0.508 -0.9398)
			(end -0.508 0.9398)
			(stroke
				(width 0.1524)
				(type default)
			)
			(layer "F.SilkS")
		)
		(fp_rect
			(start -0.508 0.9398)
			(end 0.508 -0.9398)
			(stroke
				(width 0)
				(type default)
			)
			(fill no)
			(layer "F.CrtYd")
		)
		(fp_rect
			(start -0.508 0.9398)
			(end 0.508 -0.9398)
			(stroke
				(width 0)
				(type default)
			)
			(fill no)
			(layer "F.Fab")
		)
		(pad "1" smd custom
			(at 0 -0.4445 90)
			(size 0.1397 0.1397)
			(layers "F.Cu" "F.Mask" "F.Paste")
			(net "IO_EXP6_A1")
			(options
				(clearance outline)
				(anchor circle)
			)
			(primitives
				(gr_poly
					(pts
						(arc
							(start -0.1778 -0.2794)
							(mid -0.249642 -0.249642)
							(end -0.2794 -0.1778)
						)
						(arc
							(start -0.2794 0.1778)
							(mid -0.249642 0.249642)
							(end -0.1778 0.2794)
						)
						(arc
							(start 0.1778 0.2794)
							(mid 0.249642 0.249642)
							(end 0.2794 0.1778)
						)
						(arc
							(start 0.2794 -0.1778)
							(mid 0.249642 -0.249642)
							(end 0.1778 -0.2794)
						)
					)
					(width 0)
					(fill yes)
				)
			)
		)
		(pad "2" smd custom
			(at 0 0.4445 90)
			(size 0.1397 0.1397)
			(layers "F.Cu" "F.Mask" "F.Paste")
			(net "GND")
			(options
				(clearance outline)
				(anchor circle)
			)
			(primitives
				(gr_poly
					(pts
						(arc
							(start -0.1778 -0.2794)
							(mid -0.249642 -0.249642)
							(end -0.2794 -0.1778)
						)
						(arc
							(start -0.2794 0.1778)
							(mid -0.249642 0.249642)
							(end -0.1778 0.2794)
						)
						(arc
							(start 0.1778 0.2794)
							(mid 0.249642 0.249642)
							(end 0.2794 0.1778)
						)
						(arc
							(start 0.2794 -0.1778)
							(mid 0.249642 -0.249642)
							(end 0.1778 -0.2794)
						)
					)
					(width 0)
					(fill yes)
				)
			)
		)
	)
	(footprint ""
		(layer "F.Cu")
		(at 109.73435 -102.351586 -90)
		(property "Reference" "R378"
			(at 0 0 270)
			(layer "F.SilkS")
			(hide yes)
			(effects
				(font
					(size 1.27 1.27)
				)
			)
		)
		(property "Value" "4K7R2F-GP"
			(at 0.064008 -3.993896 270)
			(unlocked yes)
			(layer "F.Fab")
			(hide yes)
			(effects
				(font
					(size 1.016 1.016)
					(thickness 0.1524)
				)
			)
		)
		(property "Device Type" "R402H16"
			(at 0.064008 -5.517896 270)
			(unlocked yes)
			(layer "F.Fab")
			(hide yes)
			(effects
				(font
					(size 1.016 1.016)
					(thickness 0.1524)
				)
			)
		)
		(duplicate_pad_numbers_are_jumpers no)
		(fp_line
			(start -0.508 -0.9398)
			(end -0.508 0.9398)
			(stroke
				(width 0.1524)
				(type default)
			)
			(layer "F.SilkS")
		)
		(fp_line
			(start 0.508 -0.9398)
			(end -0.508 -0.9398)
			(stroke
				(width 0.1524)
				(type default)
			)
			(layer "F.SilkS")
		)
		(fp_rect
			(start -0.508 0.9398)
			(end 0.508 -0.9398)
			(stroke
				(width 0)
				(type default)
			)
			(fill no)
			(layer "F.CrtYd")
		)
		(fp_rect
			(start -0.508 0.9398)
			(end 0.508 -0.9398)
			(stroke
				(width 0)
				(type default)
			)
			(fill no)
			(layer "F.Fab")
		)
		(pad "1" smd custom
			(at 0 -0.4445 270)
			(size 0.1397 0.1397)
			(layers "F.Cu" "F.Mask" "F.Paste")
			(net "DRIVE_B_15_FLT_LED")
			(options
				(clearance outline)
				(anchor circle)
			)
			(primitives
				(gr_poly
					(pts
						(arc
							(start -0.1778 -0.2794)
							(mid -0.249642 -0.249642)
							(end -0.2794 -0.1778)
						)
						(arc
							(start -0.2794 0.1778)
							(mid -0.249642 0.249642)
							(end -0.1778 0.2794)
						)
						(arc
							(start 0.1778 0.2794)
							(mid 0.249642 0.249642)
							(end 0.2794 0.1778)
						)
						(arc
							(start 0.2794 -0.1778)
							(mid 0.249642 -0.249642)
							(end 0.1778 -0.2794)
						)
					)
					(width 0)
					(fill yes)
				)
			)
		)
		(pad "2" smd custom
			(at 0 0.4445 270)
			(size 0.1397 0.1397)
			(layers "F.Cu" "F.Mask" "F.Paste")
			(net "GND")
			(options
				(clearance outline)
				(anchor circle)
			)
			(primitives
				(gr_poly
					(pts
						(arc
							(start -0.1778 -0.2794)
							(mid -0.249642 -0.249642)
							(end -0.2794 -0.1778)
						)
						(arc
							(start -0.2794 0.1778)
							(mid -0.249642 0.249642)
							(end -0.1778 0.2794)
						)
						(arc
							(start 0.1778 0.2794)
							(mid 0.249642 0.249642)
							(end 0.2794 0.1778)
						)
						(arc
							(start 0.2794 -0.1778)
							(mid 0.249642 -0.249642)
							(end 0.1778 -0.2794)
						)
					)
					(width 0)
					(fill yes)
				)
			)
		)
	)
	(footprint ""
		(layer "F.Cu")
		(at 23.876 -157.226)
		(property "Reference" "C192"
			(at 0 0 0)
			(layer "F.SilkS")
			(hide yes)
			(effects
				(font
					(size 1.27 1.27)
				)
			)
		)
		(property "Value" "SC4D7U25V5KX-1-GP"
			(at -0.0762 -6.1214 0)
			(unlocked yes)
			(layer "F.Fab")
			(hide yes)
			(effects
				(font
					(size 1.016 1.016)
					(thickness 0.1524)
				)
			)
		)
		(property "Device Type" "C805H58"
			(at -0.0762 -8.1534 0)
			(unlocked yes)
			(layer "F.Fab")
			(hide yes)
			(effects
				(font
					(size 1.016 1.016)
					(thickness 0.1524)
				)
			)
		)
		(duplicate_pad_numbers_are_jumpers no)
		(fp_line
			(start 0.635 0)
			(end -0.635 0)
			(stroke
				(width 0.508)
				(type default)
			)
			(layer "F.SilkS")
		)
		(fp_rect
			(start -0.9652 1.778)
			(end 0.9652 -1.778)
			(stroke
				(width 0)
				(type default)
			)
			(fill no)
			(layer "F.CrtYd")
		)
		(fp_poly
			(pts
				(xy -0.9652 -1.778) (xy 0.9652 -1.778) (xy 0.9652 1.778) (xy -0.9652 1.778)
			)
			(stroke
				(width 0)
				(type default)
			)
			(fill no)
			(layer "F.Fab")
		)
		(pad "1" smd rect
			(at 0 -0.9652)
			(size 1.397 1.143)
			(layers "F.Cu" "F.Mask" "F.Paste")
			(net "P12V_HDD12")
		)
		(pad "2" smd rect
			(at 0 0.9652)
			(size 1.397 1.143)
			(layers "F.Cu" "F.Mask" "F.Paste")
			(net "GND")
		)
	)
	(footprint ""
		(layer "F.Cu")
		(at 239.268 -227.076 -90)
		(property "Reference" "C17"
			(at 0 0 270)
			(layer "F.SilkS")
			(hide yes)
			(effects
				(font
					(size 1.27 1.27)
				)
			)
		)
		(property "Value" "SC1U16V3KX-5GP"
			(at 0 -2.8194 270)
			(unlocked yes)
			(layer "F.Fab")
			(hide yes)
			(effects
				(font
					(size 1.016 1.016)
					(thickness 0.1524)
				)
			)
		)
		(property "Device Type" "C603H36"
			(at 0 -4.3434 270)
			(unlocked yes)
			(layer "F.Fab")
			(hide yes)
			(effects
				(font
					(size 1.016 1.016)
					(thickness 0.1524)
				)
			)
		)
		(duplicate_pad_numbers_are_jumpers no)
		(fp_line
			(start 0.508 0)
			(end -0.508 0)
			(stroke
				(width 0.2032)
				(type default)
			)
			(layer "F.SilkS")
		)
		(fp_rect
			(start -0.5842 1.3335)
			(end 0.5842 -1.3335)
			(stroke
				(width 0)
				(type default)
			)
			(fill no)
			(layer "F.CrtYd")
		)
		(fp_rect
			(start -0.5842 1.3335)
			(end 0.5842 -1.3335)
			(stroke
				(width 0)
				(type default)
			)
			(fill no)
			(layer "F.Fab")
		)
		(pad "1" smd custom
			(at 0 -0.762 270)
			(size 0.2159 0.2159)
			(layers "F.Cu" "F.Mask" "F.Paste")
			(net "GPIO_VCC_U10")
			(options
				(clearance outline)
				(anchor circle)
			)
			(primitives
				(gr_poly
					(pts
						(arc
							(start -0.3302 -0.4318)
							(mid -0.402042 -0.402042)
							(end -0.4318 -0.3302)
						)
						(arc
							(start -0.4318 0.3302)
							(mid -0.402042 0.402042)
							(end -0.3302 0.4318)
						)
						(arc
							(start 0.3302 0.4318)
							(mid 0.402042 0.402042)
							(end 0.4318 0.3302)
						)
						(arc
							(start 0.4318 -0.3302)
							(mid 0.402042 -0.402042)
							(end 0.3302 -0.4318)
						)
					)
					(width 0)
					(fill yes)
				)
			)
		)
		(pad "2" smd custom
			(at 0 0.762 270)
			(size 0.2159 0.2159)
			(layers "F.Cu" "F.Mask" "F.Paste")
			(net "GND")
			(options
				(clearance outline)
				(anchor circle)
			)
			(primitives
				(gr_poly
					(pts
						(arc
							(start -0.3302 -0.4318)
							(mid -0.402042 -0.402042)
							(end -0.4318 -0.3302)
						)
						(arc
							(start -0.4318 0.3302)
							(mid -0.402042 0.402042)
							(end -0.3302 0.4318)
						)
						(arc
							(start 0.3302 0.4318)
							(mid 0.402042 0.402042)
							(end 0.4318 0.3302)
						)
						(arc
							(start 0.4318 -0.3302)
							(mid 0.402042 -0.402042)
							(end 0.3302 -0.4318)
						)
					)
					(width 0)
					(fill yes)
				)
			)
		)
	)
	(footprint ""
		(layer "F.Cu")
		(at 159.324802 -63.799974)
		(property "Reference" ""
			(at 0 0 0)
			(layer "F.SilkS")
			(hide yes)
			(effects
				(font
					(size 1.27 1.27)
				)
			)
		)
		(property "Value" "*"
			(at -8.398764 -8.057642 0)
			(unlocked yes)
			(layer "F.Fab")
			(hide yes)
			(effects
				(font
					(size 1.016 1.016)
					(thickness 0.1524)
				)
			)
		)
		(duplicate_pad_numbers_are_jumpers no)
		(fp_poly
			(pts
				(arc
					(start 7.3152 0)
					(mid 0 7.3152)
					(end -7.3152 0)
				)
				(arc
					(start -7.3152 -5.9944)
					(mid 0 -13.3096)
					(end 7.3152 -5.9944)
				)
			)
			(stroke
				(width 0)
				(type default)
			)
			(fill no)
			(layer "B.CrtYd")
		)
		(fp_poly
			(pts
				(arc
					(start 7.3152 0)
					(mid 0 7.3152)
					(end -7.3152 0)
				)
				(arc
					(start -7.3152 -5.9944)
					(mid 0 -13.3096)
					(end 7.3152 -5.9944)
				)
			)
			(stroke
				(width 0)
				(type default)
			)
			(fill no)
			(layer "F.CrtYd")
		)
		(fp_poly
			(pts
				(arc
					(start 7.3152 0)
					(mid 0 7.3152)
					(end -7.3152 0)
				)
				(arc
					(start -7.3152 -5.9944)
					(mid 0 -13.3096)
					(end 7.3152 -5.9944)
				)
			)
			(stroke
				(width 0)
				(type default)
			)
			(fill no)
			(layer "B.Fab")
		)
		(fp_poly
			(pts
				(arc
					(start 7.3152 0)
					(mid 0 7.3152)
					(end -7.3152 0)
				)
				(arc
					(start -7.3152 -5.9944)
					(mid 0 -13.3096)
					(end 7.3152 -5.9944)
				)
			)
			(stroke
				(width 0)
				(type default)
			)
			(fill no)
			(layer "F.Fab")
		)
		(pad "1" thru_hole oval
			(at 0 0)
			(size 14.0208 20.0152)
			(drill 0.0254
				(offset 0 -2.9972)
			)
			(layers "*.Cu" "*.Mask")
			(remove_unused_layers no)
			(net "Net_49")
			(clearance -1.002284)
			(thermal_gap 0.1524)
			(padstack
				(mode front_inner_back)
				(layer "Inner"
					(shape custom)
					(size 2.928012 2.928012)
					(options
						(anchor circle)
					)
					(primitives
						(gr_poly
							(pts
								(arc
									(start 4.571746 -2.084324)
									(mid 0.000333 7.430372)
									(end -4.571492 -2.084324)
								)
								(arc
									(start -4.571492 -2.084324)
									(mid -3.570296 -3.611977)
									(end -2.875026 -5.30098)
								)
								(arc
									(start -2.875026 -5.30098)
									(mid 0.000217 -7.43089)
									(end 2.87528 -5.30098)
								)
								(arc
									(start 2.87528 -5.30098)
									(mid 3.570511 -3.611956)
									(end 4.571746 -2.084324)
								)
							)
							(width 0)
							(fill yes)
						)
					)
					(clearance 0.1524)
				)
				(layer "B.Cu"
					(shape oval)
					(size 14.0208 20.0152)
					(offset 0 -2.9972)
					(clearance -1.002284)
				)
			)
		)
		(zone
			(layers "F.Cu" "B.Cu" "In1.Cu" "In2.Cu" "In3.Cu" "In4.Cu" "In5.Cu" "In6.Cu")
			(hatch none 0.5)
			(connect_pads
				(clearance 0)
			)
			(min_thickness 0.25)
			(keepout
				(tracks not_allowed)
				(vias allowed)
				(pads allowed)
				(copperpour not_allowed)
				(footprints allowed)
			)
			(placement
				(enabled no)
				(sheetname "")
			)
			(fill
				(thermal_gap 0.5)
				(thermal_bridge_width 0.5)
				(island_removal_mode 0)
			)
			(polygon
				(pts
					(arc
						(start 152.314402 -69.794374)
						(mid 159.324802 -76.804774)
						(end 166.335202 -69.794374)
					)
					(arc
						(start 166.335202 -63.799974)
						(mid 159.324802 -56.789574)
						(end 152.314402 -63.799974)
					)
				)
			)
		)
	)
	(footprint ""
		(layer "F.Cu")
		(at 267.854938 -96.28886 -90)
		(property "Reference" "TC15"
			(at 0 0 270)
			(layer "F.SilkS")
			(hide yes)
			(effects
				(font
					(size 1.27 1.27)
				)
			)
		)
		(property "Value" "ST100U16VDM-3-GP"
			(at 0 -9.6012 270)
			(unlocked yes)
			(layer "F.Fab")
			(hide yes)
			(effects
				(font
					(size 1.016 1.016)
					(thickness 0.1524)
				)
			)
		)
		(property "Device Type" "CT7343H79"
			(at 0 -11.1252 270)
			(unlocked yes)
			(layer "F.Fab")
			(hide yes)
			(effects
				(font
					(size 1.016 1.016)
					(thickness 0.1524)
				)
			)
		)
		(duplicate_pad_numbers_are_jumpers no)
		(fp_line
			(start -2.286 4.8768)
			(end -2.286 2.032)
			(stroke
				(width 0.1524)
				(type default)
			)
			(layer "F.SilkS")
		)
		(fp_line
			(start 2.286 4.8768)
			(end -2.286 4.8768)
			(stroke
				(width 0.1524)
				(type default)
			)
			(layer "F.SilkS")
		)
		(fp_line
			(start 2.286 2.032)
			(end 2.286 4.8768)
			(stroke
				(width 0.1524)
				(type default)
			)
			(layer "F.SilkS")
		)
		(fp_line
			(start 2.286 -2.032)
			(end 2.286 -4.8768)
			(stroke
				(width 0.1524)
				(type default)
			)
			(layer "F.SilkS")
		)
		(fp_line
			(start 2.1082 -4.699)
			(end -2.1082 -4.699)
			(stroke
				(width 0.508)
				(type default)
			)
			(layer "F.SilkS")
		)
		(fp_line
			(start -2.286 -4.8768)
			(end -2.286 -2.032)
			(stroke
				(width 0.1524)
				(type default)
			)
			(layer "F.SilkS")
		)
		(fp_line
			(start 2.286 -4.8768)
			(end -2.286 -4.8768)
			(stroke
				(width 0.1524)
				(type default)
			)
			(layer "F.SilkS")
		)
		(fp_rect
			(start -2.1463 3.6449)
			(end 2.1463 -3.6449)
			(stroke
				(width 0)
				(type default)
			)
			(fill no)
			(layer "F.CrtYd")
		)
		(fp_poly
			(pts
				(xy -2.54 4.953) (xy -2.54 4.2926) (xy -3.81 4.2926) (xy -3.81 -4.2926) (xy -2.54 -4.2926) (xy -2.54 -4.953)
				(xy 2.54 -4.953) (xy 2.54 -4.2926) (xy 3.81 -4.2926) (xy 3.81 -1.6256) (xy 2.1463 -1.6256) (xy 2.1463 -3.6449)
				(xy -2.1463 -3.6449) (xy -2.1463 3.6449) (xy 2.1463 3.6449) (xy 2.1463 -1.6129) (xy 3.81 -1.6129)
				(xy 3.81 4.2926) (xy 2.54 4.2926) (xy 2.54 4.953)
			)
			(stroke
				(width 0)
				(type default)
			)
			(fill no)
			(layer "F.CrtYd")
		)
		(fp_rect
			(start -2.54 4.953)
			(end 2.54 -4.953)
			(stroke
				(width 0)
				(type default)
			)
			(fill no)
			(layer "F.Fab")
		)
		(fp_rect
			(start -3.81 4.2926)
			(end -2.54 -4.2926)
			(stroke
				(width 0)
				(type default)
			)
			(fill no)
			(layer "F.Fab")
		)
		(fp_rect
			(start 2.54 4.2926)
			(end 3.81 -4.2926)
			(stroke
				(width 0)
				(type default)
			)
			(fill no)
			(layer "F.Fab")
		)
		(pad "1" smd rect
			(at 0 -3.1496 270)
			(size 2.413 2.286)
			(layers "F.Cu" "F.Mask" "F.Paste")
			(net "P12V_IN")
		)
		(pad "2" smd rect
			(at 0 3.1496 270)
			(size 2.413 2.286)
			(layers "F.Cu" "F.Mask" "F.Paste")
			(net "GND")
		)
		(zone
			(layer "F.Cu")
			(hatch none 0.5)
			(connect_pads
				(clearance 0)
			)
			(min_thickness 0.25)
			(keepout
				(tracks allowed)
				(vias not_allowed)
				(pads allowed)
				(copperpour not_allowed)
				(footprints allowed)
			)
			(placement
				(enabled no)
				(sheetname "")
			)
			(fill
				(thermal_gap 0.5)
				(thermal_bridge_width 0.5)
				(island_removal_mode 0)
			)
			(polygon
				(pts
					(xy 263.257538 -97.80016) (xy 263.257538 -94.77756) (xy 266.153138 -94.77756) (xy 266.483338 -94.77756)
					(xy 266.483338 -97.80016) (xy 266.153138 -97.80016)
				)
			)
		)
		(zone
			(layer "F.Cu")
			(hatch none 0.5)
			(connect_pads
				(clearance 0)
			)
			(min_thickness 0.25)
			(keepout
				(tracks allowed)
				(vias not_allowed)
				(pads allowed)
				(copperpour not_allowed)
				(footprints allowed)
			)
			(placement
				(enabled no)
				(sheetname "")
			)
			(fill
				(thermal_gap 0.5)
				(thermal_bridge_width 0.5)
				(island_removal_mode 0)
			)
			(polygon
				(pts
					(xy 269.544038 -94.77756) (xy 272.452338 -94.77756) (xy 272.452338 -97.80016) (xy 269.556738 -97.80016)
					(xy 269.226538 -97.80016) (xy 269.226538 -94.77756)
				)
			)
		)
	)
	(footprint ""
		(layer "F.Cu")
		(at 469.654128 -214.757 180)
		(property "Reference" "Q230"
			(at 0 0 180)
			(layer "F.SilkS")
			(hide yes)
			(effects
				(font
					(size 1.27 1.27)
				)
			)
		)
		(property "Value" "2N7002K-2-GP"
			(at 0.127 -8.9662 180)
			(unlocked yes)
			(layer "F.Fab")
			(hide yes)
			(effects
				(font
					(size 1.016 1.016)
					(thickness 0.1524)
				)
			)
		)
		(property "Device Type" "SOT23DGS2D4H44"
			(at 0.127 -10.4902 180)
			(unlocked yes)
			(layer "F.Fab")
			(hide yes)
			(effects
				(font
					(size 1.016 1.016)
					(thickness 0.1524)
				)
			)
		)
		(duplicate_pad_numbers_are_jumpers no)
		(fp_line
			(start 1.651 1.778)
			(end 1.651 -1.778)
			(stroke
				(width 0.1524)
				(type default)
			)
			(layer "F.SilkS")
		)
		(fp_line
			(start 1.651 -1.778)
			(end -1.651 -1.778)
			(stroke
				(width 0.1524)
				(type default)
			)
			(layer "F.SilkS")
		)
		(fp_line
			(start -1.651 1.778)
			(end 1.651 1.778)
			(stroke
				(width 0.1524)
				(type default)
			)
			(layer "F.SilkS")
		)
		(fp_line
			(start -1.651 -1.778)
			(end -1.651 1.778)
			(stroke
				(width 0.1524)
				(type default)
			)
			(layer "F.SilkS")
		)
		(fp_poly
			(pts
				(xy -1.778 1.8796) (xy -1.778 -1.8796) (xy 1.778 -1.8796) (xy 1.778 1.8796)
			)
			(stroke
				(width 0)
				(type default)
			)
			(fill no)
			(layer "F.CrtYd")
		)
		(fp_poly
			(pts
				(xy -1.778 1.8796) (xy -1.778 -1.8796) (xy 1.778 -1.8796) (xy 1.778 1.8796)
			)
			(stroke
				(width 0)
				(type default)
			)
			(fill no)
			(layer "F.Fab")
		)
		(pad "D" smd custom
			(at 0 -0.9525 180)
			(size 0.1905 0.1905)
			(layers "F.Cu" "F.Mask" "F.Paste")
			(net "FLT_HDD11_N")
			(options
				(clearance outline)
				(anchor circle)
			)
			(primitives
				(gr_poly
					(pts
						(arc
							(start -0.1778 0.5715)
							(mid -0.321484 0.511984)
							(end -0.381 0.3683)
						)
						(arc
							(start -0.381 -0.3683)
							(mid -0.321484 -0.511984)
							(end -0.1778 -0.5715)
						)
						(arc
							(start 0.1778 -0.5715)
							(mid 0.321484 -0.511984)
							(end 0.381 -0.3683)
						)
						(arc
							(start 0.381 0.3683)
							(mid 0.321484 0.511984)
							(end 0.1778 0.5715)
						)
					)
					(width 0)
					(fill yes)
				)
			)
		)
		(pad "G" smd custom
			(at -0.98425 0.9525 180)
			(size 0.1905 0.1905)
			(layers "F.Cu" "F.Mask" "F.Paste")
			(net "DRIVE_B_11_FLT_LED")
			(options
				(clearance outline)
				(anchor circle)
			)
			(primitives
				(gr_poly
					(pts
						(arc
							(start -0.1778 0.5715)
							(mid -0.321484 0.511984)
							(end -0.381 0.3683)
						)
						(arc
							(start -0.381 -0.3683)
							(mid -0.321484 -0.511984)
							(end -0.1778 -0.5715)
						)
						(arc
							(start 0.1778 -0.5715)
							(mid 0.321484 -0.511984)
							(end 0.381 -0.3683)
						)
						(arc
							(start 0.381 0.3683)
							(mid 0.321484 0.511984)
							(end 0.1778 0.5715)
						)
					)
					(width 0)
					(fill yes)
				)
			)
		)
		(pad "S" smd custom
			(at 0.98425 0.9525 180)
			(size 0.1905 0.1905)
			(layers "F.Cu" "F.Mask" "F.Paste")
			(net "GND")
			(options
				(clearance outline)
				(anchor circle)
			)
			(primitives
				(gr_poly
					(pts
						(arc
							(start -0.1778 0.5715)
							(mid -0.321484 0.511984)
							(end -0.381 0.3683)
						)
						(arc
							(start -0.381 -0.3683)
							(mid -0.321484 -0.511984)
							(end -0.1778 -0.5715)
						)
						(arc
							(start 0.1778 -0.5715)
							(mid 0.321484 -0.511984)
							(end 0.381 -0.3683)
						)
						(arc
							(start 0.381 0.3683)
							(mid 0.321484 0.511984)
							(end 0.1778 0.5715)
						)
					)
					(width 0)
					(fill yes)
				)
			)
		)
	)
	(footprint ""
		(layer "F.Cu")
		(at 336.804 -263.017)
		(property "Reference" "Q24"
			(at 0 0 0)
			(layer "F.SilkS")
			(hide yes)
			(effects
				(font
					(size 1.27 1.27)
				)
			)
		)
		(property "Value" "AO4407AL-GP"
			(at -3.707384 -1.5367 0)
			(unlocked yes)
			(layer "F.Fab")
			(hide yes)
			(effects
				(font
					(size 1.016 1.016)
					(thickness 0.1524)
				)
			)
		)
		(property "Device Type" "SOIC8H69"
			(at -3.707384 -3.0607 0)
			(unlocked yes)
			(layer "F.Fab")
			(hide yes)
			(effects
				(font
					(size 1.016 1.016)
					(thickness 0.1524)
				)
			)
		)
		(duplicate_pad_numbers_are_jumpers no)
		(fp_line
			(start -2.7432 -1.4224)
			(end -2.7432 1.4224)
			(stroke
				(width 0.1524)
				(type default)
			)
			(layer "F.SilkS")
		)
		(fp_line
			(start -2.7432 1.4224)
			(end -2.6416 1.4224)
			(stroke
				(width 0.1524)
				(type default)
			)
			(layer "F.SilkS")
		)
		(fp_line
			(start -2.7432 1.4224)
			(end 2.1336 1.4224)
			(stroke
				(width 0.1524)
				(type default)
			)
			(layer "F.SilkS")
		)
		(fp_line
			(start -2.7178 -0.508)
			(end -2.1844 -0.0508)
			(stroke
				(width 0.1524)
				(type default)
			)
			(layer "F.SilkS")
		)
		(fp_line
			(start -2.6289 3.4417)
			(end -2.6289 1.4732)
			(stroke
				(width 0.381)
				(type default)
			)
			(layer "F.SilkS")
		)
		(fp_line
			(start -2.1844 -0.0508)
			(end -2.7178 0.508)
			(stroke
				(width 0.1524)
				(type default)
			)
			(layer "F.SilkS")
		)
		(fp_line
			(start 2.1336 -1.4224)
			(end -2.7432 -1.4224)
			(stroke
				(width 0.1524)
				(type default)
			)
			(layer "F.SilkS")
		)
		(fp_line
			(start 2.1336 1.4224)
			(end 2.1336 -1.4224)
			(stroke
				(width 0.1524)
				(type default)
			)
			(layer "F.SilkS")
		)
		(fp_poly
			(pts
				(xy -2.2098 -1.4224) (xy -2.2098 1.4224) (xy 2.2098 1.4224) (xy 2.2098 -1.4224)
			)
			(stroke
				(width 0)
				(type default)
			)
			(fill yes)
			(layer "F.SilkS")
		)
		(fp_rect
			(start -2.450084 2.999994)
			(end 2.450084 -2.999994)
			(stroke
				(width 0)
				(type default)
			)
			(fill no)
			(layer "F.CrtYd")
		)
		(fp_poly
			(pts
				(xy -2.8194 3.6322) (xy -2.8194 -3.6322) (xy 2.8194 -3.6322) (xy 2.8194 1.18364) (xy 2.450084 1.18364)
				(xy 2.450084 -2.999994) (xy -2.450084 -2.999994) (xy -2.450084 2.999994) (xy 2.450084 2.999994)
				(xy 2.450084 1.18618) (xy 2.8194 1.18618) (xy 2.8194 3.6322)
			)
			(stroke
				(width 0)
				(type default)
			)
			(fill no)
			(layer "F.CrtYd")
		)
		(fp_rect
			(start -2.8194 3.6322)
			(end 2.8194 -3.6322)
			(stroke
				(width 0)
				(type default)
			)
			(fill no)
			(layer "F.Fab")
		)
		(pad "1" smd rect
			(at -1.905 2.54)
			(size 0.635 1.651)
			(layers "F.Cu" "F.Mask" "F.Paste")
			(net "P12V_B")
		)
		(pad "2" smd rect
			(at -0.635 2.54)
			(size 0.635 1.651)
			(layers "F.Cu" "F.Mask" "F.Paste")
			(net "P12V_B")
		)
		(pad "3" smd rect
			(at 0.635 2.54)
			(size 0.635 1.651)
			(layers "F.Cu" "F.Mask" "F.Paste")
			(net "P12V_B")
		)
		(pad "4" smd rect
			(at 1.905 2.54)
			(size 0.635 1.651)
			(layers "F.Cu" "F.Mask" "F.Paste")
			(net "SW_HDD_N6")
		)
		(pad "5" smd rect
			(at 1.905 -2.54)
			(size 0.635 1.651)
			(layers "F.Cu" "F.Mask" "F.Paste")
			(net "P12V_HDD6")
		)
		(pad "6" smd rect
			(at 0.635 -2.54)
			(size 0.635 1.651)
			(layers "F.Cu" "F.Mask" "F.Paste")
			(net "P12V_HDD6")
		)
		(pad "7" smd rect
			(at -0.635 -2.54)
			(size 0.635 1.651)
			(layers "F.Cu" "F.Mask" "F.Paste")
			(net "P12V_HDD6")
		)
		(pad "8" smd rect
			(at -1.905 -2.54)
			(size 0.635 1.651)
			(layers "F.Cu" "F.Mask" "F.Paste")
			(net "P12V_HDD6")
		)
	)
	(footprint ""
		(layer "F.Cu")
		(at 211.95538 -247.88622)
		(property "Reference" "R42"
			(at 0 0 0)
			(layer "F.SilkS")
			(hide yes)
			(effects
				(font
					(size 1.27 1.27)
				)
			)
		)
		(property "Value" "4K7R2F-GP"
			(at 0.064008 -3.993896 0)
			(unlocked yes)
			(layer "F.Fab")
			(hide yes)
			(effects
				(font
					(size 1.016 1.016)
					(thickness 0.1524)
				)
			)
		)
		(property "Device Type" "R402H16"
			(at 0.064008 -5.517896 0)
			(unlocked yes)
			(layer "F.Fab")
			(hide yes)
			(effects
				(font
					(size 1.016 1.016)
					(thickness 0.1524)
				)
			)
		)
		(duplicate_pad_numbers_are_jumpers no)
		(fp_line
			(start -0.508 -0.9398)
			(end -0.508 0.9398)
			(stroke
				(width 0.1524)
				(type default)
			)
			(layer "F.SilkS")
		)
		(fp_line
			(start 0.508 -0.9398)
			(end -0.508 -0.9398)
			(stroke
				(width 0.1524)
				(type default)
			)
			(layer "F.SilkS")
		)
		(fp_rect
			(start -0.508 0.9398)
			(end 0.508 -0.9398)
			(stroke
				(width 0)
				(type default)
			)
			(fill no)
			(layer "F.CrtYd")
		)
		(fp_rect
			(start -0.508 0.9398)
			(end 0.508 -0.9398)
			(stroke
				(width 0)
				(type default)
			)
			(fill no)
			(layer "F.Fab")
		)
		(pad "1" smd custom
			(at 0 -0.4445)
			(size 0.1397 0.1397)
			(layers "F.Cu" "F.Mask" "F.Paste")
			(net "P3V3_STBY_B")
			(options
				(clearance outline)
				(anchor circle)
			)
			(primitives
				(gr_poly
					(pts
						(arc
							(start -0.1778 -0.2794)
							(mid -0.249642 -0.249642)
							(end -0.2794 -0.1778)
						)
						(arc
							(start -0.2794 0.1778)
							(mid -0.249642 0.249642)
							(end -0.1778 0.2794)
						)
						(arc
							(start 0.1778 0.2794)
							(mid 0.249642 0.249642)
							(end 0.2794 0.1778)
						)
						(arc
							(start 0.2794 -0.1778)
							(mid 0.249642 -0.249642)
							(end 0.1778 -0.2794)
						)
					)
					(width 0)
					(fill yes)
				)
			)
		)
		(pad "2" smd custom
			(at 0 0.4445)
			(size 0.1397 0.1397)
			(layers "F.Cu" "F.Mask" "F.Paste")
			(net "IO_EXP4_A1")
			(options
				(clearance outline)
				(anchor circle)
			)
			(primitives
				(gr_poly
					(pts
						(arc
							(start -0.1778 -0.2794)
							(mid -0.249642 -0.249642)
							(end -0.2794 -0.1778)
						)
						(arc
							(start -0.2794 0.1778)
							(mid -0.249642 0.249642)
							(end -0.1778 0.2794)
						)
						(arc
							(start 0.1778 0.2794)
							(mid 0.249642 0.249642)
							(end 0.2794 0.1778)
						)
						(arc
							(start 0.2794 -0.1778)
							(mid 0.249642 -0.249642)
							(end 0.1778 -0.2794)
						)
					)
					(width 0)
					(fill yes)
				)
			)
		)
	)
	(footprint ""
		(layer "F.Cu")
		(at 463.042 -246.761 180)
		(property "Reference" "R328"
			(at 0 0 180)
			(layer "F.SilkS")
			(hide yes)
			(effects
				(font
					(size 1.27 1.27)
				)
			)
		)
		(property "Value" "4K7R2J-2-GP"
			(at 0.064008 -3.993896 180)
			(unlocked yes)
			(layer "F.Fab")
			(hide yes)
			(effects
				(font
					(size 1.016 1.016)
					(thickness 0.1524)
				)
			)
		)
		(property "Device Type" "R402H16"
			(at 0.064008 -5.517896 180)
			(unlocked yes)
			(layer "F.Fab")
			(hide yes)
			(effects
				(font
					(size 1.016 1.016)
					(thickness 0.1524)
				)
			)
		)
		(duplicate_pad_numbers_are_jumpers no)
		(fp_line
			(start 0.508 -0.9398)
			(end -0.508 -0.9398)
			(stroke
				(width 0.1524)
				(type default)
			)
			(layer "F.SilkS")
		)
		(fp_line
			(start -0.508 -0.9398)
			(end -0.508 0.9398)
			(stroke
				(width 0.1524)
				(type default)
			)
			(layer "F.SilkS")
		)
		(fp_rect
			(start -0.508 0.9398)
			(end 0.508 -0.9398)
			(stroke
				(width 0)
				(type default)
			)
			(fill no)
			(layer "F.CrtYd")
		)
		(fp_rect
			(start -0.508 0.9398)
			(end 0.508 -0.9398)
			(stroke
				(width 0)
				(type default)
			)
			(fill no)
			(layer "F.Fab")
		)
		(pad "1" smd custom
			(at 0 -0.4445 180)
			(size 0.1397 0.1397)
			(layers "F.Cu" "F.Mask" "F.Paste")
			(net "P12V_B")
			(options
				(clearance outline)
				(anchor circle)
			)
			(primitives
				(gr_poly
					(pts
						(arc
							(start -0.1778 -0.2794)
							(mid -0.249642 -0.249642)
							(end -0.2794 -0.1778)
						)
						(arc
							(start -0.2794 0.1778)
							(mid -0.249642 0.249642)
							(end -0.1778 0.2794)
						)
						(arc
							(start 0.1778 0.2794)
							(mid 0.249642 0.249642)
							(end 0.2794 0.1778)
						)
						(arc
							(start 0.2794 -0.1778)
							(mid 0.249642 -0.249642)
							(end 0.1778 -0.2794)
						)
					)
					(width 0)
					(fill yes)
				)
			)
		)
		(pad "2" smd custom
			(at 0 0.4445 180)
			(size 0.1397 0.1397)
			(layers "F.Cu" "F.Mask" "F.Paste")
			(net "SW_HDD_R10")
			(options
				(clearance outline)
				(anchor circle)
			)
			(primitives
				(gr_poly
					(pts
						(arc
							(start -0.1778 -0.2794)
							(mid -0.249642 -0.249642)
							(end -0.2794 -0.1778)
						)
						(arc
							(start -0.2794 0.1778)
							(mid -0.249642 0.249642)
							(end -0.1778 0.2794)
						)
						(arc
							(start 0.1778 0.2794)
							(mid 0.249642 0.249642)
							(end 0.2794 0.1778)
						)
						(arc
							(start 0.2794 -0.1778)
							(mid 0.249642 -0.249642)
							(end 0.1778 -0.2794)
						)
					)
					(width 0)
					(fill yes)
				)
			)
		)
	)
	(footprint ""
		(layer "F.Cu")
		(at 475.742 -256.286 180)
		(property "Reference" "Q42"
			(at 0 0 180)
			(layer "F.SilkS")
			(hide yes)
			(effects
				(font
					(size 1.27 1.27)
				)
			)
		)
		(property "Value" "AO4406AL-GP"
			(at -3.707384 -1.5367 180)
			(unlocked yes)
			(layer "F.Fab")
			(hide yes)
			(effects
				(font
					(size 1.016 1.016)
					(thickness 0.1524)
				)
			)
		)
		(property "Device Type" "SOIC8H69"
			(at -3.707384 -3.0607 180)
			(unlocked yes)
			(layer "F.Fab")
			(hide yes)
			(effects
				(font
					(size 1.016 1.016)
					(thickness 0.1524)
				)
			)
		)
		(duplicate_pad_numbers_are_jumpers no)
		(fp_line
			(start 2.1336 1.4224)
			(end 2.1336 -1.4224)
			(stroke
				(width 0.1524)
				(type default)
			)
			(layer "F.SilkS")
		)
		(fp_line
			(start 2.1336 -1.4224)
			(end -2.7432 -1.4224)
			(stroke
				(width 0.1524)
				(type default)
			)
			(layer "F.SilkS")
		)
		(fp_line
			(start -2.1844 -0.0508)
			(end -2.7178 0.508)
			(stroke
				(width 0.1524)
				(type default)
			)
			(layer "F.SilkS")
		)
		(fp_line
			(start -2.6289 3.4417)
			(end -2.6289 1.4732)
			(stroke
				(width 0.381)
				(type default)
			)
			(layer "F.SilkS")
		)
		(fp_line
			(start -2.7178 -0.508)
			(end -2.1844 -0.0508)
			(stroke
				(width 0.1524)
				(type default)
			)
			(layer "F.SilkS")
		)
		(fp_line
			(start -2.7432 1.4224)
			(end 2.1336 1.4224)
			(stroke
				(width 0.1524)
				(type default)
			)
			(layer "F.SilkS")
		)
		(fp_line
			(start -2.7432 1.4224)
			(end -2.6416 1.4224)
			(stroke
				(width 0.1524)
				(type default)
			)
			(layer "F.SilkS")
		)
		(fp_line
			(start -2.7432 -1.4224)
			(end -2.7432 1.4224)
			(stroke
				(width 0.1524)
				(type default)
			)
			(layer "F.SilkS")
		)
		(fp_poly
			(pts
				(xy -2.2098 -1.4224) (xy -2.2098 1.4224) (xy 2.2098 1.4224) (xy 2.2098 -1.4224)
			)
			(stroke
				(width 0)
				(type default)
			)
			(fill yes)
			(layer "F.SilkS")
		)
		(fp_rect
			(start -2.450084 2.999994)
			(end 2.450084 -2.999994)
			(stroke
				(width 0)
				(type default)
			)
			(fill no)
			(layer "F.CrtYd")
		)
		(fp_poly
			(pts
				(xy -2.8194 3.6322) (xy -2.8194 -3.6322) (xy 2.8194 -3.6322) (xy 2.8194 1.18364) (xy 2.450084 1.18364)
				(xy 2.450084 -2.999994) (xy -2.450084 -2.999994) (xy -2.450084 2.999994) (xy 2.450084 2.999994)
				(xy 2.450084 1.18618) (xy 2.8194 1.18618) (xy 2.8194 3.6322)
			)
			(stroke
				(width 0)
				(type default)
			)
			(fill no)
			(layer "F.CrtYd")
		)
		(fp_rect
			(start -2.8194 3.6322)
			(end 2.8194 -3.6322)
			(stroke
				(width 0)
				(type default)
			)
			(fill no)
			(layer "F.Fab")
		)
		(pad "1" smd rect
			(at -1.905 2.54 180)
			(size 0.635 1.651)
			(layers "F.Cu" "F.Mask" "F.Paste")
			(net "P5V_HDD11")
		)
		(pad "2" smd rect
			(at -0.635 2.54 180)
			(size 0.635 1.651)
			(layers "F.Cu" "F.Mask" "F.Paste")
			(net "P5V_HDD11")
		)
		(pad "3" smd rect
			(at 0.635 2.54 180)
			(size 0.635 1.651)
			(layers "F.Cu" "F.Mask" "F.Paste")
			(net "P5V_HDD11")
		)
		(pad "4" smd rect
			(at 1.905 2.54 180)
			(size 0.635 1.651)
			(layers "F.Cu" "F.Mask" "F.Paste")
			(net "SW_HDD_P11")
		)
		(pad "5" smd rect
			(at 1.905 -2.54 180)
			(size 0.635 1.651)
			(layers "F.Cu" "F.Mask" "F.Paste")
			(net "P5V_B_3")
		)
		(pad "6" smd rect
			(at 0.635 -2.54 180)
			(size 0.635 1.651)
			(layers "F.Cu" "F.Mask" "F.Paste")
			(net "P5V_B_3")
		)
		(pad "7" smd rect
			(at -0.635 -2.54 180)
			(size 0.635 1.651)
			(layers "F.Cu" "F.Mask" "F.Paste")
			(net "P5V_B_3")
		)
		(pad "8" smd rect
			(at -1.905 -2.54 180)
			(size 0.635 1.651)
			(layers "F.Cu" "F.Mask" "F.Paste")
			(net "P5V_B_3")
		)
	)
	(footprint ""
		(layer "F.Cu")
		(at 247.15978 -211.690712)
		(property "Reference" "R110"
			(at 0 0 0)
			(layer "F.SilkS")
			(hide yes)
			(effects
				(font
					(size 1.27 1.27)
				)
			)
		)
		(property "Value" "0R2J-2-GP"
			(at 0.064008 -3.993896 0)
			(unlocked yes)
			(layer "F.Fab")
			(hide yes)
			(effects
				(font
					(size 1.016 1.016)
					(thickness 0.1524)
				)
			)
		)
		(property "Device Type" "R402H16"
			(at 0.064008 -5.517896 0)
			(unlocked yes)
			(layer "F.Fab")
			(hide yes)
			(effects
				(font
					(size 1.016 1.016)
					(thickness 0.1524)
				)
			)
		)
		(duplicate_pad_numbers_are_jumpers no)
		(fp_line
			(start -0.508 -0.9398)
			(end -0.508 0.9398)
			(stroke
				(width 0.1524)
				(type default)
			)
			(layer "F.SilkS")
		)
		(fp_line
			(start 0.508 -0.9398)
			(end -0.508 -0.9398)
			(stroke
				(width 0.1524)
				(type default)
			)
			(layer "F.SilkS")
		)
		(fp_rect
			(start -0.508 0.9398)
			(end 0.508 -0.9398)
			(stroke
				(width 0)
				(type default)
			)
			(fill no)
			(layer "F.CrtYd")
		)
		(fp_rect
			(start -0.508 0.9398)
			(end 0.508 -0.9398)
			(stroke
				(width 0)
				(type default)
			)
			(fill no)
			(layer "F.Fab")
		)
		(pad "1" smd custom
			(at 0 -0.4445)
			(size 0.1397 0.1397)
			(layers "F.Cu" "F.Mask" "F.Paste")
			(net "EEPROM_SDA")
			(options
				(clearance outline)
				(anchor circle)
			)
			(primitives
				(gr_poly
					(pts
						(arc
							(start -0.1778 -0.2794)
							(mid -0.249642 -0.249642)
							(end -0.2794 -0.1778)
						)
						(arc
							(start -0.2794 0.1778)
							(mid -0.249642 0.249642)
							(end -0.1778 0.2794)
						)
						(arc
							(start 0.1778 0.2794)
							(mid 0.249642 0.249642)
							(end 0.2794 0.1778)
						)
						(arc
							(start 0.2794 -0.1778)
							(mid 0.249642 -0.249642)
							(end 0.1778 -0.2794)
						)
					)
					(width 0)
					(fill yes)
				)
			)
		)
		(pad "2" smd custom
			(at 0 0.4445)
			(size 0.1397 0.1397)
			(layers "F.Cu" "F.Mask" "F.Paste")
			(net "I2C_DPB_B_SDA_BUF")
			(options
				(clearance outline)
				(anchor circle)
			)
			(primitives
				(gr_poly
					(pts
						(arc
							(start -0.1778 -0.2794)
							(mid -0.249642 -0.249642)
							(end -0.2794 -0.1778)
						)
						(arc
							(start -0.2794 0.1778)
							(mid -0.249642 0.249642)
							(end -0.1778 0.2794)
						)
						(arc
							(start 0.1778 0.2794)
							(mid 0.249642 0.249642)
							(end 0.2794 0.1778)
						)
						(arc
							(start 0.2794 -0.1778)
							(mid 0.249642 -0.249642)
							(end 0.1778 -0.2794)
						)
					)
					(width 0)
					(fill yes)
				)
			)
		)
	)
	(footprint ""
		(layer "F.Cu")
		(at 20.447 -249.555 180)
		(property "Reference" "Q191"
			(at 0 0 180)
			(layer "F.SilkS")
			(hide yes)
			(effects
				(font
					(size 1.27 1.27)
				)
			)
		)
		(property "Value" "2N7002KDW-GP"
			(at -2.3622 -8.2042 180)
			(unlocked yes)
			(layer "F.Fab")
			(hide yes)
			(effects
				(font
					(size 1.016 1.016)
					(thickness 0.1524)
				)
			)
		)
		(property "Device Type" "SOT-363H44"
			(at -2.3622 -10.1092 180)
			(unlocked yes)
			(layer "F.Fab")
			(hide yes)
			(effects
				(font
					(size 1.016 1.016)
					(thickness 0.1524)
				)
			)
		)
		(duplicate_pad_numbers_are_jumpers no)
		(fp_line
			(start 1.4478 1.7018)
			(end 1.4478 -1.7018)
			(stroke
				(width 0.1524)
				(type default)
			)
			(layer "F.SilkS")
		)
		(fp_line
			(start 1.4478 -1.7018)
			(end -1.4478 -1.7018)
			(stroke
				(width 0.1524)
				(type default)
			)
			(layer "F.SilkS")
		)
		(fp_line
			(start -1.27 1.524)
			(end -1.27 0.6604)
			(stroke
				(width 0.4826)
				(type default)
			)
			(layer "F.SilkS")
		)
		(fp_line
			(start -1.4478 1.7018)
			(end 1.4478 1.7018)
			(stroke
				(width 0.1524)
				(type default)
			)
			(layer "F.SilkS")
		)
		(fp_line
			(start -1.4478 -1.7018)
			(end -1.4478 1.7018)
			(stroke
				(width 0.1524)
				(type default)
			)
			(layer "F.SilkS")
		)
		(fp_poly
			(pts
				(xy -1.524 -1.778) (xy 1.524 -1.778) (xy 1.524 1.778) (xy -1.524 1.778)
			)
			(stroke
				(width 0)
				(type default)
			)
			(fill no)
			(layer "F.CrtYd")
		)
		(fp_poly
			(pts
				(xy -1.524 -1.778) (xy 1.524 -1.778) (xy 1.524 1.778) (xy -1.524 1.778)
			)
			(stroke
				(width 0)
				(type default)
			)
			(fill no)
			(layer "F.Fab")
		)
		(pad "1" smd rect
			(at -0.65024 0.9398 180)
			(size 0.4064 1.016)
			(layers "F.Cu" "F.Mask" "F.Paste")
			(net "GND")
		)
		(pad "2" smd rect
			(at 0 0.9398 180)
			(size 0.4064 1.016)
			(layers "F.Cu" "F.Mask" "F.Paste")
			(net "SW_PWR_R_HDD0")
		)
		(pad "3" smd rect
			(at 0.65024 0.9398 180)
			(size 0.4064 1.016)
			(layers "F.Cu" "F.Mask" "F.Paste")
			(net "SW_HDD_P0")
		)
		(pad "4" smd rect
			(at 0.65024 -0.9398 180)
			(size 0.4064 1.016)
			(layers "F.Cu" "F.Mask" "F.Paste")
			(net "GND")
		)
		(pad "5" smd rect
			(at 0 -0.9398 180)
			(size 0.4064 1.016)
			(layers "F.Cu" "F.Mask" "F.Paste")
			(net "SW_HDD_G0")
		)
		(pad "6" smd rect
			(at -0.65024 -0.9398 180)
			(size 0.4064 1.016)
			(layers "F.Cu" "F.Mask" "F.Paste")
			(net "SW_HDD_R0")
		)
	)
	(footprint ""
		(layer "F.Cu")
		(at 483.300024 -258.910074 -90)
		(property "Reference" "HDDSAS11"
			(at 0 0 270)
			(layer "F.SilkS")
			(hide yes)
			(effects
				(font
					(size 1.27 1.27)
				)
			)
		)
		(property "Value" "SKT-SAS15P-14P-45-GP"
			(at -20.7645 -8.9789 270)
			(unlocked yes)
			(layer "F.Fab")
			(hide yes)
			(effects
				(font
					(size 1.016 1.016)
					(thickness 0.1524)
				)
			)
		)
		(property "Device Type" "10120818-001C-TRLF"
			(at -20.7645 -10.5029 270)
			(unlocked yes)
			(layer "F.Fab")
			(hide yes)
			(effects
				(font
					(size 1.016 1.016)
					(thickness 0.1524)
				)
			)
		)
		(duplicate_pad_numbers_are_jumpers no)
		(fp_line
			(start 1.651 4.2926)
			(end 1.651 3.0099)
			(stroke
				(width 0.1524)
				(type default)
			)
			(layer "F.SilkS")
		)
		(fp_line
			(start 8.509 4.2926)
			(end 1.651 4.2926)
			(stroke
				(width 0.1524)
				(type default)
			)
			(layer "F.SilkS")
		)
		(fp_line
			(start -23.4188 3.0099)
			(end -23.4188 -3.2512)
			(stroke
				(width 0.1524)
				(type default)
			)
			(layer "F.SilkS")
		)
		(fp_line
			(start 1.651 3.0099)
			(end -23.4188 3.0099)
			(stroke
				(width 0.1524)
				(type default)
			)
			(layer "F.SilkS")
		)
		(fp_line
			(start 8.509 3.0099)
			(end 8.509 4.2926)
			(stroke
				(width 0.1524)
				(type default)
			)
			(layer "F.SilkS")
		)
		(fp_line
			(start 23.4188 3.0099)
			(end 8.509 3.0099)
			(stroke
				(width 0.1524)
				(type default)
			)
			(layer "F.SilkS")
		)
		(fp_line
			(start -23.4188 -3.2512)
			(end 23.4188 -3.2512)
			(stroke
				(width 0.1524)
				(type default)
			)
			(layer "F.SilkS")
		)
		(fp_line
			(start 23.4188 -3.2512)
			(end 23.4188 3.0099)
			(stroke
				(width 0.1524)
				(type default)
			)
			(layer "F.SilkS")
		)
		(fp_line
			(start 15.5067 -3.3401)
			(end 16.2687 -3.3401)
			(stroke
				(width 0.3302)
				(type default)
			)
			(layer "F.SilkS")
		)
		(fp_poly
			(pts
				(xy 15.868904 -3.230372) (xy 16.503904 -3.865372) (xy 15.233904 -3.865372)
			)
			(stroke
				(width 0)
				(type default)
			)
			(fill yes)
			(layer "F.SilkS")
		)
		(fp_poly
			(pts
				(xy -22.8727 -2.7559) (xy 22.8727 -2.7559) (xy 22.8727 2.7559) (xy 8.255 2.7559) (xy 8.255 3.5179)
				(xy 1.905 3.5179) (xy 1.905 2.7559) (xy -22.8727 2.7559)
			)
			(stroke
				(width 0)
				(type default)
			)
			(fill no)
			(layer "F.CrtYd")
		)
		(fp_poly
			(pts
				(xy 1.397 4.5466) (xy 1.397 3.2639) (xy -23.6728 3.2639) (xy -23.6728 -3.5052) (xy 23.6728 -3.5052)
				(xy 23.6728 -0.00635) (xy 22.8727 -0.00635) (xy 22.8727 -2.7559) (xy -22.8727 -2.7559) (xy -22.8727 2.7559)
				(xy 1.905 2.7559) (xy 1.905 3.5179) (xy 8.255 3.5179) (xy 8.255 2.7559) (xy 22.8727 2.7559) (xy 22.8727 0.00635)
				(xy 23.6728 0.00635) (xy 23.6728 3.2639) (xy 8.763 3.2639) (xy 8.763 4.5466)
			)
			(stroke
				(width 0)
				(type default)
			)
			(fill no)
			(layer "F.CrtYd")
		)
		(fp_poly
			(pts
				(xy 1.397 4.5466) (xy 1.397 3.2639) (xy -23.6728 3.2639) (xy -23.6728 -3.5052) (xy 23.6728 -3.5052)
				(xy 23.6728 3.2639) (xy 8.763 3.2639) (xy 8.763 4.5466)
			)
			(stroke
				(width 0)
				(type default)
			)
			(fill no)
			(layer "F.Fab")
		)
		(pad "" np_thru_hole circle
			(at -18.874994 0 270)
			(size 0.254 0.254)
			(drill 1.3462)
			(layers "*.Cu" "*.Mask")
			(clearance 0.9017)
			(thermal_gap 0.9017)
		)
		(pad "" np_thru_hole circle
			(at 18.874994 0 270)
			(size 0.254 0.254)
			(drill 0.9398)
			(layers "*.Cu" "*.Mask")
			(clearance 0.6985)
			(thermal_gap 0.6985)
		)
		(pad "G1" smd rect
			(at 21.874988 0 270)
			(size 2.5908 2.5908)
			(layers "F.Cu" "F.Mask" "F.Paste")
			(net "GND")
		)
		(pad "G2" smd rect
			(at -21.874988 0 270)
			(size 2.5908 2.5908)
			(layers "F.Cu" "F.Mask" "F.Paste")
			(net "GND")
		)
		(pad "P1" smd rect
			(at 1.905 -1.82499 270)
			(size 0.6096 2.3622)
			(layers "F.Cu" "F.Mask" "F.Paste")
			(net "Net_1749")
		)
		(pad "P2" smd rect
			(at 0.635 -1.82499 270)
			(size 0.6096 2.3622)
			(layers "F.Cu" "F.Mask" "F.Paste")
			(net "Net_1750")
		)
		(pad "P3" smd rect
			(at -0.635 -1.82499 270)
			(size 0.6096 2.3622)
			(layers "F.Cu" "F.Mask" "F.Paste")
			(net "Net_1751")
		)
		(pad "P4" smd rect
			(at -1.905 -1.82499 270)
			(size 0.6096 2.3622)
			(layers "F.Cu" "F.Mask" "F.Paste")
			(net "GND")
		)
		(pad "P5" smd rect
			(at -3.175 -1.82499 270)
			(size 0.6096 2.3622)
			(layers "F.Cu" "F.Mask" "F.Paste")
			(net "HDD_PRSNT_11")
		)
		(pad "P6" smd rect
			(at -4.445 -1.82499 270)
			(size 0.6096 2.3622)
			(layers "F.Cu" "F.Mask" "F.Paste")
			(net "GND")
		)
		(pad "P7" smd rect
			(at -5.715 -1.82499 270)
			(size 0.6096 2.3622)
			(layers "F.Cu" "F.Mask" "F.Paste")
			(net "5V_PRE_11")
		)
		(pad "P8" smd rect
			(at -6.985 -1.82499 270)
			(size 0.6096 2.3622)
			(layers "F.Cu" "F.Mask" "F.Paste")
			(net "P5V_HDD11")
		)
		(pad "P9" smd rect
			(at -8.255 -1.82499 270)
			(size 0.6096 2.3622)
			(layers "F.Cu" "F.Mask" "F.Paste")
			(net "P5V_HDD11")
		)
		(pad "P10" smd rect
			(at -9.525 -1.82499 270)
			(size 0.6096 2.3622)
			(layers "F.Cu" "F.Mask" "F.Paste")
			(net "GND")
		)
		(pad "P11" smd rect
			(at -10.795 -1.82499 270)
			(size 0.6096 2.3622)
			(layers "F.Cu" "F.Mask" "F.Paste")
			(net "ACT_HDD_11")
		)
		(pad "P12" smd rect
			(at -12.065 -1.82499 270)
			(size 0.6096 2.3622)
			(layers "F.Cu" "F.Mask" "F.Paste")
			(net "GND")
		)
		(pad "P13" smd rect
			(at -13.335 -1.82499 270)
			(size 0.6096 2.3622)
			(layers "F.Cu" "F.Mask" "F.Paste")
			(net "12V_PRE_11")
		)
		(pad "P14" smd rect
			(at -14.605 -1.82499 270)
			(size 0.6096 2.3622)
			(layers "F.Cu" "F.Mask" "F.Paste")
			(net "P12V_HDD11")
		)
		(pad "P15" smd rect
			(at -15.875 -1.82499 270)
			(size 0.6096 2.3622)
			(layers "F.Cu" "F.Mask" "F.Paste")
			(net "P12V_HDD11")
		)
		(pad "S1" smd rect
			(at 15.875 -1.82499 270)
			(size 0.6096 2.3622)
			(layers "F.Cu" "F.Mask" "F.Paste")
			(net "GND")
		)
		(pad "S2" smd rect
			(at 14.605 -1.82499 270)
			(size 0.6096 2.3622)
			(layers "F.Cu" "F.Mask" "F.Paste")
			(net "SAS_HDD_RX_P11")
		)
		(pad "S3" smd rect
			(at 13.335 -1.82499 270)
			(size 0.6096 2.3622)
			(layers "F.Cu" "F.Mask" "F.Paste")
			(net "SAS_HDD_RX_N11")
		)
		(pad "S4" smd rect
			(at 12.065 -1.82499 270)
			(size 0.6096 2.3622)
			(layers "F.Cu" "F.Mask" "F.Paste")
			(net "GND")
		)
		(pad "S5" smd rect
			(at 10.795 -1.82499 270)
			(size 0.6096 2.3622)
			(layers "F.Cu" "F.Mask" "F.Paste")
			(net "PHY_DRV_B_TO_SCC_B_11_DN")
		)
		(pad "S6" smd rect
			(at 9.525 -1.82499 270)
			(size 0.6096 2.3622)
			(layers "F.Cu" "F.Mask" "F.Paste")
			(net "PHY_DRV_B_TO_SCC_B_11_DP")
		)
		(pad "S7" smd rect
			(at 8.255 -1.82499 270)
			(size 0.6096 2.3622)
			(layers "F.Cu" "F.Mask" "F.Paste")
			(net "GND")
		)
		(pad "S8" smd rect
			(at 7.480046 2.845054 270)
			(size 0.508 2.3622)
			(layers "F.Cu" "F.Mask" "F.Paste")
			(net "GND")
		)
		(pad "S9" smd rect
			(at 6.679946 2.845054 270)
			(size 0.508 2.3622)
			(layers "F.Cu" "F.Mask" "F.Paste")
			(net "Net_434")
		)
		(pad "S10" smd rect
			(at 5.8801 2.845054 270)
			(size 0.508 2.3622)
			(layers "F.Cu" "F.Mask" "F.Paste")
			(net "Net_326")
		)
		(pad "S11" smd rect
			(at 5.08 2.845054 270)
			(size 0.508 2.3622)
			(layers "F.Cu" "F.Mask" "F.Paste")
			(net "GND")
		)
		(pad "S12" smd rect
			(at 4.2799 2.845054 270)
			(size 0.508 2.3622)
			(layers "F.Cu" "F.Mask" "F.Paste")
			(net "Net_362")
		)
		(pad "S13" smd rect
			(at 3.480054 2.845054 270)
			(size 0.508 2.3622)
			(layers "F.Cu" "F.Mask" "F.Paste")
			(net "Net_398")
		)
		(pad "S14" smd rect
			(at 2.679954 2.845054 270)
			(size 0.508 2.3622)
			(layers "F.Cu" "F.Mask" "F.Paste")
			(net "GND")
		)
		(zone
			(layer "F.Cu")
			(hatch none 0.5)
			(connect_pads
				(clearance 0)
			)
			(min_thickness 0.25)
			(keepout
				(tracks not_allowed)
				(vias allowed)
				(pads allowed)
				(copperpour not_allowed)
				(footprints allowed)
			)
			(placement
				(enabled no)
				(sheetname "")
			)
			(fill
				(thermal_gap 0.5)
				(thermal_bridge_width 0.5)
				(island_removal_mode 0)
			)
			(polygon
				(pts
					(xy 486.957624 -275.648674) (xy 479.883724 -275.648674) (xy 479.883724 -282.582874) (xy 480.988624 -282.582874)
					(xy 480.988624 -278.468074) (xy 485.611424 -278.468074) (xy 485.611424 -282.582874) (xy 486.957624 -282.582874)
				)
			)
		)
		(zone
			(layer "F.Cu")
			(hatch none 0.5)
			(connect_pads
				(clearance 0)
			)
			(min_thickness 0.25)
			(keepout
				(tracks allowed)
				(vias not_allowed)
				(pads allowed)
				(copperpour not_allowed)
				(footprints allowed)
			)
			(placement
				(enabled no)
				(sheetname "")
			)
			(fill
				(thermal_gap 0.5)
				(thermal_bridge_width 0.5)
				(island_removal_mode 0)
			)
			(polygon
				(pts
					(xy 486.957624 -275.648674) (xy 479.883724 -275.648674) (xy 479.883724 -282.582874) (xy 480.988624 -282.582874)
					(xy 480.988624 -278.468074) (xy 485.611424 -278.468074) (xy 485.611424 -282.582874) (xy 486.957624 -282.582874)
				)
			)
		)
		(zone
			(layer "F.Cu")
			(hatch none 0.5)
			(connect_pads
				(clearance 0)
			)
			(min_thickness 0.25)
			(keepout
				(tracks allowed)
				(vias not_allowed)
				(pads allowed)
				(copperpour not_allowed)
				(footprints allowed)
			)
			(placement
				(enabled no)
				(sheetname "")
			)
			(fill
				(thermal_gap 0.5)
				(thermal_bridge_width 0.5)
				(island_removal_mode 0)
			)
			(polygon
				(pts
					(xy 486.957624 -242.171474) (xy 479.883724 -242.171474) (xy 479.883724 -235.237274) (xy 480.988624 -235.237274)
					(xy 480.988624 -239.352074) (xy 485.611424 -239.352074) (xy 485.611424 -235.237274) (xy 486.957624 -235.237274)
				)
			)
		)
		(zone
			(layer "F.Cu")
			(hatch none 0.5)
			(connect_pads
				(clearance 0)
			)
			(min_thickness 0.25)
			(keepout
				(tracks not_allowed)
				(vias allowed)
				(pads allowed)
				(copperpour not_allowed)
				(footprints allowed)
			)
			(placement
				(enabled no)
				(sheetname "")
			)
			(fill
				(thermal_gap 0.5)
				(thermal_bridge_width 0.5)
				(island_removal_mode 0)
			)
			(polygon
				(pts
					(xy 486.957624 -242.171474) (xy 479.883724 -242.171474) (xy 479.883724 -235.237274) (xy 480.988624 -235.237274)
					(xy 480.988624 -239.352074) (xy 485.611424 -239.352074) (xy 485.611424 -235.237274) (xy 486.957624 -235.237274)
				)
			)
		)
		(zone
			(layers "F.Cu" "B.Cu" "In1.Cu" "In2.Cu" "In3.Cu" "In4.Cu" "In5.Cu" "In6.Cu")
			(hatch none 0.5)
			(connect_pads
				(clearance 0)
			)
			(min_thickness 0.25)
			(keepout
				(tracks not_allowed)
				(vias allowed)
				(pads allowed)
				(copperpour not_allowed)
				(footprints allowed)
			)
			(placement
				(enabled no)
				(sheetname "")
			)
			(fill
				(thermal_gap 0.5)
				(thermal_bridge_width 0.5)
				(island_removal_mode 0)
			)
			(polygon
				(pts
					(arc
						(start 484.074724 -240.03508)
						(mid 482.525324 -240.03508)
						(end 484.074724 -240.03508)
					)
				)
			)
		)
		(zone
			(layers "F.Cu" "B.Cu" "In1.Cu" "In2.Cu" "In3.Cu" "In4.Cu" "In5.Cu" "In6.Cu")
			(hatch none 0.5)
			(connect_pads
				(clearance 0)
			)
			(min_thickness 0.25)
			(keepout
				(tracks not_allowed)
				(vias allowed)
				(pads allowed)
				(copperpour not_allowed)
				(footprints allowed)
			)
			(placement
				(enabled no)
				(sheetname "")
			)
			(fill
				(thermal_gap 0.5)
				(thermal_bridge_width 0.5)
				(island_removal_mode 0)
			)
			(polygon
				(pts
					(arc
						(start 484.277924 -277.785068)
						(mid 482.322124 -277.785068)
						(end 484.277924 -277.785068)
					)
				)
			)
		)
	)
	(footprint ""
		(layer "F.Cu")
		(at 114.681 -262.001 -90)
		(property "Reference" "C70"
			(at 0 0 270)
			(layer "F.SilkS")
			(hide yes)
			(effects
				(font
					(size 1.27 1.27)
				)
			)
		)
		(property "Value" "SC10U16V6KX-2GP"
			(at -0.0762 -5.1308 270)
			(unlocked yes)
			(layer "F.Fab")
			(hide yes)
			(effects
				(font
					(size 1.016 1.016)
					(thickness 0.1524)
				)
			)
		)
		(property "Device Type" "C1206H71"
			(at -0.127 -6.6548 270)
			(unlocked yes)
			(layer "F.Fab")
			(hide yes)
			(effects
				(font
					(size 1.016 1.016)
					(thickness 0.1524)
				)
			)
		)
		(duplicate_pad_numbers_are_jumpers no)
		(fp_line
			(start -1.016 2.2352)
			(end -1.016 0.8382)
			(stroke
				(width 0.1524)
				(type default)
			)
			(layer "F.SilkS")
		)
		(fp_line
			(start 1.016 2.2352)
			(end -1.016 2.2352)
			(stroke
				(width 0.1524)
				(type default)
			)
			(layer "F.SilkS")
		)
		(fp_line
			(start 1.016 0.8382)
			(end 1.016 2.2352)
			(stroke
				(width 0.1524)
				(type default)
			)
			(layer "F.SilkS")
		)
		(fp_line
			(start -1.016 -0.8382)
			(end -1.016 -2.2352)
			(stroke
				(width 0.1524)
				(type default)
			)
			(layer "F.SilkS")
		)
		(fp_line
			(start -1.016 -2.2352)
			(end 1.016 -2.2352)
			(stroke
				(width 0.1524)
				(type default)
			)
			(layer "F.SilkS")
		)
		(fp_line
			(start 1.016 -2.2352)
			(end 1.016 -0.8382)
			(stroke
				(width 0.1524)
				(type default)
			)
			(layer "F.SilkS")
		)
		(fp_rect
			(start -1.0922 2.3114)
			(end 1.0922 -2.3114)
			(stroke
				(width 0)
				(type default)
			)
			(fill no)
			(layer "F.CrtYd")
		)
		(fp_poly
			(pts
				(xy 1.0922 -2.3114) (xy 1.0922 2.3114) (xy -1.0922 2.3114) (xy -1.0922 -2.3114)
			)
			(stroke
				(width 0)
				(type default)
			)
			(fill no)
			(layer "F.Fab")
		)
		(pad "1" smd rect
			(at 0 -1.397 270)
			(size 1.651 1.27)
			(layers "F.Cu" "F.Mask" "F.Paste")
			(net "P5V_HDD3")
		)
		(pad "2" smd rect
			(at 0 1.397 270)
			(size 1.651 1.27)
			(layers "F.Cu" "F.Mask" "F.Paste")
			(net "GND")
		)
	)
	(footprint ""
		(layer "F.Cu")
		(at 258.938522 -363.575346 90)
		(property "Reference" "R1034"
			(at 0 0 90)
			(layer "F.SilkS")
			(hide yes)
			(effects
				(font
					(size 1.27 1.27)
				)
			)
		)
		(property "Value" "0R2J-2-GP"
			(at 0.064008 -3.993896 90)
			(unlocked yes)
			(layer "F.Fab")
			(hide yes)
			(effects
				(font
					(size 1.016 1.016)
					(thickness 0.1524)
				)
			)
		)
		(property "Device Type" "R402H16"
			(at 0.064008 -5.517896 90)
			(unlocked yes)
			(layer "F.Fab")
			(hide yes)
			(effects
				(font
					(size 1.016 1.016)
					(thickness 0.1524)
				)
			)
		)
		(duplicate_pad_numbers_are_jumpers no)
		(fp_line
			(start 0.508 -0.9398)
			(end -0.508 -0.9398)
			(stroke
				(width 0.1524)
				(type default)
			)
			(layer "F.SilkS")
		)
		(fp_line
			(start -0.508 -0.9398)
			(end -0.508 0.9398)
			(stroke
				(width 0.1524)
				(type default)
			)
			(layer "F.SilkS")
		)
		(fp_rect
			(start -0.508 0.9398)
			(end 0.508 -0.9398)
			(stroke
				(width 0)
				(type default)
			)
			(fill no)
			(layer "F.CrtYd")
		)
		(fp_rect
			(start -0.508 0.9398)
			(end 0.508 -0.9398)
			(stroke
				(width 0)
				(type default)
			)
			(fill no)
			(layer "F.Fab")
		)
		(pad "1" smd custom
			(at 0 -0.4445 90)
			(size 0.1397 0.1397)
			(layers "F.Cu" "F.Mask" "F.Paste")
			(net "MB3_SPISS_PD")
			(options
				(clearance outline)
				(anchor circle)
			)
			(primitives
				(gr_poly
					(pts
						(arc
							(start -0.1778 -0.2794)
							(mid -0.249642 -0.249642)
							(end -0.2794 -0.1778)
						)
						(arc
							(start -0.2794 0.1778)
							(mid -0.249642 0.249642)
							(end -0.1778 0.2794)
						)
						(arc
							(start 0.1778 0.2794)
							(mid 0.249642 0.249642)
							(end 0.2794 0.1778)
						)
						(arc
							(start 0.2794 -0.1778)
							(mid 0.249642 -0.249642)
							(end 0.1778 -0.2794)
						)
					)
					(width 0)
					(fill yes)
				)
			)
		)
		(pad "2" smd custom
			(at 0 0.4445 90)
			(size 0.1397 0.1397)
			(layers "F.Cu" "F.Mask" "F.Paste")
			(net "AGND_CURRENT_DPB")
			(options
				(clearance outline)
				(anchor circle)
			)
			(primitives
				(gr_poly
					(pts
						(arc
							(start -0.1778 -0.2794)
							(mid -0.249642 -0.249642)
							(end -0.2794 -0.1778)
						)
						(arc
							(start -0.2794 0.1778)
							(mid -0.249642 0.249642)
							(end -0.1778 0.2794)
						)
						(arc
							(start 0.1778 0.2794)
							(mid 0.249642 0.249642)
							(end 0.2794 0.1778)
						)
						(arc
							(start 0.2794 -0.1778)
							(mid 0.249642 -0.249642)
							(end 0.1778 -0.2794)
						)
					)
					(width 0)
					(fill yes)
				)
			)
		)
	)
	(footprint ""
		(layer "F.Cu")
		(at 167.7162 -371.856 90)
		(property "Reference" "R1000"
			(at 0 0 90)
			(layer "F.SilkS")
			(hide yes)
			(effects
				(font
					(size 1.27 1.27)
				)
			)
		)
		(property "Value" "10R2F-L-GP"
			(at 0.064008 -3.993896 90)
			(unlocked yes)
			(layer "F.Fab")
			(hide yes)
			(effects
				(font
					(size 1.016 1.016)
					(thickness 0.1524)
				)
			)
		)
		(property "Device Type" "R402H14"
			(at 0.064008 -5.517896 90)
			(unlocked yes)
			(layer "F.Fab")
			(hide yes)
			(effects
				(font
					(size 1.016 1.016)
					(thickness 0.1524)
				)
			)
		)
		(duplicate_pad_numbers_are_jumpers no)
		(fp_line
			(start 0.508 -0.9398)
			(end -0.508 -0.9398)
			(stroke
				(width 0.1524)
				(type default)
			)
			(layer "F.SilkS")
		)
		(fp_line
			(start -0.508 -0.9398)
			(end -0.508 0.9398)
			(stroke
				(width 0.1524)
				(type default)
			)
			(layer "F.SilkS")
		)
		(fp_rect
			(start -0.508 0.9398)
			(end 0.508 -0.9398)
			(stroke
				(width 0)
				(type default)
			)
			(fill no)
			(layer "F.CrtYd")
		)
		(fp_rect
			(start -0.508 0.9398)
			(end 0.508 -0.9398)
			(stroke
				(width 0)
				(type default)
			)
			(fill no)
			(layer "F.Fab")
		)
		(pad "1" smd custom
			(at 0 -0.4445 90)
			(size 0.1397 0.1397)
			(layers "F.Cu" "F.Mask" "F.Paste")
			(net "MB0_CM_SENSE_R2_N")
			(options
				(clearance outline)
				(anchor circle)
			)
			(primitives
				(gr_poly
					(pts
						(arc
							(start -0.1778 -0.2794)
							(mid -0.249642 -0.249642)
							(end -0.2794 -0.1778)
						)
						(arc
							(start -0.2794 0.1778)
							(mid -0.249642 0.249642)
							(end -0.1778 0.2794)
						)
						(arc
							(start 0.1778 0.2794)
							(mid 0.249642 0.249642)
							(end 0.2794 0.1778)
						)
						(arc
							(start 0.2794 -0.1778)
							(mid 0.249642 -0.249642)
							(end 0.1778 -0.2794)
						)
					)
					(width 0)
					(fill yes)
				)
			)
		)
		(pad "2" smd custom
			(at 0 0.4445 90)
			(size 0.1397 0.1397)
			(layers "F.Cu" "F.Mask" "F.Paste")
			(net "MB0_CM_SENSE_N")
			(options
				(clearance outline)
				(anchor circle)
			)
			(primitives
				(gr_poly
					(pts
						(arc
							(start -0.1778 -0.2794)
							(mid -0.249642 -0.249642)
							(end -0.2794 -0.1778)
						)
						(arc
							(start -0.2794 0.1778)
							(mid -0.249642 0.249642)
							(end -0.1778 0.2794)
						)
						(arc
							(start 0.1778 0.2794)
							(mid 0.249642 0.249642)
							(end 0.2794 0.1778)
						)
						(arc
							(start 0.2794 -0.1778)
							(mid 0.249642 -0.249642)
							(end 0.1778 -0.2794)
						)
					)
					(width 0)
					(fill yes)
				)
			)
		)
	)
	(footprint ""
		(layer "F.Cu")
		(at 458.061568 -97.480628 -90)
		(property "Reference" "R489"
			(at 0 0 270)
			(layer "F.SilkS")
			(hide yes)
			(effects
				(font
					(size 1.27 1.27)
				)
			)
		)
		(property "Value" "4K7R2F-GP"
			(at 0.064008 -3.993896 270)
			(unlocked yes)
			(layer "F.Fab")
			(hide yes)
			(effects
				(font
					(size 1.016 1.016)
					(thickness 0.1524)
				)
			)
		)
		(property "Device Type" "R402H16"
			(at 0.064008 -5.517896 270)
			(unlocked yes)
			(layer "F.Fab")
			(hide yes)
			(effects
				(font
					(size 1.016 1.016)
					(thickness 0.1524)
				)
			)
		)
		(duplicate_pad_numbers_are_jumpers no)
		(fp_line
			(start -0.508 -0.9398)
			(end -0.508 0.9398)
			(stroke
				(width 0.1524)
				(type default)
			)
			(layer "F.SilkS")
		)
		(fp_line
			(start 0.508 -0.9398)
			(end -0.508 -0.9398)
			(stroke
				(width 0.1524)
				(type default)
			)
			(layer "F.SilkS")
		)
		(fp_rect
			(start -0.508 0.9398)
			(end 0.508 -0.9398)
			(stroke
				(width 0)
				(type default)
			)
			(fill no)
			(layer "F.CrtYd")
		)
		(fp_rect
			(start -0.508 0.9398)
			(end 0.508 -0.9398)
			(stroke
				(width 0)
				(type default)
			)
			(fill no)
			(layer "F.Fab")
		)
		(pad "1" smd custom
			(at 0 -0.4445 270)
			(size 0.1397 0.1397)
			(layers "F.Cu" "F.Mask" "F.Paste")
			(net "DRIVE_B_23_ACT")
			(options
				(clearance outline)
				(anchor circle)
			)
			(primitives
				(gr_poly
					(pts
						(arc
							(start -0.1778 -0.2794)
							(mid -0.249642 -0.249642)
							(end -0.2794 -0.1778)
						)
						(arc
							(start -0.2794 0.1778)
							(mid -0.249642 0.249642)
							(end -0.1778 0.2794)
						)
						(arc
							(start 0.1778 0.2794)
							(mid 0.249642 0.249642)
							(end 0.2794 0.1778)
						)
						(arc
							(start 0.2794 -0.1778)
							(mid 0.249642 -0.249642)
							(end 0.1778 -0.2794)
						)
					)
					(width 0)
					(fill yes)
				)
			)
		)
		(pad "2" smd custom
			(at 0 0.4445 270)
			(size 0.1397 0.1397)
			(layers "F.Cu" "F.Mask" "F.Paste")
			(net "GND")
			(options
				(clearance outline)
				(anchor circle)
			)
			(primitives
				(gr_poly
					(pts
						(arc
							(start -0.1778 -0.2794)
							(mid -0.249642 -0.249642)
							(end -0.2794 -0.1778)
						)
						(arc
							(start -0.2794 0.1778)
							(mid -0.249642 0.249642)
							(end -0.1778 0.2794)
						)
						(arc
							(start 0.1778 0.2794)
							(mid 0.249642 0.249642)
							(end 0.2794 0.1778)
						)
						(arc
							(start 0.2794 -0.1778)
							(mid 0.249642 -0.249642)
							(end 0.1778 -0.2794)
						)
					)
					(width 0)
					(fill yes)
				)
			)
		)
	)
	(footprint ""
		(layer "F.Cu")
		(at 222.669862 -205.994 -90)
		(property "Reference" "R47"
			(at 0 0 270)
			(layer "F.SilkS")
			(hide yes)
			(effects
				(font
					(size 1.27 1.27)
				)
			)
		)
		(property "Value" "4K7R2F-GP"
			(at 0.064008 -3.993896 270)
			(unlocked yes)
			(layer "F.Fab")
			(hide yes)
			(effects
				(font
					(size 1.016 1.016)
					(thickness 0.1524)
				)
			)
		)
		(property "Device Type" "R402H16"
			(at 0.064008 -5.517896 270)
			(unlocked yes)
			(layer "F.Fab")
			(hide yes)
			(effects
				(font
					(size 1.016 1.016)
					(thickness 0.1524)
				)
			)
		)
		(duplicate_pad_numbers_are_jumpers no)
		(fp_line
			(start -0.508 -0.9398)
			(end -0.508 0.9398)
			(stroke
				(width 0.1524)
				(type default)
			)
			(layer "F.SilkS")
		)
		(fp_line
			(start 0.508 -0.9398)
			(end -0.508 -0.9398)
			(stroke
				(width 0.1524)
				(type default)
			)
			(layer "F.SilkS")
		)
		(fp_rect
			(start -0.508 0.9398)
			(end 0.508 -0.9398)
			(stroke
				(width 0)
				(type default)
			)
			(fill no)
			(layer "F.CrtYd")
		)
		(fp_rect
			(start -0.508 0.9398)
			(end 0.508 -0.9398)
			(stroke
				(width 0)
				(type default)
			)
			(fill no)
			(layer "F.Fab")
		)
		(pad "1" smd custom
			(at 0 -0.4445 270)
			(size 0.1397 0.1397)
			(layers "F.Cu" "F.Mask" "F.Paste")
			(net "P3V3_STBY_B")
			(options
				(clearance outline)
				(anchor circle)
			)
			(primitives
				(gr_poly
					(pts
						(arc
							(start -0.1778 -0.2794)
							(mid -0.249642 -0.249642)
							(end -0.2794 -0.1778)
						)
						(arc
							(start -0.2794 0.1778)
							(mid -0.249642 0.249642)
							(end -0.1778 0.2794)
						)
						(arc
							(start 0.1778 0.2794)
							(mid 0.249642 0.249642)
							(end 0.2794 0.1778)
						)
						(arc
							(start 0.2794 -0.1778)
							(mid 0.249642 -0.249642)
							(end 0.1778 -0.2794)
						)
					)
					(width 0)
					(fill yes)
				)
			)
		)
		(pad "2" smd custom
			(at 0 0.4445 270)
			(size 0.1397 0.1397)
			(layers "F.Cu" "F.Mask" "F.Paste")
			(net "IO_EXP5_A2")
			(options
				(clearance outline)
				(anchor circle)
			)
			(primitives
				(gr_poly
					(pts
						(arc
							(start -0.1778 -0.2794)
							(mid -0.249642 -0.249642)
							(end -0.2794 -0.1778)
						)
						(arc
							(start -0.2794 0.1778)
							(mid -0.249642 0.249642)
							(end -0.1778 0.2794)
						)
						(arc
							(start 0.1778 0.2794)
							(mid 0.249642 0.249642)
							(end 0.2794 0.1778)
						)
						(arc
							(start 0.2794 -0.1778)
							(mid 0.249642 -0.249642)
							(end 0.1778 -0.2794)
						)
					)
					(width 0)
					(fill yes)
				)
			)
		)
	)
	(footprint ""
		(layer "F.Cu")
		(at 117.602 -249.555 90)
		(property "Reference" "R215"
			(at 0 0 90)
			(layer "F.SilkS")
			(hide yes)
			(effects
				(font
					(size 1.27 1.27)
				)
			)
		)
		(property "Value" "4K7R2F-GP"
			(at 0.064008 -3.993896 90)
			(unlocked yes)
			(layer "F.Fab")
			(hide yes)
			(effects
				(font
					(size 1.016 1.016)
					(thickness 0.1524)
				)
			)
		)
		(property "Device Type" "R402H16"
			(at 0.064008 -5.517896 90)
			(unlocked yes)
			(layer "F.Fab")
			(hide yes)
			(effects
				(font
					(size 1.016 1.016)
					(thickness 0.1524)
				)
			)
		)
		(duplicate_pad_numbers_are_jumpers no)
		(fp_line
			(start 0.508 -0.9398)
			(end -0.508 -0.9398)
			(stroke
				(width 0.1524)
				(type default)
			)
			(layer "F.SilkS")
		)
		(fp_line
			(start -0.508 -0.9398)
			(end -0.508 0.9398)
			(stroke
				(width 0.1524)
				(type default)
			)
			(layer "F.SilkS")
		)
		(fp_rect
			(start -0.508 0.9398)
			(end 0.508 -0.9398)
			(stroke
				(width 0)
				(type default)
			)
			(fill no)
			(layer "F.CrtYd")
		)
		(fp_rect
			(start -0.508 0.9398)
			(end 0.508 -0.9398)
			(stroke
				(width 0)
				(type default)
			)
			(fill no)
			(layer "F.Fab")
		)
		(pad "1" smd custom
			(at 0 -0.4445 90)
			(size 0.1397 0.1397)
			(layers "F.Cu" "F.Mask" "F.Paste")
			(net "SW_PWR_R_HDD3")
			(options
				(clearance outline)
				(anchor circle)
			)
			(primitives
				(gr_poly
					(pts
						(arc
							(start -0.1778 -0.2794)
							(mid -0.249642 -0.249642)
							(end -0.2794 -0.1778)
						)
						(arc
							(start -0.2794 0.1778)
							(mid -0.249642 0.249642)
							(end -0.1778 0.2794)
						)
						(arc
							(start 0.1778 0.2794)
							(mid 0.249642 0.249642)
							(end 0.2794 0.1778)
						)
						(arc
							(start 0.2794 -0.1778)
							(mid 0.249642 -0.249642)
							(end 0.1778 -0.2794)
						)
					)
					(width 0)
					(fill yes)
				)
			)
		)
		(pad "2" smd custom
			(at 0 0.4445 90)
			(size 0.1397 0.1397)
			(layers "F.Cu" "F.Mask" "F.Paste")
			(net "GND")
			(options
				(clearance outline)
				(anchor circle)
			)
			(primitives
				(gr_poly
					(pts
						(arc
							(start -0.1778 -0.2794)
							(mid -0.249642 -0.249642)
							(end -0.2794 -0.1778)
						)
						(arc
							(start -0.2794 0.1778)
							(mid -0.249642 0.249642)
							(end -0.1778 0.2794)
						)
						(arc
							(start 0.1778 0.2794)
							(mid 0.249642 0.249642)
							(end 0.2794 0.1778)
						)
						(arc
							(start 0.2794 -0.1778)
							(mid 0.249642 -0.249642)
							(end 0.1778 -0.2794)
						)
					)
					(width 0)
					(fill yes)
				)
			)
		)
	)
	(footprint ""
		(layer "F.Cu")
		(at 185.950098 -258.910074 -90)
		(property "Reference" "HDDSAS5"
			(at 0 0 270)
			(layer "F.SilkS")
			(hide yes)
			(effects
				(font
					(size 1.27 1.27)
				)
			)
		)
		(property "Value" "SKT-SAS15P-14P-45-GP"
			(at -20.7645 -8.9789 270)
			(unlocked yes)
			(layer "F.Fab")
			(hide yes)
			(effects
				(font
					(size 1.016 1.016)
					(thickness 0.1524)
				)
			)
		)
		(property "Device Type" "10120818-001C-TRLF"
			(at -20.7645 -10.5029 270)
			(unlocked yes)
			(layer "F.Fab")
			(hide yes)
			(effects
				(font
					(size 1.016 1.016)
					(thickness 0.1524)
				)
			)
		)
		(duplicate_pad_numbers_are_jumpers no)
		(fp_line
			(start 1.651 4.2926)
			(end 1.651 3.0099)
			(stroke
				(width 0.1524)
				(type default)
			)
			(layer "F.SilkS")
		)
		(fp_line
			(start 8.509 4.2926)
			(end 1.651 4.2926)
			(stroke
				(width 0.1524)
				(type default)
			)
			(layer "F.SilkS")
		)
		(fp_line
			(start -23.4188 3.0099)
			(end -23.4188 -3.2512)
			(stroke
				(width 0.1524)
				(type default)
			)
			(layer "F.SilkS")
		)
		(fp_line
			(start 1.651 3.0099)
			(end -23.4188 3.0099)
			(stroke
				(width 0.1524)
				(type default)
			)
			(layer "F.SilkS")
		)
		(fp_line
			(start 8.509 3.0099)
			(end 8.509 4.2926)
			(stroke
				(width 0.1524)
				(type default)
			)
			(layer "F.SilkS")
		)
		(fp_line
			(start 23.4188 3.0099)
			(end 8.509 3.0099)
			(stroke
				(width 0.1524)
				(type default)
			)
			(layer "F.SilkS")
		)
		(fp_line
			(start -23.4188 -3.2512)
			(end 23.4188 -3.2512)
			(stroke
				(width 0.1524)
				(type default)
			)
			(layer "F.SilkS")
		)
		(fp_line
			(start 23.4188 -3.2512)
			(end 23.4188 3.0099)
			(stroke
				(width 0.1524)
				(type default)
			)
			(layer "F.SilkS")
		)
		(fp_line
			(start 15.5067 -3.3401)
			(end 16.2687 -3.3401)
			(stroke
				(width 0.3302)
				(type default)
			)
			(layer "F.SilkS")
		)
		(fp_poly
			(pts
				(xy 15.868904 -3.230372) (xy 16.503904 -3.865372) (xy 15.233904 -3.865372)
			)
			(stroke
				(width 0)
				(type default)
			)
			(fill yes)
			(layer "F.SilkS")
		)
		(fp_poly
			(pts
				(xy -22.8727 -2.7559) (xy 22.8727 -2.7559) (xy 22.8727 2.7559) (xy 8.255 2.7559) (xy 8.255 3.5179)
				(xy 1.905 3.5179) (xy 1.905 2.7559) (xy -22.8727 2.7559)
			)
			(stroke
				(width 0)
				(type default)
			)
			(fill no)
			(layer "F.CrtYd")
		)
		(fp_poly
			(pts
				(xy 1.397 4.5466) (xy 1.397 3.2639) (xy -23.6728 3.2639) (xy -23.6728 -3.5052) (xy 23.6728 -3.5052)
				(xy 23.6728 -0.00635) (xy 22.8727 -0.00635) (xy 22.8727 -2.7559) (xy -22.8727 -2.7559) (xy -22.8727 2.7559)
				(xy 1.905 2.7559) (xy 1.905 3.5179) (xy 8.255 3.5179) (xy 8.255 2.7559) (xy 22.8727 2.7559) (xy 22.8727 0.00635)
				(xy 23.6728 0.00635) (xy 23.6728 3.2639) (xy 8.763 3.2639) (xy 8.763 4.5466)
			)
			(stroke
				(width 0)
				(type default)
			)
			(fill no)
			(layer "F.CrtYd")
		)
		(fp_poly
			(pts
				(xy 1.397 4.5466) (xy 1.397 3.2639) (xy -23.6728 3.2639) (xy -23.6728 -3.5052) (xy 23.6728 -3.5052)
				(xy 23.6728 3.2639) (xy 8.763 3.2639) (xy 8.763 4.5466)
			)
			(stroke
				(width 0)
				(type default)
			)
			(fill no)
			(layer "F.Fab")
		)
		(pad "" np_thru_hole circle
			(at -18.874994 0 270)
			(size 0.254 0.254)
			(drill 1.3462)
			(layers "*.Cu" "*.Mask")
			(clearance 0.9017)
			(thermal_gap 0.9017)
		)
		(pad "" np_thru_hole circle
			(at 18.874994 0 270)
			(size 0.254 0.254)
			(drill 0.9398)
			(layers "*.Cu" "*.Mask")
			(clearance 0.6985)
			(thermal_gap 0.6985)
		)
		(pad "G1" smd rect
			(at 21.874988 0 270)
			(size 2.5908 2.5908)
			(layers "F.Cu" "F.Mask" "F.Paste")
			(net "GND")
		)
		(pad "G2" smd rect
			(at -21.874988 0 270)
			(size 2.5908 2.5908)
			(layers "F.Cu" "F.Mask" "F.Paste")
			(net "GND")
		)
		(pad "P1" smd rect
			(at 1.905 -1.82499 270)
			(size 0.6096 2.3622)
			(layers "F.Cu" "F.Mask" "F.Paste")
			(net "Net_1604")
		)
		(pad "P2" smd rect
			(at 0.635 -1.82499 270)
			(size 0.6096 2.3622)
			(layers "F.Cu" "F.Mask" "F.Paste")
			(net "Net_1605")
		)
		(pad "P3" smd rect
			(at -0.635 -1.82499 270)
			(size 0.6096 2.3622)
			(layers "F.Cu" "F.Mask" "F.Paste")
			(net "Net_1606")
		)
		(pad "P4" smd rect
			(at -1.905 -1.82499 270)
			(size 0.6096 2.3622)
			(layers "F.Cu" "F.Mask" "F.Paste")
			(net "GND")
		)
		(pad "P5" smd rect
			(at -3.175 -1.82499 270)
			(size 0.6096 2.3622)
			(layers "F.Cu" "F.Mask" "F.Paste")
			(net "HDD_PRSNT_5")
		)
		(pad "P6" smd rect
			(at -4.445 -1.82499 270)
			(size 0.6096 2.3622)
			(layers "F.Cu" "F.Mask" "F.Paste")
			(net "GND")
		)
		(pad "P7" smd rect
			(at -5.715 -1.82499 270)
			(size 0.6096 2.3622)
			(layers "F.Cu" "F.Mask" "F.Paste")
			(net "5V_PRE_5")
		)
		(pad "P8" smd rect
			(at -6.985 -1.82499 270)
			(size 0.6096 2.3622)
			(layers "F.Cu" "F.Mask" "F.Paste")
			(net "P5V_HDD5")
		)
		(pad "P9" smd rect
			(at -8.255 -1.82499 270)
			(size 0.6096 2.3622)
			(layers "F.Cu" "F.Mask" "F.Paste")
			(net "P5V_HDD5")
		)
		(pad "P10" smd rect
			(at -9.525 -1.82499 270)
			(size 0.6096 2.3622)
			(layers "F.Cu" "F.Mask" "F.Paste")
			(net "GND")
		)
		(pad "P11" smd rect
			(at -10.795 -1.82499 270)
			(size 0.6096 2.3622)
			(layers "F.Cu" "F.Mask" "F.Paste")
			(net "ACT_HDD_5")
		)
		(pad "P12" smd rect
			(at -12.065 -1.82499 270)
			(size 0.6096 2.3622)
			(layers "F.Cu" "F.Mask" "F.Paste")
			(net "GND")
		)
		(pad "P13" smd rect
			(at -13.335 -1.82499 270)
			(size 0.6096 2.3622)
			(layers "F.Cu" "F.Mask" "F.Paste")
			(net "12V_PRE_5")
		)
		(pad "P14" smd rect
			(at -14.605 -1.82499 270)
			(size 0.6096 2.3622)
			(layers "F.Cu" "F.Mask" "F.Paste")
			(net "P12V_HDD5")
		)
		(pad "P15" smd rect
			(at -15.875 -1.82499 270)
			(size 0.6096 2.3622)
			(layers "F.Cu" "F.Mask" "F.Paste")
			(net "P12V_HDD5")
		)
		(pad "S1" smd rect
			(at 15.875 -1.82499 270)
			(size 0.6096 2.3622)
			(layers "F.Cu" "F.Mask" "F.Paste")
			(net "GND")
		)
		(pad "S2" smd rect
			(at 14.605 -1.82499 270)
			(size 0.6096 2.3622)
			(layers "F.Cu" "F.Mask" "F.Paste")
			(net "SAS_HDD_RX_P5")
		)
		(pad "S3" smd rect
			(at 13.335 -1.82499 270)
			(size 0.6096 2.3622)
			(layers "F.Cu" "F.Mask" "F.Paste")
			(net "SAS_HDD_RX_N5")
		)
		(pad "S4" smd rect
			(at 12.065 -1.82499 270)
			(size 0.6096 2.3622)
			(layers "F.Cu" "F.Mask" "F.Paste")
			(net "GND")
		)
		(pad "S5" smd rect
			(at 10.795 -1.82499 270)
			(size 0.6096 2.3622)
			(layers "F.Cu" "F.Mask" "F.Paste")
			(net "PHY_DRV_B_TO_SCC_B_5_DN")
		)
		(pad "S6" smd rect
			(at 9.525 -1.82499 270)
			(size 0.6096 2.3622)
			(layers "F.Cu" "F.Mask" "F.Paste")
			(net "PHY_DRV_B_TO_SCC_B_5_DP")
		)
		(pad "S7" smd rect
			(at 8.255 -1.82499 270)
			(size 0.6096 2.3622)
			(layers "F.Cu" "F.Mask" "F.Paste")
			(net "GND")
		)
		(pad "S8" smd rect
			(at 7.480046 2.845054 270)
			(size 0.508 2.3622)
			(layers "F.Cu" "F.Mask" "F.Paste")
			(net "GND")
		)
		(pad "S9" smd rect
			(at 6.679946 2.845054 270)
			(size 0.508 2.3622)
			(layers "F.Cu" "F.Mask" "F.Paste")
			(net "Net_463")
		)
		(pad "S10" smd rect
			(at 5.8801 2.845054 270)
			(size 0.508 2.3622)
			(layers "F.Cu" "F.Mask" "F.Paste")
			(net "Net_355")
		)
		(pad "S11" smd rect
			(at 5.08 2.845054 270)
			(size 0.508 2.3622)
			(layers "F.Cu" "F.Mask" "F.Paste")
			(net "GND")
		)
		(pad "S12" smd rect
			(at 4.2799 2.845054 270)
			(size 0.508 2.3622)
			(layers "F.Cu" "F.Mask" "F.Paste")
			(net "Net_391")
		)
		(pad "S13" smd rect
			(at 3.480054 2.845054 270)
			(size 0.508 2.3622)
			(layers "F.Cu" "F.Mask" "F.Paste")
			(net "Net_427")
		)
		(pad "S14" smd rect
			(at 2.679954 2.845054 270)
			(size 0.508 2.3622)
			(layers "F.Cu" "F.Mask" "F.Paste")
			(net "GND")
		)
		(zone
			(layer "F.Cu")
			(hatch none 0.5)
			(connect_pads
				(clearance 0)
			)
			(min_thickness 0.25)
			(keepout
				(tracks allowed)
				(vias not_allowed)
				(pads allowed)
				(copperpour not_allowed)
				(footprints allowed)
			)
			(placement
				(enabled no)
				(sheetname "")
			)
			(fill
				(thermal_gap 0.5)
				(thermal_bridge_width 0.5)
				(island_removal_mode 0)
			)
			(polygon
				(pts
					(xy 189.607698 -275.648674) (xy 182.533798 -275.648674) (xy 182.533798 -282.582874) (xy 183.638698 -282.582874)
					(xy 183.638698 -278.468074) (xy 188.261498 -278.468074) (xy 188.261498 -282.582874) (xy 189.607698 -282.582874)
				)
			)
		)
		(zone
			(layer "F.Cu")
			(hatch none 0.5)
			(connect_pads
				(clearance 0)
			)
			(min_thickness 0.25)
			(keepout
				(tracks not_allowed)
				(vias allowed)
				(pads allowed)
				(copperpour not_allowed)
				(footprints allowed)
			)
			(placement
				(enabled no)
				(sheetname "")
			)
			(fill
				(thermal_gap 0.5)
				(thermal_bridge_width 0.5)
				(island_removal_mode 0)
			)
			(polygon
				(pts
					(xy 189.607698 -275.648674) (xy 182.533798 -275.648674) (xy 182.533798 -282.582874) (xy 183.638698 -282.582874)
					(xy 183.638698 -278.468074) (xy 188.261498 -278.468074) (xy 188.261498 -282.582874) (xy 189.607698 -282.582874)
				)
			)
		)
		(zone
			(layer "F.Cu")
			(hatch none 0.5)
			(connect_pads
				(clearance 0)
			)
			(min_thickness 0.25)
			(keepout
				(tracks allowed)
				(vias not_allowed)
				(pads allowed)
				(copperpour not_allowed)
				(footprints allowed)
			)
			(placement
				(enabled no)
				(sheetname "")
			)
			(fill
				(thermal_gap 0.5)
				(thermal_bridge_width 0.5)
				(island_removal_mode 0)
			)
			(polygon
				(pts
					(xy 189.607698 -242.171474) (xy 182.533798 -242.171474) (xy 182.533798 -235.237274) (xy 183.638698 -235.237274)
					(xy 183.638698 -239.352074) (xy 188.261498 -239.352074) (xy 188.261498 -235.237274) (xy 189.607698 -235.237274)
				)
			)
		)
		(zone
			(layer "F.Cu")
			(hatch none 0.5)
			(connect_pads
				(clearance 0)
			)
			(min_thickness 0.25)
			(keepout
				(tracks not_allowed)
				(vias allowed)
				(pads allowed)
				(copperpour not_allowed)
				(footprints allowed)
			)
			(placement
				(enabled no)
				(sheetname "")
			)
			(fill
				(thermal_gap 0.5)
				(thermal_bridge_width 0.5)
				(island_removal_mode 0)
			)
			(polygon
				(pts
					(xy 189.607698 -242.171474) (xy 182.533798 -242.171474) (xy 182.533798 -235.237274) (xy 183.638698 -235.237274)
					(xy 183.638698 -239.352074) (xy 188.261498 -239.352074) (xy 188.261498 -235.237274) (xy 189.607698 -235.237274)
				)
			)
		)
		(zone
			(layers "F.Cu" "B.Cu" "In1.Cu" "In2.Cu" "In3.Cu" "In4.Cu" "In5.Cu" "In6.Cu")
			(hatch none 0.5)
			(connect_pads
				(clearance 0)
			)
			(min_thickness 0.25)
			(keepout
				(tracks not_allowed)
				(vias allowed)
				(pads allowed)
				(copperpour not_allowed)
				(footprints allowed)
			)
			(placement
				(enabled no)
				(sheetname "")
			)
			(fill
				(thermal_gap 0.5)
				(thermal_bridge_width 0.5)
				(island_removal_mode 0)
			)
			(polygon
				(pts
					(arc
						(start 186.724798 -240.03508)
						(mid 185.175398 -240.03508)
						(end 186.724798 -240.03508)
					)
				)
			)
		)
		(zone
			(layers "F.Cu" "B.Cu" "In1.Cu" "In2.Cu" "In3.Cu" "In4.Cu" "In5.Cu" "In6.Cu")
			(hatch none 0.5)
			(connect_pads
				(clearance 0)
			)
			(min_thickness 0.25)
			(keepout
				(tracks not_allowed)
				(vias allowed)
				(pads allowed)
				(copperpour not_allowed)
				(footprints allowed)
			)
			(placement
				(enabled no)
				(sheetname "")
			)
			(fill
				(thermal_gap 0.5)
				(thermal_bridge_width 0.5)
				(island_removal_mode 0)
			)
			(polygon
				(pts
					(arc
						(start 186.927998 -277.785068)
						(mid 184.972198 -277.785068)
						(end 186.927998 -277.785068)
					)
				)
			)
		)
	)
	(footprint ""
		(layer "F.Cu")
		(at 133.731 -372.618 90)
		(property "Reference" "R941"
			(at 0 0 90)
			(layer "F.SilkS")
			(hide yes)
			(effects
				(font
					(size 1.27 1.27)
				)
			)
		)
		(property "Value" "10KR2F-2-GP"
			(at 0.064008 -3.993896 90)
			(unlocked yes)
			(layer "F.Fab")
			(hide yes)
			(effects
				(font
					(size 1.016 1.016)
					(thickness 0.1524)
				)
			)
		)
		(property "Device Type" "R402H16"
			(at 0.064008 -5.517896 90)
			(unlocked yes)
			(layer "F.Fab")
			(hide yes)
			(effects
				(font
					(size 1.016 1.016)
					(thickness 0.1524)
				)
			)
		)
		(duplicate_pad_numbers_are_jumpers no)
		(fp_line
			(start 0.508 -0.9398)
			(end -0.508 -0.9398)
			(stroke
				(width 0.1524)
				(type default)
			)
			(layer "F.SilkS")
		)
		(fp_line
			(start -0.508 -0.9398)
			(end -0.508 0.9398)
			(stroke
				(width 0.1524)
				(type default)
			)
			(layer "F.SilkS")
		)
		(fp_rect
			(start -0.508 0.9398)
			(end 0.508 -0.9398)
			(stroke
				(width 0)
				(type default)
			)
			(fill no)
			(layer "F.CrtYd")
		)
		(fp_rect
			(start -0.508 0.9398)
			(end 0.508 -0.9398)
			(stroke
				(width 0)
				(type default)
			)
			(fill no)
			(layer "F.Fab")
		)
		(pad "1" smd custom
			(at 0 -0.4445 90)
			(size 0.1397 0.1397)
			(layers "F.Cu" "F.Mask" "F.Paste")
			(net "GND")
			(options
				(clearance outline)
				(anchor circle)
			)
			(primitives
				(gr_poly
					(pts
						(arc
							(start -0.1778 -0.2794)
							(mid -0.249642 -0.249642)
							(end -0.2794 -0.1778)
						)
						(arc
							(start -0.2794 0.1778)
							(mid -0.249642 0.249642)
							(end -0.1778 0.2794)
						)
						(arc
							(start 0.1778 0.2794)
							(mid 0.249642 0.249642)
							(end 0.2794 0.1778)
						)
						(arc
							(start 0.2794 -0.1778)
							(mid 0.249642 -0.249642)
							(end 0.1778 -0.2794)
						)
					)
					(width 0)
					(fill yes)
				)
			)
		)
		(pad "2" smd custom
			(at 0 0.4445 90)
			(size 0.1397 0.1397)
			(layers "F.Cu" "F.Mask" "F.Paste")
			(net "FANTACH_F1")
			(options
				(clearance outline)
				(anchor circle)
			)
			(primitives
				(gr_poly
					(pts
						(arc
							(start -0.1778 -0.2794)
							(mid -0.249642 -0.249642)
							(end -0.2794 -0.1778)
						)
						(arc
							(start -0.2794 0.1778)
							(mid -0.249642 0.249642)
							(end -0.1778 0.2794)
						)
						(arc
							(start 0.1778 0.2794)
							(mid 0.249642 0.249642)
							(end 0.2794 0.1778)
						)
						(arc
							(start 0.2794 -0.1778)
							(mid 0.249642 -0.249642)
							(end 0.1778 -0.2794)
						)
					)
					(width 0)
					(fill yes)
				)
			)
		)
	)
	(footprint ""
		(layer "F.Cu")
		(at 478.79 -33.147)
		(property "Reference" "R874"
			(at 0 0 0)
			(layer "F.SilkS")
			(hide yes)
			(effects
				(font
					(size 1.27 1.27)
				)
			)
		)
		(property "Value" "2R6F-GP"
			(at -0.0508 -4.8514 0)
			(unlocked yes)
			(layer "F.Fab")
			(hide yes)
			(effects
				(font
					(size 1.016 1.016)
					(thickness 0.1524)
				)
			)
		)
		(property "Device Type" "R1206H26"
			(at 0 -6.3754 0)
			(unlocked yes)
			(layer "F.Fab")
			(hide yes)
			(effects
				(font
					(size 1.016 1.016)
					(thickness 0.1524)
				)
			)
		)
		(duplicate_pad_numbers_are_jumpers no)
		(fp_line
			(start -1.016 -2.2352)
			(end 1.016 -2.2352)
			(stroke
				(width 0.1524)
				(type default)
			)
			(layer "F.SilkS")
		)
		(fp_line
			(start -1.016 2.2352)
			(end -1.016 -2.2352)
			(stroke
				(width 0.1524)
				(type default)
			)
			(layer "F.SilkS")
		)
		(fp_line
			(start 1.016 -2.2352)
			(end 1.016 2.2352)
			(stroke
				(width 0.1524)
				(type default)
			)
			(layer "F.SilkS")
		)
		(fp_line
			(start 1.016 2.2352)
			(end -1.016 2.2352)
			(stroke
				(width 0.1524)
				(type default)
			)
			(layer "F.SilkS")
		)
		(fp_rect
			(start -1.0922 2.3114)
			(end 1.0922 -2.3114)
			(stroke
				(width 0)
				(type default)
			)
			(fill no)
			(layer "F.CrtYd")
		)
		(fp_poly
			(pts
				(xy -1.0922 -2.3114) (xy 1.0922 -2.3114) (xy 1.0922 2.3114) (xy -1.0922 2.3114)
			)
			(stroke
				(width 0)
				(type default)
			)
			(fill no)
			(layer "F.Fab")
		)
		(pad "1" smd rect
			(at 0 -1.397)
			(size 1.651 1.27)
			(layers "F.Cu" "F.Mask" "F.Paste")
			(net "P5V_HDD35")
		)
		(pad "2" smd rect
			(at 0 1.397)
			(size 1.651 1.27)
			(layers "F.Cu" "F.Mask" "F.Paste")
			(net "5V_PRE_35")
		)
	)
	(footprint ""
		(layer "F.Cu")
		(at 364.744 -128.651 180)
		(property "Reference" "R515"
			(at 0 0 180)
			(layer "F.SilkS")
			(hide yes)
			(effects
				(font
					(size 1.27 1.27)
				)
			)
		)
		(property "Value" "1KR2F-3-GP"
			(at 0.064008 -3.993896 180)
			(unlocked yes)
			(layer "F.Fab")
			(hide yes)
			(effects
				(font
					(size 1.016 1.016)
					(thickness 0.1524)
				)
			)
		)
		(property "Device Type" "R402H16"
			(at 0.064008 -5.517896 180)
			(unlocked yes)
			(layer "F.Fab")
			(hide yes)
			(effects
				(font
					(size 1.016 1.016)
					(thickness 0.1524)
				)
			)
		)
		(duplicate_pad_numbers_are_jumpers no)
		(fp_line
			(start 0.508 -0.9398)
			(end -0.508 -0.9398)
			(stroke
				(width 0.1524)
				(type default)
			)
			(layer "F.SilkS")
		)
		(fp_line
			(start -0.508 -0.9398)
			(end -0.508 0.9398)
			(stroke
				(width 0.1524)
				(type default)
			)
			(layer "F.SilkS")
		)
		(fp_rect
			(start -0.508 0.9398)
			(end 0.508 -0.9398)
			(stroke
				(width 0)
				(type default)
			)
			(fill no)
			(layer "F.CrtYd")
		)
		(fp_rect
			(start -0.508 0.9398)
			(end 0.508 -0.9398)
			(stroke
				(width 0)
				(type default)
			)
			(fill no)
			(layer "F.Fab")
		)
		(pad "1" smd custom
			(at 0 -0.4445 180)
			(size 0.1397 0.1397)
			(layers "F.Cu" "F.Mask" "F.Paste")
			(net "P3V3_STBY_B")
			(options
				(clearance outline)
				(anchor circle)
			)
			(primitives
				(gr_poly
					(pts
						(arc
							(start -0.1778 -0.2794)
							(mid -0.249642 -0.249642)
							(end -0.2794 -0.1778)
						)
						(arc
							(start -0.2794 0.1778)
							(mid -0.249642 0.249642)
							(end -0.1778 0.2794)
						)
						(arc
							(start 0.1778 0.2794)
							(mid 0.249642 0.249642)
							(end 0.2794 0.1778)
						)
						(arc
							(start 0.2794 -0.1778)
							(mid 0.249642 -0.249642)
							(end 0.1778 -0.2794)
						)
					)
					(width 0)
					(fill yes)
				)
			)
		)
		(pad "2" smd custom
			(at 0 0.4445 180)
			(size 0.1397 0.1397)
			(layers "F.Cu" "F.Mask" "F.Paste")
			(net "SW_PWR_R_HDD19")
			(options
				(clearance outline)
				(anchor circle)
			)
			(primitives
				(gr_poly
					(pts
						(arc
							(start -0.1778 -0.2794)
							(mid -0.249642 -0.249642)
							(end -0.2794 -0.1778)
						)
						(arc
							(start -0.2794 0.1778)
							(mid -0.249642 0.249642)
							(end -0.1778 0.2794)
						)
						(arc
							(start 0.1778 0.2794)
							(mid 0.249642 0.249642)
							(end 0.2794 0.1778)
						)
						(arc
							(start 0.2794 -0.1778)
							(mid 0.249642 -0.249642)
							(end 0.1778 -0.2794)
						)
					)
					(width 0)
					(fill yes)
				)
			)
		)
	)
	(footprint ""
		(layer "F.Cu")
		(at 168.275 -377.19 -90)
		(property "Reference" "Q193"
			(at 0 0 270)
			(layer "F.SilkS")
			(hide yes)
			(effects
				(font
					(size 1.27 1.27)
				)
			)
		)
		(property "Value" "MMBT3904-3-GP"
			(at 0.10287 -10.29843 270)
			(unlocked yes)
			(layer "F.Fab")
			(hide yes)
			(effects
				(font
					(size 1.016 1.016)
					(thickness 0.1524)
				)
			)
		)
		(property "Device Type" "SOT23CBE2D4H44"
			(at 0.10287 -12.20343 270)
			(unlocked yes)
			(layer "F.Fab")
			(hide yes)
			(effects
				(font
					(size 1.016 1.016)
					(thickness 0.1524)
				)
			)
		)
		(duplicate_pad_numbers_are_jumpers no)
		(fp_line
			(start -1.651 1.778)
			(end 1.651 1.778)
			(stroke
				(width 0.1524)
				(type default)
			)
			(layer "F.SilkS")
		)
		(fp_line
			(start 1.651 1.778)
			(end 1.651 -1.778)
			(stroke
				(width 0.1524)
				(type default)
			)
			(layer "F.SilkS")
		)
		(fp_line
			(start -1.651 -1.778)
			(end -1.651 1.778)
			(stroke
				(width 0.1524)
				(type default)
			)
			(layer "F.SilkS")
		)
		(fp_line
			(start 1.651 -1.778)
			(end -1.651 -1.778)
			(stroke
				(width 0.1524)
				(type default)
			)
			(layer "F.SilkS")
		)
		(fp_poly
			(pts
				(xy -1.778 1.8796) (xy -1.778 -1.8796) (xy 1.778 -1.8796) (xy 1.778 1.8796)
			)
			(stroke
				(width 0)
				(type default)
			)
			(fill no)
			(layer "F.CrtYd")
		)
		(fp_poly
			(pts
				(xy -1.778 1.8796) (xy -1.778 -1.8796) (xy 1.778 -1.8796) (xy 1.778 1.8796)
			)
			(stroke
				(width 0)
				(type default)
			)
			(fill no)
			(layer "F.Fab")
		)
		(pad "B" smd custom
			(at -0.98425 0.9525 270)
			(size 0.1905 0.1905)
			(layers "F.Cu" "F.Mask" "F.Paste")
			(net "MB0_TEMP_B")
			(options
				(clearance outline)
				(anchor circle)
			)
			(primitives
				(gr_poly
					(pts
						(arc
							(start -0.1778 0.5715)
							(mid -0.321484 0.511984)
							(end -0.381 0.3683)
						)
						(arc
							(start -0.381 -0.3683)
							(mid -0.321484 -0.511984)
							(end -0.1778 -0.5715)
						)
						(arc
							(start 0.1778 -0.5715)
							(mid 0.321484 -0.511984)
							(end 0.381 -0.3683)
						)
						(arc
							(start 0.381 0.3683)
							(mid 0.321484 0.511984)
							(end 0.1778 0.5715)
						)
					)
					(width 0)
					(fill yes)
				)
			)
		)
		(pad "C" smd custom
			(at 0 -0.9525 270)
			(size 0.1905 0.1905)
			(layers "F.Cu" "F.Mask" "F.Paste")
			(net "MB0_TEMP_B")
			(options
				(clearance outline)
				(anchor circle)
			)
			(primitives
				(gr_poly
					(pts
						(arc
							(start -0.1778 0.5715)
							(mid -0.321484 0.511984)
							(end -0.381 0.3683)
						)
						(arc
							(start -0.381 -0.3683)
							(mid -0.321484 -0.511984)
							(end -0.1778 -0.5715)
						)
						(arc
							(start 0.1778 -0.5715)
							(mid 0.321484 -0.511984)
							(end 0.381 -0.3683)
						)
						(arc
							(start 0.381 0.3683)
							(mid 0.321484 0.511984)
							(end 0.1778 0.5715)
						)
					)
					(width 0)
					(fill yes)
				)
			)
		)
		(pad "E" smd custom
			(at 0.98425 0.9525 270)
			(size 0.1905 0.1905)
			(layers "F.Cu" "F.Mask" "F.Paste")
			(net "MB0_TEMP_E")
			(options
				(clearance outline)
				(anchor circle)
			)
			(primitives
				(gr_poly
					(pts
						(arc
							(start -0.1778 0.5715)
							(mid -0.321484 0.511984)
							(end -0.381 0.3683)
						)
						(arc
							(start -0.381 -0.3683)
							(mid -0.321484 -0.511984)
							(end -0.1778 -0.5715)
						)
						(arc
							(start 0.1778 -0.5715)
							(mid 0.321484 -0.511984)
							(end 0.381 -0.3683)
						)
						(arc
							(start 0.381 0.3683)
							(mid 0.321484 0.511984)
							(end 0.1778 0.5715)
						)
					)
					(width 0)
					(fill yes)
				)
			)
		)
	)
	(footprint ""
		(layer "F.Cu")
		(at 264.328402 -372.399814)
		(property "Reference" "R1063"
			(at 0 0 0)
			(layer "F.SilkS")
			(hide yes)
			(effects
				(font
					(size 1.27 1.27)
				)
			)
		)
		(property "Value" "10KR2F-2-GP"
			(at 0.064008 -3.993896 0)
			(unlocked yes)
			(layer "F.Fab")
			(hide yes)
			(effects
				(font
					(size 1.016 1.016)
					(thickness 0.1524)
				)
			)
		)
		(property "Device Type" "R402H16"
			(at 0.064008 -5.517896 0)
			(unlocked yes)
			(layer "F.Fab")
			(hide yes)
			(effects
				(font
					(size 1.016 1.016)
					(thickness 0.1524)
				)
			)
		)
		(duplicate_pad_numbers_are_jumpers no)
		(fp_line
			(start -0.508 -0.9398)
			(end -0.508 0.9398)
			(stroke
				(width 0.1524)
				(type default)
			)
			(layer "F.SilkS")
		)
		(fp_line
			(start 0.508 -0.9398)
			(end -0.508 -0.9398)
			(stroke
				(width 0.1524)
				(type default)
			)
			(layer "F.SilkS")
		)
		(fp_rect
			(start -0.508 0.9398)
			(end 0.508 -0.9398)
			(stroke
				(width 0)
				(type default)
			)
			(fill no)
			(layer "F.CrtYd")
		)
		(fp_rect
			(start -0.508 0.9398)
			(end 0.508 -0.9398)
			(stroke
				(width 0)
				(type default)
			)
			(fill no)
			(layer "F.Fab")
		)
		(pad "1" smd custom
			(at 0 -0.4445)
			(size 0.1397 0.1397)
			(layers "F.Cu" "F.Mask" "F.Paste")
			(net "P3V3_IN")
			(options
				(clearance outline)
				(anchor circle)
			)
			(primitives
				(gr_poly
					(pts
						(arc
							(start -0.1778 -0.2794)
							(mid -0.249642 -0.249642)
							(end -0.2794 -0.1778)
						)
						(arc
							(start -0.2794 0.1778)
							(mid -0.249642 0.249642)
							(end -0.1778 0.2794)
						)
						(arc
							(start 0.1778 0.2794)
							(mid 0.249642 0.249642)
							(end 0.2794 0.1778)
						)
						(arc
							(start 0.2794 -0.1778)
							(mid 0.249642 -0.249642)
							(end 0.1778 -0.2794)
						)
					)
					(width 0)
					(fill yes)
				)
			)
		)
		(pad "2" smd custom
			(at 0 0.4445)
			(size 0.1397 0.1397)
			(layers "F.Cu" "F.Mask" "F.Paste")
			(net "DRAWER_CLOSED_N")
			(options
				(clearance outline)
				(anchor circle)
			)
			(primitives
				(gr_poly
					(pts
						(arc
							(start -0.1778 -0.2794)
							(mid -0.249642 -0.249642)
							(end -0.2794 -0.1778)
						)
						(arc
							(start -0.2794 0.1778)
							(mid -0.249642 0.249642)
							(end -0.1778 0.2794)
						)
						(arc
							(start 0.1778 0.2794)
							(mid 0.249642 0.249642)
							(end 0.2794 0.1778)
						)
						(arc
							(start 0.2794 -0.1778)
							(mid 0.249642 -0.249642)
							(end 0.1778 -0.2794)
						)
					)
					(width 0)
					(fill yes)
				)
			)
		)
	)
	(footprint ""
		(layer "F.Cu")
		(at 414.042352 -245.016274 90)
		(property "Reference" "VIA19"
			(at 0 0 90)
			(layer "F.SilkS")
			(hide yes)
			(effects
				(font
					(size 1.27 1.27)
				)
			)
		)
		(property "Value" "100OHM-8L-2D36MM-L18-GP"
			(at 3.8989 0.5715 90)
			(unlocked yes)
			(layer "F.Fab")
			(hide yes)
			(effects
				(font
					(size 1.016 1.016)
					(thickness 0.1524)
				)
			)
		)
		(property "Device Type" "VIA-PCIE-4P-414097"
			(at 3.8989 -0.9525 90)
			(unlocked yes)
			(layer "F.Fab")
			(hide yes)
			(effects
				(font
					(size 1.016 1.016)
					(thickness 0.1524)
				)
			)
		)
		(duplicate_pad_numbers_are_jumpers no)
		(fp_rect
			(start -2.0701 0.4826)
			(end 2.0701 -0.4826)
			(stroke
				(width 0)
				(type default)
			)
			(fill no)
			(layer "F.CrtYd")
		)
		(fp_rect
			(start -2.0701 0.4826)
			(end 2.0701 -0.4826)
			(stroke
				(width 0)
				(type default)
			)
			(fill no)
			(layer "F.Fab")
		)
		(pad "1" thru_hole circle
			(at -1.5875 0 90)
			(size 0.508 0.508)
			(drill 0.254)
			(layers "*.Cu" "*.Mask")
			(remove_unused_layers no)
			(net "GND")
			(clearance 0.2286)
			(thermal_gap 0.2286)
		)
		(pad "2" thru_hole circle
			(at -0.5715 0 90)
			(size 0.508 0.508)
			(drill 0.254)
			(layers "*.Cu" "*.Mask")
			(remove_unused_layers no)
			(net "PHY_SCC_B_TO_DRV_B_9_DP")
			(clearance 0.2286)
			(thermal_gap 0.2286)
		)
		(pad "3" thru_hole circle
			(at 0.5715 0 90)
			(size 0.508 0.508)
			(drill 0.254)
			(layers "*.Cu" "*.Mask")
			(remove_unused_layers no)
			(net "PHY_SCC_B_TO_DRV_B_9_DN")
			(clearance 0.2286)
			(thermal_gap 0.2286)
		)
		(pad "4" thru_hole circle
			(at 1.5875 0 90)
			(size 0.508 0.508)
			(drill 0.254)
			(layers "*.Cu" "*.Mask")
			(remove_unused_layers no)
			(net "GND")
			(clearance 0.2286)
			(thermal_gap 0.2286)
		)
	)
	(footprint ""
		(layer "F.Cu")
		(at 46.482 -260.858)
		(property "Reference" "Q4"
			(at 0 0 0)
			(layer "F.SilkS")
			(hide yes)
			(effects
				(font
					(size 1.27 1.27)
				)
			)
		)
		(property "Value" "AO4407AL-GP"
			(at -3.707384 -1.5367 0)
			(unlocked yes)
			(layer "F.Fab")
			(hide yes)
			(effects
				(font
					(size 1.016 1.016)
					(thickness 0.1524)
				)
			)
		)
		(property "Device Type" "SOIC8H69"
			(at -3.707384 -3.0607 0)
			(unlocked yes)
			(layer "F.Fab")
			(hide yes)
			(effects
				(font
					(size 1.016 1.016)
					(thickness 0.1524)
				)
			)
		)
		(duplicate_pad_numbers_are_jumpers no)
		(fp_line
			(start -2.7432 -1.4224)
			(end -2.7432 1.4224)
			(stroke
				(width 0.1524)
				(type default)
			)
			(layer "F.SilkS")
		)
		(fp_line
			(start -2.7432 1.4224)
			(end -2.6416 1.4224)
			(stroke
				(width 0.1524)
				(type default)
			)
			(layer "F.SilkS")
		)
		(fp_line
			(start -2.7432 1.4224)
			(end 2.1336 1.4224)
			(stroke
				(width 0.1524)
				(type default)
			)
			(layer "F.SilkS")
		)
		(fp_line
			(start -2.7178 -0.508)
			(end -2.1844 -0.0508)
			(stroke
				(width 0.1524)
				(type default)
			)
			(layer "F.SilkS")
		)
		(fp_line
			(start -2.6289 3.4417)
			(end -2.6289 1.4732)
			(stroke
				(width 0.381)
				(type default)
			)
			(layer "F.SilkS")
		)
		(fp_line
			(start -2.1844 -0.0508)
			(end -2.7178 0.508)
			(stroke
				(width 0.1524)
				(type default)
			)
			(layer "F.SilkS")
		)
		(fp_line
			(start 2.1336 -1.4224)
			(end -2.7432 -1.4224)
			(stroke
				(width 0.1524)
				(type default)
			)
			(layer "F.SilkS")
		)
		(fp_line
			(start 2.1336 1.4224)
			(end 2.1336 -1.4224)
			(stroke
				(width 0.1524)
				(type default)
			)
			(layer "F.SilkS")
		)
		(fp_poly
			(pts
				(xy -2.2098 -1.4224) (xy -2.2098 1.4224) (xy 2.2098 1.4224) (xy 2.2098 -1.4224)
			)
			(stroke
				(width 0)
				(type default)
			)
			(fill yes)
			(layer "F.SilkS")
		)
		(fp_rect
			(start -2.450084 2.999994)
			(end 2.450084 -2.999994)
			(stroke
				(width 0)
				(type default)
			)
			(fill no)
			(layer "F.CrtYd")
		)
		(fp_poly
			(pts
				(xy -2.8194 3.6322) (xy -2.8194 -3.6322) (xy 2.8194 -3.6322) (xy 2.8194 1.18364) (xy 2.450084 1.18364)
				(xy 2.450084 -2.999994) (xy -2.450084 -2.999994) (xy -2.450084 2.999994) (xy 2.450084 2.999994)
				(xy 2.450084 1.18618) (xy 2.8194 1.18618) (xy 2.8194 3.6322)
			)
			(stroke
				(width 0)
				(type default)
			)
			(fill no)
			(layer "F.CrtYd")
		)
		(fp_rect
			(start -2.8194 3.6322)
			(end 2.8194 -3.6322)
			(stroke
				(width 0)
				(type default)
			)
			(fill no)
			(layer "F.Fab")
		)
		(pad "1" smd rect
			(at -1.905 2.54)
			(size 0.635 1.651)
			(layers "F.Cu" "F.Mask" "F.Paste")
			(net "P12V_B")
		)
		(pad "2" smd rect
			(at -0.635 2.54)
			(size 0.635 1.651)
			(layers "F.Cu" "F.Mask" "F.Paste")
			(net "P12V_B")
		)
		(pad "3" smd rect
			(at 0.635 2.54)
			(size 0.635 1.651)
			(layers "F.Cu" "F.Mask" "F.Paste")
			(net "P12V_B")
		)
		(pad "4" smd rect
			(at 1.905 2.54)
			(size 0.635 1.651)
			(layers "F.Cu" "F.Mask" "F.Paste")
			(net "SW_HDD_N1")
		)
		(pad "5" smd rect
			(at 1.905 -2.54)
			(size 0.635 1.651)
			(layers "F.Cu" "F.Mask" "F.Paste")
			(net "P12V_HDD1")
		)
		(pad "6" smd rect
			(at 0.635 -2.54)
			(size 0.635 1.651)
			(layers "F.Cu" "F.Mask" "F.Paste")
			(net "P12V_HDD1")
		)
		(pad "7" smd rect
			(at -0.635 -2.54)
			(size 0.635 1.651)
			(layers "F.Cu" "F.Mask" "F.Paste")
			(net "P12V_HDD1")
		)
		(pad "8" smd rect
			(at -1.905 -2.54)
			(size 0.635 1.651)
			(layers "F.Cu" "F.Mask" "F.Paste")
			(net "P12V_HDD1")
		)
	)
	(footprint ""
		(layer "F.Cu")
		(at 114.7826 -263.779 -90)
		(property "Reference" "C69"
			(at 0 0 270)
			(layer "F.SilkS")
			(hide yes)
			(effects
				(font
					(size 1.27 1.27)
				)
			)
		)
		(property "Value" "SC1U16V3KX-5GP"
			(at 0 -2.8194 270)
			(unlocked yes)
			(layer "F.Fab")
			(hide yes)
			(effects
				(font
					(size 1.016 1.016)
					(thickness 0.1524)
				)
			)
		)
		(property "Device Type" "C603H36"
			(at 0 -4.3434 270)
			(unlocked yes)
			(layer "F.Fab")
			(hide yes)
			(effects
				(font
					(size 1.016 1.016)
					(thickness 0.1524)
				)
			)
		)
		(duplicate_pad_numbers_are_jumpers no)
		(fp_line
			(start 0.508 0)
			(end -0.508 0)
			(stroke
				(width 0.2032)
				(type default)
			)
			(layer "F.SilkS")
		)
		(fp_rect
			(start -0.5842 1.3335)
			(end 0.5842 -1.3335)
			(stroke
				(width 0)
				(type default)
			)
			(fill no)
			(layer "F.CrtYd")
		)
		(fp_rect
			(start -0.5842 1.3335)
			(end 0.5842 -1.3335)
			(stroke
				(width 0)
				(type default)
			)
			(fill no)
			(layer "F.Fab")
		)
		(pad "1" smd custom
			(at 0 -0.762 270)
			(size 0.2159 0.2159)
			(layers "F.Cu" "F.Mask" "F.Paste")
			(net "P5V_HDD3")
			(options
				(clearance outline)
				(anchor circle)
			)
			(primitives
				(gr_poly
					(pts
						(arc
							(start -0.3302 -0.4318)
							(mid -0.402042 -0.402042)
							(end -0.4318 -0.3302)
						)
						(arc
							(start -0.4318 0.3302)
							(mid -0.402042 0.402042)
							(end -0.3302 0.4318)
						)
						(arc
							(start 0.3302 0.4318)
							(mid 0.402042 0.402042)
							(end 0.4318 0.3302)
						)
						(arc
							(start 0.4318 -0.3302)
							(mid 0.402042 -0.402042)
							(end 0.3302 -0.4318)
						)
					)
					(width 0)
					(fill yes)
				)
			)
		)
		(pad "2" smd custom
			(at 0 0.762 270)
			(size 0.2159 0.2159)
			(layers "F.Cu" "F.Mask" "F.Paste")
			(net "GND")
			(options
				(clearance outline)
				(anchor circle)
			)
			(primitives
				(gr_poly
					(pts
						(arc
							(start -0.3302 -0.4318)
							(mid -0.402042 -0.402042)
							(end -0.4318 -0.3302)
						)
						(arc
							(start -0.4318 0.3302)
							(mid -0.402042 0.402042)
							(end -0.3302 0.4318)
						)
						(arc
							(start 0.3302 0.4318)
							(mid 0.402042 0.402042)
							(end 0.4318 0.3302)
						)
						(arc
							(start 0.4318 -0.3302)
							(mid 0.402042 -0.402042)
							(end 0.3302 -0.4318)
						)
					)
					(width 0)
					(fill yes)
				)
			)
		)
	)
	(footprint ""
		(layer "F.Cu")
		(at 467.5124 -6.4008 -90)
		(property "Reference" "R135"
			(at 0 0 270)
			(layer "F.SilkS")
			(hide yes)
			(effects
				(font
					(size 1.27 1.27)
				)
			)
		)
		(property "Value" "4K7R2F-GP"
			(at 0.064008 -3.993896 270)
			(unlocked yes)
			(layer "F.Fab")
			(hide yes)
			(effects
				(font
					(size 1.016 1.016)
					(thickness 0.1524)
				)
			)
		)
		(property "Device Type" "R402H16"
			(at 0.064008 -5.517896 270)
			(unlocked yes)
			(layer "F.Fab")
			(hide yes)
			(effects
				(font
					(size 1.016 1.016)
					(thickness 0.1524)
				)
			)
		)
		(duplicate_pad_numbers_are_jumpers no)
		(fp_line
			(start -0.508 -0.9398)
			(end -0.508 0.9398)
			(stroke
				(width 0.1524)
				(type default)
			)
			(layer "F.SilkS")
		)
		(fp_line
			(start 0.508 -0.9398)
			(end -0.508 -0.9398)
			(stroke
				(width 0.1524)
				(type default)
			)
			(layer "F.SilkS")
		)
		(fp_rect
			(start -0.508 0.9398)
			(end 0.508 -0.9398)
			(stroke
				(width 0)
				(type default)
			)
			(fill no)
			(layer "F.CrtYd")
		)
		(fp_rect
			(start -0.508 0.9398)
			(end 0.508 -0.9398)
			(stroke
				(width 0)
				(type default)
			)
			(fill no)
			(layer "F.Fab")
		)
		(pad "1" smd custom
			(at 0 -0.4445 270)
			(size 0.1397 0.1397)
			(layers "F.Cu" "F.Mask" "F.Paste")
			(net "P3V3_STBY_B")
			(options
				(clearance outline)
				(anchor circle)
			)
			(primitives
				(gr_poly
					(pts
						(arc
							(start -0.1778 -0.2794)
							(mid -0.249642 -0.249642)
							(end -0.2794 -0.1778)
						)
						(arc
							(start -0.2794 0.1778)
							(mid -0.249642 0.249642)
							(end -0.1778 0.2794)
						)
						(arc
							(start 0.1778 0.2794)
							(mid 0.249642 0.249642)
							(end 0.2794 0.1778)
						)
						(arc
							(start 0.2794 -0.1778)
							(mid 0.249642 -0.249642)
							(end 0.1778 -0.2794)
						)
					)
					(width 0)
					(fill yes)
				)
			)
		)
		(pad "2" smd custom
			(at 0 0.4445 270)
			(size 0.1397 0.1397)
			(layers "F.Cu" "F.Mask" "F.Paste")
			(net "TEMP2_A1")
			(options
				(clearance outline)
				(anchor circle)
			)
			(primitives
				(gr_poly
					(pts
						(arc
							(start -0.1778 -0.2794)
							(mid -0.249642 -0.249642)
							(end -0.2794 -0.1778)
						)
						(arc
							(start -0.2794 0.1778)
							(mid -0.249642 0.249642)
							(end -0.1778 0.2794)
						)
						(arc
							(start 0.1778 0.2794)
							(mid 0.249642 0.249642)
							(end 0.2794 0.1778)
						)
						(arc
							(start 0.2794 -0.1778)
							(mid 0.249642 -0.249642)
							(end 0.1778 -0.2794)
						)
					)
					(width 0)
					(fill yes)
				)
			)
		)
	)
	(footprint ""
		(layer "F.Cu")
		(at 321.634612 -14.660626 -90)
		(property "Reference" "C419"
			(at 0 0 270)
			(layer "F.SilkS")
			(hide yes)
			(effects
				(font
					(size 1.27 1.27)
				)
			)
		)
		(property "Value" "SCD01U16V1KX-GP"
			(at -2.8321 -1.7399 270)
			(unlocked yes)
			(layer "F.Fab")
			(hide yes)
			(effects
				(font
					(size 1.016 1.016)
					(thickness 0.1524)
				)
			)
		)
		(property "Device Type" "C0201H13"
			(at -2.8321 -3.2639 270)
			(unlocked yes)
			(layer "F.Fab")
			(hide yes)
			(effects
				(font
					(size 1.016 1.016)
					(thickness 0.1524)
				)
			)
		)
		(duplicate_pad_numbers_are_jumpers no)
		(fp_rect
			(start -0.2794 0.6477)
			(end 0.2794 -0.6477)
			(stroke
				(width 0)
				(type default)
			)
			(fill no)
			(layer "F.CrtYd")
		)
		(fp_rect
			(start -0.2794 0.6477)
			(end 0.2794 -0.6477)
			(stroke
				(width 0)
				(type default)
			)
			(fill no)
			(layer "F.Fab")
		)
		(pad "1" smd custom
			(at 0 -0.2794 270)
			(size 0.0762 0.0762)
			(layers "F.Cu" "F.Mask" "F.Paste")
			(net "SAS_HDD_RX_P30")
			(options
				(clearance outline)
				(anchor circle)
			)
			(primitives
				(gr_poly
					(pts
						(arc
							(start 0.1524 -0.127)
							(mid 0.137521 -0.162921)
							(end 0.1016 -0.1778)
						)
						(arc
							(start -0.1016 -0.1778)
							(mid -0.137521 -0.162921)
							(end -0.1524 -0.127)
						)
						(arc
							(start -0.1524 0.127)
							(mid -0.137521 0.162921)
							(end -0.1016 0.1778)
						)
						(arc
							(start 0.1016 0.1778)
							(mid 0.137521 0.162921)
							(end 0.1524 0.127)
						)
					)
					(width 0)
					(fill yes)
				)
			)
		)
		(pad "2" smd custom
			(at 0 0.2794 270)
			(size 0.0762 0.0762)
			(layers "F.Cu" "F.Mask" "F.Paste")
			(net "PHY_SCC_B_TO_DRV_B_30_DP")
			(options
				(clearance outline)
				(anchor circle)
			)
			(primitives
				(gr_poly
					(pts
						(arc
							(start 0.1524 -0.127)
							(mid 0.137521 -0.162921)
							(end 0.1016 -0.1778)
						)
						(arc
							(start -0.1016 -0.1778)
							(mid -0.137521 -0.162921)
							(end -0.1524 -0.127)
						)
						(arc
							(start -0.1524 0.127)
							(mid -0.137521 0.162921)
							(end -0.1016 0.1778)
						)
						(arc
							(start 0.1016 0.1778)
							(mid 0.137521 0.162921)
							(end 0.1524 0.127)
						)
					)
					(width 0)
					(fill yes)
				)
			)
		)
	)
	(footprint ""
		(layer "F.Cu")
		(at 433.324 -143.891 90)
		(property "Reference" "C312"
			(at 0 0 90)
			(layer "F.SilkS")
			(hide yes)
			(effects
				(font
					(size 1.27 1.27)
				)
			)
		)
		(property "Value" "SCD033U25V2KX-GP"
			(at 1.1811 -2.7051 90)
			(unlocked yes)
			(layer "F.Fab")
			(hide yes)
			(effects
				(font
					(size 1.016 1.016)
					(thickness 0.1524)
				)
			)
		)
		(property "Device Type" "C402H22"
			(at 1.1811 -4.2291 90)
			(unlocked yes)
			(layer "F.Fab")
			(hide yes)
			(effects
				(font
					(size 1.016 1.016)
					(thickness 0.1524)
				)
			)
		)
		(duplicate_pad_numbers_are_jumpers no)
		(fp_rect
			(start -0.4318 0.9525)
			(end 0.4318 -0.9525)
			(stroke
				(width 0)
				(type default)
			)
			(fill no)
			(layer "F.CrtYd")
		)
		(fp_rect
			(start -0.4318 0.9525)
			(end 0.4318 -0.9525)
			(stroke
				(width 0)
				(type default)
			)
			(fill no)
			(layer "F.Fab")
		)
		(pad "1" smd custom
			(at 0 -0.4445 90)
			(size 0.1524 0.1524)
			(layers "F.Cu" "F.Mask" "F.Paste")
			(net "P12V_B")
			(options
				(clearance outline)
				(anchor circle)
			)
			(primitives
				(gr_poly
					(pts
						(arc
							(start 0.3048 -0.2032)
							(mid 0.275042 -0.275042)
							(end 0.2032 -0.3048)
						)
						(arc
							(start -0.2032 -0.3048)
							(mid -0.275042 -0.275042)
							(end -0.3048 -0.2032)
						)
						(arc
							(start -0.3048 0.2032)
							(mid -0.275042 0.275042)
							(end -0.2032 0.3048)
						)
						(arc
							(start 0.2032 0.3048)
							(mid 0.275042 0.275042)
							(end 0.3048 0.2032)
						)
					)
					(width 0)
					(fill yes)
				)
			)
		)
		(pad "2" smd custom
			(at 0 0.4445 90)
			(size 0.1524 0.1524)
			(layers "F.Cu" "F.Mask" "F.Paste")
			(net "SW_HDD_N21")
			(options
				(clearance outline)
				(anchor circle)
			)
			(primitives
				(gr_poly
					(pts
						(arc
							(start 0.3048 -0.2032)
							(mid 0.275042 -0.275042)
							(end 0.2032 -0.3048)
						)
						(arc
							(start -0.2032 -0.3048)
							(mid -0.275042 -0.275042)
							(end -0.3048 -0.2032)
						)
						(arc
							(start -0.3048 0.2032)
							(mid -0.275042 0.275042)
							(end -0.2032 0.3048)
						)
						(arc
							(start 0.2032 0.3048)
							(mid 0.275042 0.275042)
							(end 0.3048 0.2032)
						)
					)
					(width 0)
					(fill yes)
				)
			)
		)
	)
	(footprint ""
		(layer "F.Cu")
		(at 105.915968 -212.312504 -90)
		(property "Reference" "R197"
			(at 0 0 270)
			(layer "F.SilkS")
			(hide yes)
			(effects
				(font
					(size 1.27 1.27)
				)
			)
		)
		(property "Value" "4K7R2F-GP"
			(at 0.064008 -3.993896 270)
			(unlocked yes)
			(layer "F.Fab")
			(hide yes)
			(effects
				(font
					(size 1.016 1.016)
					(thickness 0.1524)
				)
			)
		)
		(property "Device Type" "R402H16"
			(at 0.064008 -5.517896 270)
			(unlocked yes)
			(layer "F.Fab")
			(hide yes)
			(effects
				(font
					(size 1.016 1.016)
					(thickness 0.1524)
				)
			)
		)
		(duplicate_pad_numbers_are_jumpers no)
		(fp_line
			(start -0.508 -0.9398)
			(end -0.508 0.9398)
			(stroke
				(width 0.1524)
				(type default)
			)
			(layer "F.SilkS")
		)
		(fp_line
			(start 0.508 -0.9398)
			(end -0.508 -0.9398)
			(stroke
				(width 0.1524)
				(type default)
			)
			(layer "F.SilkS")
		)
		(fp_rect
			(start -0.508 0.9398)
			(end 0.508 -0.9398)
			(stroke
				(width 0)
				(type default)
			)
			(fill no)
			(layer "F.CrtYd")
		)
		(fp_rect
			(start -0.508 0.9398)
			(end 0.508 -0.9398)
			(stroke
				(width 0)
				(type default)
			)
			(fill no)
			(layer "F.Fab")
		)
		(pad "1" smd custom
			(at 0 -0.4445 270)
			(size 0.1397 0.1397)
			(layers "F.Cu" "F.Mask" "F.Paste")
			(net "DRIVE_B_3_ACT")
			(options
				(clearance outline)
				(anchor circle)
			)
			(primitives
				(gr_poly
					(pts
						(arc
							(start -0.1778 -0.2794)
							(mid -0.249642 -0.249642)
							(end -0.2794 -0.1778)
						)
						(arc
							(start -0.2794 0.1778)
							(mid -0.249642 0.249642)
							(end -0.1778 0.2794)
						)
						(arc
							(start 0.1778 0.2794)
							(mid 0.249642 0.249642)
							(end 0.2794 0.1778)
						)
						(arc
							(start 0.2794 -0.1778)
							(mid 0.249642 -0.249642)
							(end 0.1778 -0.2794)
						)
					)
					(width 0)
					(fill yes)
				)
			)
		)
		(pad "2" smd custom
			(at 0 0.4445 270)
			(size 0.1397 0.1397)
			(layers "F.Cu" "F.Mask" "F.Paste")
			(net "GND")
			(options
				(clearance outline)
				(anchor circle)
			)
			(primitives
				(gr_poly
					(pts
						(arc
							(start -0.1778 -0.2794)
							(mid -0.249642 -0.249642)
							(end -0.2794 -0.1778)
						)
						(arc
							(start -0.2794 0.1778)
							(mid -0.249642 0.249642)
							(end -0.1778 0.2794)
						)
						(arc
							(start 0.1778 0.2794)
							(mid 0.249642 0.249642)
							(end 0.2794 0.1778)
						)
						(arc
							(start 0.2794 -0.1778)
							(mid 0.249642 -0.249642)
							(end 0.1778 -0.2794)
						)
					)
					(width 0)
					(fill yes)
				)
			)
		)
	)
	(footprint ""
		(layer "F.Cu")
		(at 146.431 -263.779 -90)
		(property "Reference" "C82"
			(at 0 0 270)
			(layer "F.SilkS")
			(hide yes)
			(effects
				(font
					(size 1.27 1.27)
				)
			)
		)
		(property "Value" "SC1U16V3KX-5GP"
			(at 0 -2.8194 270)
			(unlocked yes)
			(layer "F.Fab")
			(hide yes)
			(effects
				(font
					(size 1.016 1.016)
					(thickness 0.1524)
				)
			)
		)
		(property "Device Type" "C603H36"
			(at 0 -4.3434 270)
			(unlocked yes)
			(layer "F.Fab")
			(hide yes)
			(effects
				(font
					(size 1.016 1.016)
					(thickness 0.1524)
				)
			)
		)
		(duplicate_pad_numbers_are_jumpers no)
		(fp_line
			(start 0.508 0)
			(end -0.508 0)
			(stroke
				(width 0.2032)
				(type default)
			)
			(layer "F.SilkS")
		)
		(fp_rect
			(start -0.5842 1.3335)
			(end 0.5842 -1.3335)
			(stroke
				(width 0)
				(type default)
			)
			(fill no)
			(layer "F.CrtYd")
		)
		(fp_rect
			(start -0.5842 1.3335)
			(end 0.5842 -1.3335)
			(stroke
				(width 0)
				(type default)
			)
			(fill no)
			(layer "F.Fab")
		)
		(pad "1" smd custom
			(at 0 -0.762 270)
			(size 0.2159 0.2159)
			(layers "F.Cu" "F.Mask" "F.Paste")
			(net "P5V_HDD4")
			(options
				(clearance outline)
				(anchor circle)
			)
			(primitives
				(gr_poly
					(pts
						(arc
							(start -0.3302 -0.4318)
							(mid -0.402042 -0.402042)
							(end -0.4318 -0.3302)
						)
						(arc
							(start -0.4318 0.3302)
							(mid -0.402042 0.402042)
							(end -0.3302 0.4318)
						)
						(arc
							(start 0.3302 0.4318)
							(mid 0.402042 0.402042)
							(end 0.4318 0.3302)
						)
						(arc
							(start 0.4318 -0.3302)
							(mid 0.402042 -0.402042)
							(end 0.3302 -0.4318)
						)
					)
					(width 0)
					(fill yes)
				)
			)
		)
		(pad "2" smd custom
			(at 0 0.762 270)
			(size 0.2159 0.2159)
			(layers "F.Cu" "F.Mask" "F.Paste")
			(net "GND")
			(options
				(clearance outline)
				(anchor circle)
			)
			(primitives
				(gr_poly
					(pts
						(arc
							(start -0.3302 -0.4318)
							(mid -0.402042 -0.402042)
							(end -0.4318 -0.3302)
						)
						(arc
							(start -0.4318 0.3302)
							(mid -0.402042 0.402042)
							(end -0.3302 0.4318)
						)
						(arc
							(start 0.3302 0.4318)
							(mid 0.402042 0.402042)
							(end 0.4318 0.3302)
						)
						(arc
							(start 0.4318 -0.3302)
							(mid 0.402042 -0.402042)
							(end 0.3302 -0.4318)
						)
					)
					(width 0)
					(fill yes)
				)
			)
		)
	)
	(footprint ""
		(layer "F.Cu")
		(at 150.495 -275.463 180)
		(property "Reference" "C88"
			(at 0 0 180)
			(layer "F.SilkS")
			(hide yes)
			(effects
				(font
					(size 1.27 1.27)
				)
			)
		)
		(property "Value" "SC1U25V3KX-GP"
			(at 0 -2.8194 180)
			(unlocked yes)
			(layer "F.Fab")
			(hide yes)
			(effects
				(font
					(size 1.016 1.016)
					(thickness 0.1524)
				)
			)
		)
		(property "Device Type" "C603H36"
			(at 0 -4.3434 180)
			(unlocked yes)
			(layer "F.Fab")
			(hide yes)
			(effects
				(font
					(size 1.016 1.016)
					(thickness 0.1524)
				)
			)
		)
		(duplicate_pad_numbers_are_jumpers no)
		(fp_line
			(start 0.508 0)
			(end -0.508 0)
			(stroke
				(width 0.2032)
				(type default)
			)
			(layer "F.SilkS")
		)
		(fp_rect
			(start -0.5842 1.3335)
			(end 0.5842 -1.3335)
			(stroke
				(width 0)
				(type default)
			)
			(fill no)
			(layer "F.CrtYd")
		)
		(fp_rect
			(start -0.5842 1.3335)
			(end 0.5842 -1.3335)
			(stroke
				(width 0)
				(type default)
			)
			(fill no)
			(layer "F.Fab")
		)
		(pad "1" smd custom
			(at 0 -0.762 180)
			(size 0.2159 0.2159)
			(layers "F.Cu" "F.Mask" "F.Paste")
			(net "P12V_HDD4")
			(options
				(clearance outline)
				(anchor circle)
			)
			(primitives
				(gr_poly
					(pts
						(arc
							(start -0.3302 -0.4318)
							(mid -0.402042 -0.402042)
							(end -0.4318 -0.3302)
						)
						(arc
							(start -0.4318 0.3302)
							(mid -0.402042 0.402042)
							(end -0.3302 0.4318)
						)
						(arc
							(start 0.3302 0.4318)
							(mid 0.402042 0.402042)
							(end 0.4318 0.3302)
						)
						(arc
							(start 0.4318 -0.3302)
							(mid 0.402042 -0.402042)
							(end 0.3302 -0.4318)
						)
					)
					(width 0)
					(fill yes)
				)
			)
		)
		(pad "2" smd custom
			(at 0 0.762 180)
			(size 0.2159 0.2159)
			(layers "F.Cu" "F.Mask" "F.Paste")
			(net "GND")
			(options
				(clearance outline)
				(anchor circle)
			)
			(primitives
				(gr_poly
					(pts
						(arc
							(start -0.3302 -0.4318)
							(mid -0.402042 -0.402042)
							(end -0.4318 -0.3302)
						)
						(arc
							(start -0.4318 0.3302)
							(mid -0.402042 0.402042)
							(end -0.3302 0.4318)
						)
						(arc
							(start 0.3302 0.4318)
							(mid 0.402042 0.402042)
							(end 0.4318 0.3302)
						)
						(arc
							(start 0.4318 -0.3302)
							(mid 0.402042 -0.402042)
							(end 0.3302 -0.4318)
						)
					)
					(width 0)
					(fill yes)
				)
			)
		)
	)
	(footprint ""
		(layer "F.Cu")
		(at 66.7258 -263.144 -90)
		(property "Reference" "R174"
			(at 0 0 270)
			(layer "F.SilkS")
			(hide yes)
			(effects
				(font
					(size 1.27 1.27)
				)
			)
		)
		(property "Value" "10KR2F-2-GP"
			(at 0.064008 -3.993896 270)
			(unlocked yes)
			(layer "F.Fab")
			(hide yes)
			(effects
				(font
					(size 1.016 1.016)
					(thickness 0.1524)
				)
			)
		)
		(property "Device Type" "R402H16"
			(at 0.064008 -5.517896 270)
			(unlocked yes)
			(layer "F.Fab")
			(hide yes)
			(effects
				(font
					(size 1.016 1.016)
					(thickness 0.1524)
				)
			)
		)
		(duplicate_pad_numbers_are_jumpers no)
		(fp_line
			(start -0.508 -0.9398)
			(end -0.508 0.9398)
			(stroke
				(width 0.1524)
				(type default)
			)
			(layer "F.SilkS")
		)
		(fp_line
			(start 0.508 -0.9398)
			(end -0.508 -0.9398)
			(stroke
				(width 0.1524)
				(type default)
			)
			(layer "F.SilkS")
		)
		(fp_rect
			(start -0.508 0.9398)
			(end 0.508 -0.9398)
			(stroke
				(width 0)
				(type default)
			)
			(fill no)
			(layer "F.CrtYd")
		)
		(fp_rect
			(start -0.508 0.9398)
			(end 0.508 -0.9398)
			(stroke
				(width 0)
				(type default)
			)
			(fill no)
			(layer "F.Fab")
		)
		(pad "1" smd custom
			(at 0 -0.4445 270)
			(size 0.1397 0.1397)
			(layers "F.Cu" "F.Mask" "F.Paste")
			(net "P3V3_STBY_B")
			(options
				(clearance outline)
				(anchor circle)
			)
			(primitives
				(gr_poly
					(pts
						(arc
							(start -0.1778 -0.2794)
							(mid -0.249642 -0.249642)
							(end -0.2794 -0.1778)
						)
						(arc
							(start -0.2794 0.1778)
							(mid -0.249642 0.249642)
							(end -0.1778 0.2794)
						)
						(arc
							(start 0.1778 0.2794)
							(mid 0.249642 0.249642)
							(end 0.2794 0.1778)
						)
						(arc
							(start 0.2794 -0.1778)
							(mid 0.249642 -0.249642)
							(end 0.1778 -0.2794)
						)
					)
					(width 0)
					(fill yes)
				)
			)
		)
		(pad "2" smd custom
			(at 0 0.4445 270)
			(size 0.1397 0.1397)
			(layers "F.Cu" "F.Mask" "F.Paste")
			(net "HDD_PRSNT_1")
			(options
				(clearance outline)
				(anchor circle)
			)
			(primitives
				(gr_poly
					(pts
						(arc
							(start -0.1778 -0.2794)
							(mid -0.249642 -0.249642)
							(end -0.2794 -0.1778)
						)
						(arc
							(start -0.2794 0.1778)
							(mid -0.249642 0.249642)
							(end -0.1778 0.2794)
						)
						(arc
							(start 0.1778 0.2794)
							(mid 0.249642 0.249642)
							(end 0.2794 0.1778)
						)
						(arc
							(start 0.2794 -0.1778)
							(mid 0.249642 -0.249642)
							(end 0.1778 -0.2794)
						)
					)
					(width 0)
					(fill yes)
				)
			)
		)
	)
	(footprint ""
		(layer "F.Cu")
		(at 312.443876 -217.413586 -90)
		(property "Reference" "R242"
			(at 0 0 270)
			(layer "F.SilkS")
			(hide yes)
			(effects
				(font
					(size 1.27 1.27)
				)
			)
		)
		(property "Value" "4K7R2F-GP"
			(at 0.064008 -3.993896 270)
			(unlocked yes)
			(layer "F.Fab")
			(hide yes)
			(effects
				(font
					(size 1.016 1.016)
					(thickness 0.1524)
				)
			)
		)
		(property "Device Type" "R402H16"
			(at 0.064008 -5.517896 270)
			(unlocked yes)
			(layer "F.Fab")
			(hide yes)
			(effects
				(font
					(size 1.016 1.016)
					(thickness 0.1524)
				)
			)
		)
		(duplicate_pad_numbers_are_jumpers no)
		(fp_line
			(start -0.508 -0.9398)
			(end -0.508 0.9398)
			(stroke
				(width 0.1524)
				(type default)
			)
			(layer "F.SilkS")
		)
		(fp_line
			(start 0.508 -0.9398)
			(end -0.508 -0.9398)
			(stroke
				(width 0.1524)
				(type default)
			)
			(layer "F.SilkS")
		)
		(fp_rect
			(start -0.508 0.9398)
			(end 0.508 -0.9398)
			(stroke
				(width 0)
				(type default)
			)
			(fill no)
			(layer "F.CrtYd")
		)
		(fp_rect
			(start -0.508 0.9398)
			(end 0.508 -0.9398)
			(stroke
				(width 0)
				(type default)
			)
			(fill no)
			(layer "F.Fab")
		)
		(pad "1" smd custom
			(at 0 -0.4445 270)
			(size 0.1397 0.1397)
			(layers "F.Cu" "F.Mask" "F.Paste")
			(net "DRIVE_B_6_FLT_LED")
			(options
				(clearance outline)
				(anchor circle)
			)
			(primitives
				(gr_poly
					(pts
						(arc
							(start -0.1778 -0.2794)
							(mid -0.249642 -0.249642)
							(end -0.2794 -0.1778)
						)
						(arc
							(start -0.2794 0.1778)
							(mid -0.249642 0.249642)
							(end -0.1778 0.2794)
						)
						(arc
							(start 0.1778 0.2794)
							(mid 0.249642 0.249642)
							(end 0.2794 0.1778)
						)
						(arc
							(start 0.2794 -0.1778)
							(mid 0.249642 -0.249642)
							(end 0.1778 -0.2794)
						)
					)
					(width 0)
					(fill yes)
				)
			)
		)
		(pad "2" smd custom
			(at 0 0.4445 270)
			(size 0.1397 0.1397)
			(layers "F.Cu" "F.Mask" "F.Paste")
			(net "GND")
			(options
				(clearance outline)
				(anchor circle)
			)
			(primitives
				(gr_poly
					(pts
						(arc
							(start -0.1778 -0.2794)
							(mid -0.249642 -0.249642)
							(end -0.2794 -0.1778)
						)
						(arc
							(start -0.2794 0.1778)
							(mid -0.249642 0.249642)
							(end -0.1778 0.2794)
						)
						(arc
							(start 0.1778 0.2794)
							(mid 0.249642 0.249642)
							(end 0.2794 0.1778)
						)
						(arc
							(start 0.2794 -0.1778)
							(mid 0.249642 -0.249642)
							(end 0.1778 -0.2794)
						)
					)
					(width 0)
					(fill yes)
				)
			)
		)
	)
	(footprint ""
		(layer "F.Cu")
		(at 395.478 -36.83 180)
		(property "Reference" "C447"
			(at 0 0 180)
			(layer "F.SilkS")
			(hide yes)
			(effects
				(font
					(size 1.27 1.27)
				)
			)
		)
		(property "Value" "SC10U16V6KX-2GP"
			(at -0.0762 -5.1308 180)
			(unlocked yes)
			(layer "F.Fab")
			(hide yes)
			(effects
				(font
					(size 1.016 1.016)
					(thickness 0.1524)
				)
			)
		)
		(property "Device Type" "C1206H71"
			(at -0.127 -6.6548 180)
			(unlocked yes)
			(layer "F.Fab")
			(hide yes)
			(effects
				(font
					(size 1.016 1.016)
					(thickness 0.1524)
				)
			)
		)
		(duplicate_pad_numbers_are_jumpers no)
		(fp_line
			(start 1.016 2.2352)
			(end -1.016 2.2352)
			(stroke
				(width 0.1524)
				(type default)
			)
			(layer "F.SilkS")
		)
		(fp_line
			(start 1.016 0.8382)
			(end 1.016 2.2352)
			(stroke
				(width 0.1524)
				(type default)
			)
			(layer "F.SilkS")
		)
		(fp_line
			(start 1.016 -2.2352)
			(end 1.016 -0.8382)
			(stroke
				(width 0.1524)
				(type default)
			)
			(layer "F.SilkS")
		)
		(fp_line
			(start -1.016 2.2352)
			(end -1.016 0.8382)
			(stroke
				(width 0.1524)
				(type default)
			)
			(layer "F.SilkS")
		)
		(fp_line
			(start -1.016 -0.8382)
			(end -1.016 -2.2352)
			(stroke
				(width 0.1524)
				(type default)
			)
			(layer "F.SilkS")
		)
		(fp_line
			(start -1.016 -2.2352)
			(end 1.016 -2.2352)
			(stroke
				(width 0.1524)
				(type default)
			)
			(layer "F.SilkS")
		)
		(fp_rect
			(start -1.0922 2.3114)
			(end 1.0922 -2.3114)
			(stroke
				(width 0)
				(type default)
			)
			(fill no)
			(layer "F.CrtYd")
		)
		(fp_poly
			(pts
				(xy 1.0922 -2.3114) (xy 1.0922 2.3114) (xy -1.0922 2.3114) (xy -1.0922 -2.3114)
			)
			(stroke
				(width 0)
				(type default)
			)
			(fill no)
			(layer "F.Fab")
		)
		(pad "1" smd rect
			(at 0 -1.397 180)
			(size 1.651 1.27)
			(layers "F.Cu" "F.Mask" "F.Paste")
			(net "P5V_HDD32")
		)
		(pad "2" smd rect
			(at 0 1.397 180)
			(size 1.651 1.27)
			(layers "F.Cu" "F.Mask" "F.Paste")
			(net "GND")
		)
	)
	(footprint ""
		(layer "F.Cu")
		(at 253.350522 -366.115346 180)
		(property "Reference" "U22"
			(at 0 0 180)
			(layer "F.SilkS")
			(hide yes)
			(effects
				(font
					(size 1.27 1.27)
				)
			)
		)
		(property "Value" "ADM1278-2ACPZ-RL-1-GP"
			(at -4.7625 -7.4422 180)
			(unlocked yes)
			(layer "F.Fab")
			(hide yes)
			(effects
				(font
					(size 1.016 1.016)
					(thickness 0.1524)
				)
			)
		)
		(property "Device Type" "QFN32-G3D45-UH32"
			(at -4.7625 -8.9662 180)
			(unlocked yes)
			(layer "F.Fab")
			(hide yes)
			(effects
				(font
					(size 1.016 1.016)
					(thickness 0.1524)
				)
			)
		)
		(duplicate_pad_numbers_are_jumpers no)
		(fp_line
			(start 4.0513 -0.749808)
			(end 3.2893 -0.749808)
			(stroke
				(width 0.1524)
				(type default)
			)
			(layer "F.SilkS")
		)
		(fp_line
			(start 3.7973 1.749552)
			(end 3.2893 1.749552)
			(stroke
				(width 0.1524)
				(type default)
			)
			(layer "F.SilkS")
		)
		(fp_line
			(start 3.5179 3.5179)
			(end 2.2479 3.5179)
			(stroke
				(width 0.1524)
				(type default)
			)
			(layer "F.SilkS")
		)
		(fp_line
			(start 3.5179 2.2479)
			(end 3.5179 3.5179)
			(stroke
				(width 0.1524)
				(type default)
			)
			(layer "F.SilkS")
		)
		(fp_line
			(start -0.250698 4.0513)
			(end -0.250698 3.2893)
			(stroke
				(width 0.1524)
				(type default)
			)
			(layer "F.SilkS")
		)
		(fp_line
			(start -0.250698 -3.7973)
			(end -0.250698 -3.2893)
			(stroke
				(width 0.1524)
				(type default)
			)
			(layer "F.SilkS")
		)
		(fp_line
			(start -3.5179 3.5179)
			(end -2.2479 3.5179)
			(stroke
				(width 0.1524)
				(type default)
			)
			(layer "F.SilkS")
		)
		(fp_line
			(start -3.5179 2.2479)
			(end -3.5179 3.5179)
			(stroke
				(width 0.1524)
				(type default)
			)
			(layer "F.SilkS")
		)
		(fp_line
			(start -3.5179 -2.2479)
			(end -3.5179 -3.5179)
			(stroke
				(width 0.1524)
				(type default)
			)
			(layer "F.SilkS")
		)
		(fp_line
			(start -3.5179 -3.5179)
			(end -2.2479 -3.5179)
			(stroke
				(width 0.1524)
				(type default)
			)
			(layer "F.SilkS")
		)
		(fp_line
			(start -3.7973 1.24968)
			(end -3.2893 1.24968)
			(stroke
				(width 0.1524)
				(type default)
			)
			(layer "F.SilkS")
		)
		(fp_line
			(start -4.0513 -1.24968)
			(end -3.2893 -1.24968)
			(stroke
				(width 0.1524)
				(type default)
			)
			(layer "F.SilkS")
		)
		(fp_poly
			(pts
				(xy 2.2479 -3.5179) (xy 3.5179 -2.2479) (xy 3.5179 -3.5179)
			)
			(stroke
				(width 0)
				(type default)
			)
			(fill yes)
			(layer "F.SilkS")
		)
		(fp_rect
			(start -2.5019 2.5019)
			(end 2.5019 -2.5019)
			(stroke
				(width 0)
				(type default)
			)
			(fill no)
			(layer "F.CrtYd")
		)
		(fp_poly
			(pts
				(xy -3.5179 3.5179) (xy -3.5179 -3.5179) (xy 3.5179 -3.5179) (xy 3.5179 3.5179) (xy -2.49682 3.5179)
				(xy -2.49682 2.5019) (xy 2.5019 2.5019) (xy 2.5019 -2.5019) (xy -2.5019 -2.5019) (xy -2.5019 3.5179)
			)
			(stroke
				(width 0)
				(type default)
			)
			(fill no)
			(layer "F.CrtYd")
		)
		(fp_rect
			(start -3.5179 3.5179)
			(end 3.5179 -3.5179)
			(stroke
				(width 0)
				(type default)
			)
			(fill no)
			(layer "F.Fab")
		)
		(pad "1" smd rect
			(at 1.75006 -2.5527 180)
			(size 0.3048 0.9144)
			(layers "F.Cu" "F.Mask" "F.Paste")
			(net "MB3_PSET_R")
		)
		(pad "2" smd rect
			(at 1.249934 -2.4765 180)
			(size 0.3048 1.0668)
			(layers "F.Cu" "F.Mask" "F.Paste")
			(net "MB3_VCAP_R")
		)
		(pad "3" smd rect
			(at 0.750062 -2.4765 180)
			(size 0.3048 1.0668)
			(layers "F.Cu" "F.Mask" "F.Paste")
			(net "MB3_ISET_R")
		)
		(pad "4" smd rect
			(at 0.249936 -2.4765 180)
			(size 0.3048 1.0668)
			(layers "F.Cu" "F.Mask" "F.Paste")
			(net "MB3_ISTART_R")
		)
		(pad "5" smd rect
			(at -0.249936 -2.4765 180)
			(size 0.3048 1.0668)
			(layers "F.Cu" "F.Mask" "F.Paste")
			(net "MB3_TIME_R")
		)
		(pad "6" smd rect
			(at -0.750062 -2.4765 180)
			(size 0.3048 1.0668)
			(layers "F.Cu" "F.Mask" "F.Paste")
			(net "Net_972")
		)
		(pad "7" smd rect
			(at -1.249934 -2.4765 180)
			(size 0.3048 1.0668)
			(layers "F.Cu" "F.Mask" "F.Paste")
			(net "MB3_CM_ADR1_R")
		)
		(pad "8" smd rect
			(at -1.75006 -2.5527 180)
			(size 0.3048 0.9144)
			(layers "F.Cu" "F.Mask" "F.Paste")
			(net "MB3_CM_ADR2_R")
		)
		(pad "9" smd rect
			(at -2.5527 -1.75006 180)
			(size 0.9144 0.3048)
			(layers "F.Cu" "F.Mask" "F.Paste")
			(net "MB3_SPISS_PD")
		)
		(pad "10" smd rect
			(at -2.4765 -1.249934 180)
			(size 1.0668 0.3048)
			(layers "F.Cu" "F.Mask" "F.Paste")
			(net "Net_976")
		)
		(pad "11" smd rect
			(at -2.4765 -0.750062 180)
			(size 1.0668 0.3048)
			(layers "F.Cu" "F.Mask" "F.Paste")
			(net "Net_975")
		)
		(pad "12" smd rect
			(at -2.4765 -0.249936 180)
			(size 1.0668 0.3048)
			(layers "F.Cu" "F.Mask" "F.Paste")
			(net "MB3_HS_ENABLE")
		)
		(pad "13" smd rect
			(at -2.4765 0.249936 180)
			(size 1.0668 0.3048)
			(layers "F.Cu" "F.Mask" "F.Paste")
			(net "Net_974")
		)
		(pad "14" smd rect
			(at -2.4765 0.750062 180)
			(size 1.0668 0.3048)
			(layers "F.Cu" "F.Mask" "F.Paste")
			(net "Net_973")
		)
		(pad "15" smd rect
			(at -2.4765 1.249934 180)
			(size 1.0668 0.3048)
			(layers "F.Cu" "F.Mask" "F.Paste")
			(net "MB3_SDA_R")
		)
		(pad "16" smd rect
			(at -2.5527 1.75006 180)
			(size 0.9144 0.3048)
			(layers "F.Cu" "F.Mask" "F.Paste")
			(net "MB3_SCL_R")
		)
		(pad "17" smd rect
			(at -1.75006 2.5527 180)
			(size 0.3048 0.9144)
			(layers "F.Cu" "F.Mask" "F.Paste")
			(net "MB3_RETRY_R")
		)
		(pad "18" smd rect
			(at -1.249934 2.4765 180)
			(size 0.3048 1.0668)
			(layers "F.Cu" "F.Mask" "F.Paste")
			(net "P12V_B_PGOOD")
		)
		(pad "19" smd rect
			(at -0.750062 2.4765 180)
			(size 0.3048 1.0668)
			(layers "F.Cu" "F.Mask" "F.Paste")
			(net "Net_977")
		)
		(pad "20" smd rect
			(at -0.249936 2.4765 180)
			(size 0.3048 1.0668)
			(layers "F.Cu" "F.Mask" "F.Paste")
			(net "MB3_CM_VOUT_R")
		)
		(pad "21" smd rect
			(at 0.249936 2.4765 180)
			(size 0.3048 1.0668)
			(layers "F.Cu" "F.Mask" "F.Paste")
			(net "MB3_P12V_PWGIN_R")
		)
		(pad "22" smd rect
			(at 0.750062 2.4765 180)
			(size 0.3048 1.0668)
			(layers "F.Cu" "F.Mask" "F.Paste")
			(net "AGND_CURRENT_DPB")
		)
		(pad "23" smd rect
			(at 1.249934 2.4765 180)
			(size 0.3048 1.0668)
			(layers "F.Cu" "F.Mask" "F.Paste")
			(net "GND")
		)
		(pad "24" smd rect
			(at 1.75006 2.5527 180)
			(size 0.3048 0.9144)
			(layers "F.Cu" "F.Mask" "F.Paste")
			(net "MB3_CM_GATE")
		)
		(pad "25" smd rect
			(at 2.5527 1.75006 180)
			(size 0.9144 0.3048)
			(layers "F.Cu" "F.Mask" "F.Paste")
			(net "MB3_TEMP")
		)
		(pad "26" smd rect
			(at 2.4765 1.249934 180)
			(size 1.0668 0.3048)
			(layers "F.Cu" "F.Mask" "F.Paste")
			(net "MB3_CM_SENSE_N")
		)
		(pad "27" smd rect
			(at 2.4765 0.750062 180)
			(size 1.0668 0.3048)
			(layers "F.Cu" "F.Mask" "F.Paste")
			(net "MB3_HS_SENSE_N")
		)
		(pad "28" smd rect
			(at 2.4765 0.249936 180)
			(size 1.0668 0.3048)
			(layers "F.Cu" "F.Mask" "F.Paste")
			(net "MB3_HS_SENSE_P")
		)
		(pad "29" smd rect
			(at 2.4765 -0.249936 180)
			(size 1.0668 0.3048)
			(layers "F.Cu" "F.Mask" "F.Paste")
			(net "MB3_CM_SENSE_P")
		)
		(pad "30" smd rect
			(at 2.4765 -0.750062 180)
			(size 1.0668 0.3048)
			(layers "F.Cu" "F.Mask" "F.Paste")
			(net "MB3_P12V_HS")
		)
		(pad "31" smd rect
			(at 2.4765 -1.249934 180)
			(size 1.0668 0.3048)
			(layers "F.Cu" "F.Mask" "F.Paste")
			(net "MB3_CM_UV_R")
		)
		(pad "32" smd rect
			(at 2.5527 -1.75006 180)
			(size 0.9144 0.3048)
			(layers "F.Cu" "F.Mask" "F.Paste")
			(net "MB3_CM_OV_R")
		)
		(pad "33" smd rect
			(at 0 0 180)
			(size 3.4544 3.4544)
			(layers "F.Cu" "F.Mask" "F.Paste")
			(net "AGND_CURRENT_DPB")
		)
	)
	(footprint ""
		(layer "F.Cu")
		(at 441.96 -99.187)
		(property "Reference" "R457"
			(at 0 0 0)
			(layer "F.SilkS")
			(hide yes)
			(effects
				(font
					(size 1.27 1.27)
				)
			)
		)
		(property "Value" "91R3F-1-GP"
			(at -0.0254 -2.5146 0)
			(unlocked yes)
			(layer "F.Fab")
			(hide yes)
			(effects
				(font
					(size 1.016 1.016)
					(thickness 0.1524)
				)
			)
		)
		(property "Device Type" "R603H22"
			(at -0.0254 -4.0386 0)
			(unlocked yes)
			(layer "F.Fab")
			(hide yes)
			(effects
				(font
					(size 1.016 1.016)
					(thickness 0.1524)
				)
			)
		)
		(duplicate_pad_numbers_are_jumpers no)
		(fp_line
			(start -0.4826 0)
			(end -0.2032 0)
			(stroke
				(width 0.2032)
				(type default)
			)
			(layer "F.SilkS")
		)
		(fp_line
			(start 0.2032 0)
			(end 0.4826 0)
			(stroke
				(width 0.2032)
				(type default)
			)
			(layer "F.SilkS")
		)
		(fp_rect
			(start -0.5842 1.3335)
			(end 0.5842 -1.3335)
			(stroke
				(width 0)
				(type default)
			)
			(fill no)
			(layer "F.CrtYd")
		)
		(fp_rect
			(start -0.5842 1.3335)
			(end 0.5842 -1.3335)
			(stroke
				(width 0)
				(type default)
			)
			(fill no)
			(layer "F.Fab")
		)
		(pad "1" smd custom
			(at 0 -0.762)
			(size 0.2159 0.2159)
			(layers "F.Cu" "F.Mask" "F.Paste")
			(net "P5V_B_4")
			(options
				(clearance outline)
				(anchor circle)
			)
			(primitives
				(gr_poly
					(pts
						(arc
							(start -0.3302 -0.4318)
							(mid -0.402042 -0.402042)
							(end -0.4318 -0.3302)
						)
						(arc
							(start -0.4318 0.3302)
							(mid -0.402042 0.402042)
							(end -0.3302 0.4318)
						)
						(arc
							(start 0.3302 0.4318)
							(mid 0.402042 0.402042)
							(end 0.4318 0.3302)
						)
						(arc
							(start 0.4318 -0.3302)
							(mid 0.402042 -0.402042)
							(end 0.3302 -0.4318)
						)
					)
					(width 0)
					(fill yes)
				)
			)
		)
		(pad "2" smd custom
			(at 0 0.762)
			(size 0.2159 0.2159)
			(layers "F.Cu" "F.Mask" "F.Paste")
			(net "DRV_ACT_22")
			(options
				(clearance outline)
				(anchor circle)
			)
			(primitives
				(gr_poly
					(pts
						(arc
							(start -0.3302 -0.4318)
							(mid -0.402042 -0.402042)
							(end -0.4318 -0.3302)
						)
						(arc
							(start -0.4318 0.3302)
							(mid -0.402042 0.402042)
							(end -0.3302 0.4318)
						)
						(arc
							(start 0.3302 0.4318)
							(mid 0.402042 0.402042)
							(end 0.4318 0.3302)
						)
						(arc
							(start 0.4318 -0.3302)
							(mid 0.402042 -0.402042)
							(end 0.3302 -0.4318)
						)
					)
					(width 0)
					(fill yes)
				)
			)
		)
	)
	(footprint ""
		(layer "F.Cu")
		(at 416.284664 -130.21945 -90)
		(property "Reference" "C301"
			(at 0 0 270)
			(layer "F.SilkS")
			(hide yes)
			(effects
				(font
					(size 1.27 1.27)
				)
			)
		)
		(property "Value" "SCD01U16V1KX-GP"
			(at -2.8321 -1.7399 270)
			(unlocked yes)
			(layer "F.Fab")
			(hide yes)
			(effects
				(font
					(size 1.016 1.016)
					(thickness 0.1524)
				)
			)
		)
		(property "Device Type" "C0201H13"
			(at -2.8321 -3.2639 270)
			(unlocked yes)
			(layer "F.Fab")
			(hide yes)
			(effects
				(font
					(size 1.016 1.016)
					(thickness 0.1524)
				)
			)
		)
		(duplicate_pad_numbers_are_jumpers no)
		(fp_rect
			(start -0.2794 0.6477)
			(end 0.2794 -0.6477)
			(stroke
				(width 0)
				(type default)
			)
			(fill no)
			(layer "F.CrtYd")
		)
		(fp_rect
			(start -0.2794 0.6477)
			(end 0.2794 -0.6477)
			(stroke
				(width 0)
				(type default)
			)
			(fill no)
			(layer "F.Fab")
		)
		(pad "1" smd custom
			(at 0 -0.2794 270)
			(size 0.0762 0.0762)
			(layers "F.Cu" "F.Mask" "F.Paste")
			(net "SAS_HDD_RX_N21")
			(options
				(clearance outline)
				(anchor circle)
			)
			(primitives
				(gr_poly
					(pts
						(arc
							(start 0.1524 -0.127)
							(mid 0.137521 -0.162921)
							(end 0.1016 -0.1778)
						)
						(arc
							(start -0.1016 -0.1778)
							(mid -0.137521 -0.162921)
							(end -0.1524 -0.127)
						)
						(arc
							(start -0.1524 0.127)
							(mid -0.137521 0.162921)
							(end -0.1016 0.1778)
						)
						(arc
							(start 0.1016 0.1778)
							(mid 0.137521 0.162921)
							(end 0.1524 0.127)
						)
					)
					(width 0)
					(fill yes)
				)
			)
		)
		(pad "2" smd custom
			(at 0 0.2794 270)
			(size 0.0762 0.0762)
			(layers "F.Cu" "F.Mask" "F.Paste")
			(net "PHY_SCC_B_TO_DRV_B_21_DN")
			(options
				(clearance outline)
				(anchor circle)
			)
			(primitives
				(gr_poly
					(pts
						(arc
							(start 0.1524 -0.127)
							(mid 0.137521 -0.162921)
							(end 0.1016 -0.1778)
						)
						(arc
							(start -0.1016 -0.1778)
							(mid -0.137521 -0.162921)
							(end -0.1524 -0.127)
						)
						(arc
							(start -0.1524 0.127)
							(mid -0.137521 0.162921)
							(end -0.1016 0.1778)
						)
						(arc
							(start 0.1016 0.1778)
							(mid 0.137521 0.162921)
							(end 0.1524 0.127)
						)
					)
					(width 0)
					(fill yes)
				)
			)
		)
	)
	(footprint ""
		(layer "F.Cu")
		(at 189.799976 -203.999846)
		(property "Reference" ""
			(at 0 0 0)
			(layer "F.SilkS")
			(hide yes)
			(effects
				(font
					(size 1.27 1.27)
				)
			)
		)
		(property "Value" "*"
			(at -8.398764 -8.057642 0)
			(unlocked yes)
			(layer "F.Fab")
			(hide yes)
			(effects
				(font
					(size 1.016 1.016)
					(thickness 0.1524)
				)
			)
		)
		(duplicate_pad_numbers_are_jumpers no)
		(fp_poly
			(pts
				(arc
					(start 7.3152 0)
					(mid 0 7.3152)
					(end -7.3152 0)
				)
				(arc
					(start -7.3152 -5.9944)
					(mid 0 -13.3096)
					(end 7.3152 -5.9944)
				)
			)
			(stroke
				(width 0)
				(type default)
			)
			(fill no)
			(layer "B.CrtYd")
		)
		(fp_poly
			(pts
				(arc
					(start 7.3152 0)
					(mid 0 7.3152)
					(end -7.3152 0)
				)
				(arc
					(start -7.3152 -5.9944)
					(mid 0 -13.3096)
					(end 7.3152 -5.9944)
				)
			)
			(stroke
				(width 0)
				(type default)
			)
			(fill no)
			(layer "F.CrtYd")
		)
		(fp_poly
			(pts
				(arc
					(start 7.3152 0)
					(mid 0 7.3152)
					(end -7.3152 0)
				)
				(arc
					(start -7.3152 -5.9944)
					(mid 0 -13.3096)
					(end 7.3152 -5.9944)
				)
			)
			(stroke
				(width 0)
				(type default)
			)
			(fill no)
			(layer "B.Fab")
		)
		(fp_poly
			(pts
				(arc
					(start 7.3152 0)
					(mid 0 7.3152)
					(end -7.3152 0)
				)
				(arc
					(start -7.3152 -5.9944)
					(mid 0 -13.3096)
					(end 7.3152 -5.9944)
				)
			)
			(stroke
				(width 0)
				(type default)
			)
			(fill no)
			(layer "F.Fab")
		)
		(pad "1" thru_hole oval
			(at 0 0)
			(size 14.0208 20.0152)
			(drill 0.0254
				(offset 0 -2.9972)
			)
			(layers "*.Cu" "*.Mask")
			(remove_unused_layers no)
			(net "Net_16")
			(clearance -1.002284)
			(thermal_gap 0.1524)
			(padstack
				(mode front_inner_back)
				(layer "Inner"
					(shape custom)
					(size 2.928012 2.928012)
					(options
						(anchor circle)
					)
					(primitives
						(gr_poly
							(pts
								(arc
									(start 4.571746 -2.084324)
									(mid 0.000333 7.430372)
									(end -4.571492 -2.084324)
								)
								(arc
									(start -4.571492 -2.084324)
									(mid -3.570296 -3.611977)
									(end -2.875026 -5.30098)
								)
								(arc
									(start -2.875026 -5.30098)
									(mid 0.000217 -7.43089)
									(end 2.87528 -5.30098)
								)
								(arc
									(start 2.87528 -5.30098)
									(mid 3.570511 -3.611956)
									(end 4.571746 -2.084324)
								)
							)
							(width 0)
							(fill yes)
						)
					)
					(clearance 0.1524)
				)
				(layer "B.Cu"
					(shape oval)
					(size 14.0208 20.0152)
					(offset 0 -2.9972)
					(clearance -1.002284)
				)
			)
		)
		(zone
			(layers "F.Cu" "B.Cu" "In1.Cu" "In2.Cu" "In3.Cu" "In4.Cu" "In5.Cu" "In6.Cu")
			(hatch none 0.5)
			(connect_pads
				(clearance 0)
			)
			(min_thickness 0.25)
			(keepout
				(tracks not_allowed)
				(vias allowed)
				(pads allowed)
				(copperpour not_allowed)
				(footprints allowed)
			)
			(placement
				(enabled no)
				(sheetname "")
			)
			(fill
				(thermal_gap 0.5)
				(thermal_bridge_width 0.5)
				(island_removal_mode 0)
			)
			(polygon
				(pts
					(arc
						(start 182.789576 -209.994246)
						(mid 189.799976 -217.004646)
						(end 196.810376 -209.994246)
					)
					(arc
						(start 196.810376 -203.999846)
						(mid 189.799976 -196.989446)
						(end 182.789576 -203.999846)
					)
				)
			)
		)
	)
	(footprint ""
		(layer "F.Cu")
		(at 424.434 -152.908 180)
		(property "Reference" "C303"
			(at 0 0 180)
			(layer "F.SilkS")
			(hide yes)
			(effects
				(font
					(size 1.27 1.27)
				)
			)
		)
		(property "Value" "SC1U16V3KX-5GP"
			(at 0 -2.8194 180)
			(unlocked yes)
			(layer "F.Fab")
			(hide yes)
			(effects
				(font
					(size 1.016 1.016)
					(thickness 0.1524)
				)
			)
		)
		(property "Device Type" "C603H36"
			(at 0 -4.3434 180)
			(unlocked yes)
			(layer "F.Fab")
			(hide yes)
			(effects
				(font
					(size 1.016 1.016)
					(thickness 0.1524)
				)
			)
		)
		(duplicate_pad_numbers_are_jumpers no)
		(fp_line
			(start 0.508 0)
			(end -0.508 0)
			(stroke
				(width 0.2032)
				(type default)
			)
			(layer "F.SilkS")
		)
		(fp_rect
			(start -0.5842 1.3335)
			(end 0.5842 -1.3335)
			(stroke
				(width 0)
				(type default)
			)
			(fill no)
			(layer "F.CrtYd")
		)
		(fp_rect
			(start -0.5842 1.3335)
			(end 0.5842 -1.3335)
			(stroke
				(width 0)
				(type default)
			)
			(fill no)
			(layer "F.Fab")
		)
		(pad "1" smd custom
			(at 0 -0.762 180)
			(size 0.2159 0.2159)
			(layers "F.Cu" "F.Mask" "F.Paste")
			(net "P5V_HDD21")
			(options
				(clearance outline)
				(anchor circle)
			)
			(primitives
				(gr_poly
					(pts
						(arc
							(start -0.3302 -0.4318)
							(mid -0.402042 -0.402042)
							(end -0.4318 -0.3302)
						)
						(arc
							(start -0.4318 0.3302)
							(mid -0.402042 0.402042)
							(end -0.3302 0.4318)
						)
						(arc
							(start 0.3302 0.4318)
							(mid 0.402042 0.402042)
							(end 0.4318 0.3302)
						)
						(arc
							(start 0.4318 -0.3302)
							(mid 0.402042 -0.402042)
							(end 0.3302 -0.4318)
						)
					)
					(width 0)
					(fill yes)
				)
			)
		)
		(pad "2" smd custom
			(at 0 0.762 180)
			(size 0.2159 0.2159)
			(layers "F.Cu" "F.Mask" "F.Paste")
			(net "GND")
			(options
				(clearance outline)
				(anchor circle)
			)
			(primitives
				(gr_poly
					(pts
						(arc
							(start -0.3302 -0.4318)
							(mid -0.402042 -0.402042)
							(end -0.4318 -0.3302)
						)
						(arc
							(start -0.4318 0.3302)
							(mid -0.402042 0.402042)
							(end -0.3302 0.4318)
						)
						(arc
							(start 0.3302 0.4318)
							(mid 0.402042 0.402042)
							(end 0.4318 0.3302)
						)
						(arc
							(start 0.4318 -0.3302)
							(mid 0.402042 -0.402042)
							(end 0.3302 -0.4318)
						)
					)
					(width 0)
					(fill yes)
				)
			)
		)
	)
	(footprint ""
		(layer "F.Cu")
		(at 332.105 -128.651)
		(property "Reference" "R496"
			(at 0 0 0)
			(layer "F.SilkS")
			(hide yes)
			(effects
				(font
					(size 1.27 1.27)
				)
			)
		)
		(property "Value" "4K7R2F-GP"
			(at 0.064008 -3.993896 0)
			(unlocked yes)
			(layer "F.Fab")
			(hide yes)
			(effects
				(font
					(size 1.016 1.016)
					(thickness 0.1524)
				)
			)
		)
		(property "Device Type" "R402H16"
			(at 0.064008 -5.517896 0)
			(unlocked yes)
			(layer "F.Fab")
			(hide yes)
			(effects
				(font
					(size 1.016 1.016)
					(thickness 0.1524)
				)
			)
		)
		(duplicate_pad_numbers_are_jumpers no)
		(fp_line
			(start -0.508 -0.9398)
			(end -0.508 0.9398)
			(stroke
				(width 0.1524)
				(type default)
			)
			(layer "F.SilkS")
		)
		(fp_line
			(start 0.508 -0.9398)
			(end -0.508 -0.9398)
			(stroke
				(width 0.1524)
				(type default)
			)
			(layer "F.SilkS")
		)
		(fp_rect
			(start -0.508 0.9398)
			(end 0.508 -0.9398)
			(stroke
				(width 0)
				(type default)
			)
			(fill no)
			(layer "F.CrtYd")
		)
		(fp_rect
			(start -0.508 0.9398)
			(end 0.508 -0.9398)
			(stroke
				(width 0)
				(type default)
			)
			(fill no)
			(layer "F.Fab")
		)
		(pad "1" smd custom
			(at 0 -0.4445)
			(size 0.1397 0.1397)
			(layers "F.Cu" "F.Mask" "F.Paste")
			(net "SW_PWR_R_HDD18")
			(options
				(clearance outline)
				(anchor circle)
			)
			(primitives
				(gr_poly
					(pts
						(arc
							(start -0.1778 -0.2794)
							(mid -0.249642 -0.249642)
							(end -0.2794 -0.1778)
						)
						(arc
							(start -0.2794 0.1778)
							(mid -0.249642 0.249642)
							(end -0.1778 0.2794)
						)
						(arc
							(start 0.1778 0.2794)
							(mid 0.249642 0.249642)
							(end 0.2794 0.1778)
						)
						(arc
							(start 0.2794 -0.1778)
							(mid 0.249642 -0.249642)
							(end 0.1778 -0.2794)
						)
					)
					(width 0)
					(fill yes)
				)
			)
		)
		(pad "2" smd custom
			(at 0 0.4445)
			(size 0.1397 0.1397)
			(layers "F.Cu" "F.Mask" "F.Paste")
			(net "GND")
			(options
				(clearance outline)
				(anchor circle)
			)
			(primitives
				(gr_poly
					(pts
						(arc
							(start -0.1778 -0.2794)
							(mid -0.249642 -0.249642)
							(end -0.2794 -0.1778)
						)
						(arc
							(start -0.2794 0.1778)
							(mid -0.249642 0.249642)
							(end -0.1778 0.2794)
						)
						(arc
							(start 0.1778 0.2794)
							(mid 0.249642 0.249642)
							(end 0.2794 0.1778)
						)
						(arc
							(start 0.2794 -0.1778)
							(mid 0.249642 -0.249642)
							(end 0.1778 -0.2794)
						)
					)
					(width 0)
					(fill yes)
				)
			)
		)
	)
	(footprint ""
		(layer "F.Cu")
		(at 114.681 -32.004 -90)
		(property "Reference" "C382"
			(at 0 0 270)
			(layer "F.SilkS")
			(hide yes)
			(effects
				(font
					(size 1.27 1.27)
				)
			)
		)
		(property "Value" "SC10U16V6KX-2GP"
			(at -0.0762 -5.1308 270)
			(unlocked yes)
			(layer "F.Fab")
			(hide yes)
			(effects
				(font
					(size 1.016 1.016)
					(thickness 0.1524)
				)
			)
		)
		(property "Device Type" "C1206H71"
			(at -0.127 -6.6548 270)
			(unlocked yes)
			(layer "F.Fab")
			(hide yes)
			(effects
				(font
					(size 1.016 1.016)
					(thickness 0.1524)
				)
			)
		)
		(duplicate_pad_numbers_are_jumpers no)
		(fp_line
			(start -1.016 2.2352)
			(end -1.016 0.8382)
			(stroke
				(width 0.1524)
				(type default)
			)
			(layer "F.SilkS")
		)
		(fp_line
			(start 1.016 2.2352)
			(end -1.016 2.2352)
			(stroke
				(width 0.1524)
				(type default)
			)
			(layer "F.SilkS")
		)
		(fp_line
			(start 1.016 0.8382)
			(end 1.016 2.2352)
			(stroke
				(width 0.1524)
				(type default)
			)
			(layer "F.SilkS")
		)
		(fp_line
			(start -1.016 -0.8382)
			(end -1.016 -2.2352)
			(stroke
				(width 0.1524)
				(type default)
			)
			(layer "F.SilkS")
		)
		(fp_line
			(start -1.016 -2.2352)
			(end 1.016 -2.2352)
			(stroke
				(width 0.1524)
				(type default)
			)
			(layer "F.SilkS")
		)
		(fp_line
			(start 1.016 -2.2352)
			(end 1.016 -0.8382)
			(stroke
				(width 0.1524)
				(type default)
			)
			(layer "F.SilkS")
		)
		(fp_rect
			(start -1.0922 2.3114)
			(end 1.0922 -2.3114)
			(stroke
				(width 0)
				(type default)
			)
			(fill no)
			(layer "F.CrtYd")
		)
		(fp_poly
			(pts
				(xy 1.0922 -2.3114) (xy 1.0922 2.3114) (xy -1.0922 2.3114) (xy -1.0922 -2.3114)
			)
			(stroke
				(width 0)
				(type default)
			)
			(fill no)
			(layer "F.Fab")
		)
		(pad "1" smd rect
			(at 0 -1.397 270)
			(size 1.651 1.27)
			(layers "F.Cu" "F.Mask" "F.Paste")
			(net "P5V_HDD27")
		)
		(pad "2" smd rect
			(at 0 1.397 270)
			(size 1.651 1.27)
			(layers "F.Cu" "F.Mask" "F.Paste")
			(net "GND")
		)
	)
	(footprint ""
		(layer "F.Cu")
		(at 399.923 -263.017)
		(property "Reference" "Q32"
			(at 0 0 0)
			(layer "F.SilkS")
			(hide yes)
			(effects
				(font
					(size 1.27 1.27)
				)
			)
		)
		(property "Value" "AO4407AL-GP"
			(at -3.707384 -1.5367 0)
			(unlocked yes)
			(layer "F.Fab")
			(hide yes)
			(effects
				(font
					(size 1.016 1.016)
					(thickness 0.1524)
				)
			)
		)
		(property "Device Type" "SOIC8H69"
			(at -3.707384 -3.0607 0)
			(unlocked yes)
			(layer "F.Fab")
			(hide yes)
			(effects
				(font
					(size 1.016 1.016)
					(thickness 0.1524)
				)
			)
		)
		(duplicate_pad_numbers_are_jumpers no)
		(fp_line
			(start -2.7432 -1.4224)
			(end -2.7432 1.4224)
			(stroke
				(width 0.1524)
				(type default)
			)
			(layer "F.SilkS")
		)
		(fp_line
			(start -2.7432 1.4224)
			(end -2.6416 1.4224)
			(stroke
				(width 0.1524)
				(type default)
			)
			(layer "F.SilkS")
		)
		(fp_line
			(start -2.7432 1.4224)
			(end 2.1336 1.4224)
			(stroke
				(width 0.1524)
				(type default)
			)
			(layer "F.SilkS")
		)
		(fp_line
			(start -2.7178 -0.508)
			(end -2.1844 -0.0508)
			(stroke
				(width 0.1524)
				(type default)
			)
			(layer "F.SilkS")
		)
		(fp_line
			(start -2.6289 3.4417)
			(end -2.6289 1.4732)
			(stroke
				(width 0.381)
				(type default)
			)
			(layer "F.SilkS")
		)
		(fp_line
			(start -2.1844 -0.0508)
			(end -2.7178 0.508)
			(stroke
				(width 0.1524)
				(type default)
			)
			(layer "F.SilkS")
		)
		(fp_line
			(start 2.1336 -1.4224)
			(end -2.7432 -1.4224)
			(stroke
				(width 0.1524)
				(type default)
			)
			(layer "F.SilkS")
		)
		(fp_line
			(start 2.1336 1.4224)
			(end 2.1336 -1.4224)
			(stroke
				(width 0.1524)
				(type default)
			)
			(layer "F.SilkS")
		)
		(fp_poly
			(pts
				(xy -2.2098 -1.4224) (xy -2.2098 1.4224) (xy 2.2098 1.4224) (xy 2.2098 -1.4224)
			)
			(stroke
				(width 0)
				(type default)
			)
			(fill yes)
			(layer "F.SilkS")
		)
		(fp_rect
			(start -2.450084 2.999994)
			(end 2.450084 -2.999994)
			(stroke
				(width 0)
				(type default)
			)
			(fill no)
			(layer "F.CrtYd")
		)
		(fp_poly
			(pts
				(xy -2.8194 3.6322) (xy -2.8194 -3.6322) (xy 2.8194 -3.6322) (xy 2.8194 1.18364) (xy 2.450084 1.18364)
				(xy 2.450084 -2.999994) (xy -2.450084 -2.999994) (xy -2.450084 2.999994) (xy 2.450084 2.999994)
				(xy 2.450084 1.18618) (xy 2.8194 1.18618) (xy 2.8194 3.6322)
			)
			(stroke
				(width 0)
				(type default)
			)
			(fill no)
			(layer "F.CrtYd")
		)
		(fp_rect
			(start -2.8194 3.6322)
			(end 2.8194 -3.6322)
			(stroke
				(width 0)
				(type default)
			)
			(fill no)
			(layer "F.Fab")
		)
		(pad "1" smd rect
			(at -1.905 2.54)
			(size 0.635 1.651)
			(layers "F.Cu" "F.Mask" "F.Paste")
			(net "P12V_B")
		)
		(pad "2" smd rect
			(at -0.635 2.54)
			(size 0.635 1.651)
			(layers "F.Cu" "F.Mask" "F.Paste")
			(net "P12V_B")
		)
		(pad "3" smd rect
			(at 0.635 2.54)
			(size 0.635 1.651)
			(layers "F.Cu" "F.Mask" "F.Paste")
			(net "P12V_B")
		)
		(pad "4" smd rect
			(at 1.905 2.54)
			(size 0.635 1.651)
			(layers "F.Cu" "F.Mask" "F.Paste")
			(net "SW_HDD_N8")
		)
		(pad "5" smd rect
			(at 1.905 -2.54)
			(size 0.635 1.651)
			(layers "F.Cu" "F.Mask" "F.Paste")
			(net "P12V_HDD8")
		)
		(pad "6" smd rect
			(at 0.635 -2.54)
			(size 0.635 1.651)
			(layers "F.Cu" "F.Mask" "F.Paste")
			(net "P12V_HDD8")
		)
		(pad "7" smd rect
			(at -0.635 -2.54)
			(size 0.635 1.651)
			(layers "F.Cu" "F.Mask" "F.Paste")
			(net "P12V_HDD8")
		)
		(pad "8" smd rect
			(at -1.905 -2.54)
			(size 0.635 1.651)
			(layers "F.Cu" "F.Mask" "F.Paste")
			(net "P12V_HDD8")
		)
	)
	(footprint ""
		(layer "F.Cu")
		(at 310.82742 -327.858882)
		(property "Reference" "R115"
			(at 0 0 0)
			(layer "F.SilkS")
			(hide yes)
			(effects
				(font
					(size 1.27 1.27)
				)
			)
		)
		(property "Value" "100KR2F-L1-GP"
			(at 0.064008 -3.993896 0)
			(unlocked yes)
			(layer "F.Fab")
			(hide yes)
			(effects
				(font
					(size 1.016 1.016)
					(thickness 0.1524)
				)
			)
		)
		(property "Device Type" "R402H16"
			(at 0.064008 -5.517896 0)
			(unlocked yes)
			(layer "F.Fab")
			(hide yes)
			(effects
				(font
					(size 1.016 1.016)
					(thickness 0.1524)
				)
			)
		)
		(duplicate_pad_numbers_are_jumpers no)
		(fp_line
			(start -0.508 -0.9398)
			(end -0.508 0.9398)
			(stroke
				(width 0.1524)
				(type default)
			)
			(layer "F.SilkS")
		)
		(fp_line
			(start 0.508 -0.9398)
			(end -0.508 -0.9398)
			(stroke
				(width 0.1524)
				(type default)
			)
			(layer "F.SilkS")
		)
		(fp_rect
			(start -0.508 0.9398)
			(end 0.508 -0.9398)
			(stroke
				(width 0)
				(type default)
			)
			(fill no)
			(layer "F.CrtYd")
		)
		(fp_rect
			(start -0.508 0.9398)
			(end 0.508 -0.9398)
			(stroke
				(width 0)
				(type default)
			)
			(fill no)
			(layer "F.Fab")
		)
		(pad "1" smd custom
			(at 0 -0.4445)
			(size 0.1397 0.1397)
			(layers "F.Cu" "F.Mask" "F.Paste")
			(net "PWM_SCC_A_ZONE_D")
			(options
				(clearance outline)
				(anchor circle)
			)
			(primitives
				(gr_poly
					(pts
						(arc
							(start -0.1778 -0.2794)
							(mid -0.249642 -0.249642)
							(end -0.2794 -0.1778)
						)
						(arc
							(start -0.2794 0.1778)
							(mid -0.249642 0.249642)
							(end -0.1778 0.2794)
						)
						(arc
							(start 0.1778 0.2794)
							(mid 0.249642 0.249642)
							(end 0.2794 0.1778)
						)
						(arc
							(start 0.2794 -0.1778)
							(mid 0.249642 -0.249642)
							(end 0.1778 -0.2794)
						)
					)
					(width 0)
					(fill yes)
				)
			)
		)
		(pad "2" smd custom
			(at 0 0.4445)
			(size 0.1397 0.1397)
			(layers "F.Cu" "F.Mask" "F.Paste")
			(net "GND")
			(options
				(clearance outline)
				(anchor circle)
			)
			(primitives
				(gr_poly
					(pts
						(arc
							(start -0.1778 -0.2794)
							(mid -0.249642 -0.249642)
							(end -0.2794 -0.1778)
						)
						(arc
							(start -0.2794 0.1778)
							(mid -0.249642 0.249642)
							(end -0.1778 0.2794)
						)
						(arc
							(start 0.1778 0.2794)
							(mid 0.249642 0.249642)
							(end 0.2794 0.1778)
						)
						(arc
							(start 0.2794 -0.1778)
							(mid 0.249642 -0.249642)
							(end 0.1778 -0.2794)
						)
					)
					(width 0)
					(fill yes)
				)
			)
		)
	)
	(footprint ""
		(layer "F.Cu")
		(at 256.484374 -229.38105 -90)
		(property "Reference" "R166"
			(at 0 0 270)
			(layer "F.SilkS")
			(hide yes)
			(effects
				(font
					(size 1.27 1.27)
				)
			)
		)
		(property "Value" "16K2R2F-GP"
			(at 0.064008 -3.993896 270)
			(unlocked yes)
			(layer "F.Fab")
			(hide yes)
			(effects
				(font
					(size 1.016 1.016)
					(thickness 0.1524)
				)
			)
		)
		(property "Device Type" "R402H16"
			(at 0.064008 -5.517896 270)
			(unlocked yes)
			(layer "F.Fab")
			(hide yes)
			(effects
				(font
					(size 1.016 1.016)
					(thickness 0.1524)
				)
			)
		)
		(duplicate_pad_numbers_are_jumpers no)
		(fp_line
			(start -0.508 -0.9398)
			(end -0.508 0.9398)
			(stroke
				(width 0.1524)
				(type default)
			)
			(layer "F.SilkS")
		)
		(fp_line
			(start 0.508 -0.9398)
			(end -0.508 -0.9398)
			(stroke
				(width 0.1524)
				(type default)
			)
			(layer "F.SilkS")
		)
		(fp_rect
			(start -0.508 0.9398)
			(end 0.508 -0.9398)
			(stroke
				(width 0)
				(type default)
			)
			(fill no)
			(layer "F.CrtYd")
		)
		(fp_rect
			(start -0.508 0.9398)
			(end 0.508 -0.9398)
			(stroke
				(width 0)
				(type default)
			)
			(fill no)
			(layer "F.Fab")
		)
		(pad "1" smd custom
			(at 0 -0.4445 270)
			(size 0.1397 0.1397)
			(layers "F.Cu" "F.Mask" "F.Paste")
			(net "P5V_B_2")
			(options
				(clearance outline)
				(anchor circle)
			)
			(primitives
				(gr_poly
					(pts
						(arc
							(start -0.1778 -0.2794)
							(mid -0.249642 -0.249642)
							(end -0.2794 -0.1778)
						)
						(arc
							(start -0.2794 0.1778)
							(mid -0.249642 0.249642)
							(end -0.1778 0.2794)
						)
						(arc
							(start 0.1778 0.2794)
							(mid 0.249642 0.249642)
							(end 0.2794 0.1778)
						)
						(arc
							(start 0.2794 -0.1778)
							(mid 0.249642 -0.249642)
							(end 0.1778 -0.2794)
						)
					)
					(width 0)
					(fill yes)
				)
			)
		)
		(pad "2" smd custom
			(at 0 0.4445 270)
			(size 0.1397 0.1397)
			(layers "F.Cu" "F.Mask" "F.Paste")
			(net "P5V_B_2_SENSE")
			(options
				(clearance outline)
				(anchor circle)
			)
			(primitives
				(gr_poly
					(pts
						(arc
							(start -0.1778 -0.2794)
							(mid -0.249642 -0.249642)
							(end -0.2794 -0.1778)
						)
						(arc
							(start -0.2794 0.1778)
							(mid -0.249642 0.249642)
							(end -0.1778 0.2794)
						)
						(arc
							(start 0.1778 0.2794)
							(mid 0.249642 0.249642)
							(end 0.2794 0.1778)
						)
						(arc
							(start 0.2794 -0.1778)
							(mid 0.249642 -0.249642)
							(end 0.1778 -0.2794)
						)
					)
					(width 0)
					(fill yes)
				)
			)
		)
	)
	(footprint ""
		(layer "F.Cu")
		(at 66.313812 -39.705026)
		(property "Reference" "TP146"
			(at 0 0 0)
			(layer "F.SilkS")
			(hide yes)
			(effects
				(font
					(size 1.27 1.27)
				)
			)
		)
		(property "Value" "*"
			(at -0.0508 -1.6764 0)
			(unlocked yes)
			(layer "F.Fab")
			(hide yes)
			(effects
				(font
					(size 1.016 1.016)
					(thickness 0.1524)
				)
			)
		)
		(property "Device Type" "TPAD32"
			(at -0.0508 -3.2004 0)
			(unlocked yes)
			(layer "F.Fab")
			(hide yes)
			(effects
				(font
					(size 1.016 1.016)
					(thickness 0.1524)
				)
			)
		)
		(duplicate_pad_numbers_are_jumpers no)
		(fp_poly
			(pts
				(arc
					(start 0.4064 0)
					(mid -0.4064 0)
					(end 0.4064 0)
				)
			)
			(stroke
				(width 0)
				(type default)
			)
			(fill no)
			(layer "F.CrtYd")
		)
		(fp_poly
			(pts
				(arc
					(start 0.7112 0)
					(mid -0.7112 0)
					(end 0.7112 0)
				)
			)
			(stroke
				(width 0)
				(type default)
			)
			(fill no)
			(layer "F.Fab")
		)
		(pad "1" smd circle
			(at 0 0)
			(size 0.8128 0.8128)
			(layers "F.Cu" "F.Mask" "F.Paste")
			(net "ACT_HDD_25")
		)
	)
	(footprint ""
		(layer "F.Cu")
		(at 335.788 -131.826 180)
		(property "Reference" "R501"
			(at 0 0 180)
			(layer "F.SilkS")
			(hide yes)
			(effects
				(font
					(size 1.27 1.27)
				)
			)
		)
		(property "Value" "0R2J-2-GP"
			(at 0.064008 -3.993896 180)
			(unlocked yes)
			(layer "F.Fab")
			(hide yes)
			(effects
				(font
					(size 1.016 1.016)
					(thickness 0.1524)
				)
			)
		)
		(property "Device Type" "R402H16"
			(at 0.064008 -5.517896 180)
			(unlocked yes)
			(layer "F.Fab")
			(hide yes)
			(effects
				(font
					(size 1.016 1.016)
					(thickness 0.1524)
				)
			)
		)
		(duplicate_pad_numbers_are_jumpers no)
		(fp_line
			(start 0.508 -0.9398)
			(end -0.508 -0.9398)
			(stroke
				(width 0.1524)
				(type default)
			)
			(layer "F.SilkS")
		)
		(fp_line
			(start -0.508 -0.9398)
			(end -0.508 0.9398)
			(stroke
				(width 0.1524)
				(type default)
			)
			(layer "F.SilkS")
		)
		(fp_rect
			(start -0.508 0.9398)
			(end 0.508 -0.9398)
			(stroke
				(width 0)
				(type default)
			)
			(fill no)
			(layer "F.CrtYd")
		)
		(fp_rect
			(start -0.508 0.9398)
			(end 0.508 -0.9398)
			(stroke
				(width 0)
				(type default)
			)
			(fill no)
			(layer "F.Fab")
		)
		(pad "1" smd custom
			(at 0 -0.4445 180)
			(size 0.1397 0.1397)
			(layers "F.Cu" "F.Mask" "F.Paste")
			(net "SW_HDD_G18")
			(options
				(clearance outline)
				(anchor circle)
			)
			(primitives
				(gr_poly
					(pts
						(arc
							(start -0.1778 -0.2794)
							(mid -0.249642 -0.249642)
							(end -0.2794 -0.1778)
						)
						(arc
							(start -0.2794 0.1778)
							(mid -0.249642 0.249642)
							(end -0.1778 0.2794)
						)
						(arc
							(start 0.1778 0.2794)
							(mid 0.249642 0.249642)
							(end 0.2794 0.1778)
						)
						(arc
							(start 0.2794 -0.1778)
							(mid 0.249642 -0.249642)
							(end 0.1778 -0.2794)
						)
					)
					(width 0)
					(fill yes)
				)
			)
		)
		(pad "2" smd custom
			(at 0 0.4445 180)
			(size 0.1397 0.1397)
			(layers "F.Cu" "F.Mask" "F.Paste")
			(net "SW_HDD_R18")
			(options
				(clearance outline)
				(anchor circle)
			)
			(primitives
				(gr_poly
					(pts
						(arc
							(start -0.1778 -0.2794)
							(mid -0.249642 -0.249642)
							(end -0.2794 -0.1778)
						)
						(arc
							(start -0.2794 0.1778)
							(mid -0.249642 0.249642)
							(end -0.1778 0.2794)
						)
						(arc
							(start 0.1778 0.2794)
							(mid 0.249642 0.249642)
							(end 0.2794 0.1778)
						)
						(arc
							(start 0.2794 -0.1778)
							(mid 0.249642 -0.249642)
							(end 0.1778 -0.2794)
						)
					)
					(width 0)
					(fill yes)
				)
			)
		)
	)
	(footprint ""
		(layer "F.Cu")
		(at 16.764 -139.065 -90)
		(property "Reference" "C194"
			(at 0 0 270)
			(layer "F.SilkS")
			(hide yes)
			(effects
				(font
					(size 1.27 1.27)
				)
			)
		)
		(property "Value" "SCD033U25V2KX-GP"
			(at 1.1811 -2.7051 270)
			(unlocked yes)
			(layer "F.Fab")
			(hide yes)
			(effects
				(font
					(size 1.016 1.016)
					(thickness 0.1524)
				)
			)
		)
		(property "Device Type" "C402H22"
			(at 1.1811 -4.2291 270)
			(unlocked yes)
			(layer "F.Fab")
			(hide yes)
			(effects
				(font
					(size 1.016 1.016)
					(thickness 0.1524)
				)
			)
		)
		(duplicate_pad_numbers_are_jumpers no)
		(fp_rect
			(start -0.4318 0.9525)
			(end 0.4318 -0.9525)
			(stroke
				(width 0)
				(type default)
			)
			(fill no)
			(layer "F.CrtYd")
		)
		(fp_rect
			(start -0.4318 0.9525)
			(end 0.4318 -0.9525)
			(stroke
				(width 0)
				(type default)
			)
			(fill no)
			(layer "F.Fab")
		)
		(pad "1" smd custom
			(at 0 -0.4445 270)
			(size 0.1524 0.1524)
			(layers "F.Cu" "F.Mask" "F.Paste")
			(net "SW_HDD_P12")
			(options
				(clearance outline)
				(anchor circle)
			)
			(primitives
				(gr_poly
					(pts
						(arc
							(start 0.3048 -0.2032)
							(mid 0.275042 -0.275042)
							(end 0.2032 -0.3048)
						)
						(arc
							(start -0.2032 -0.3048)
							(mid -0.275042 -0.275042)
							(end -0.3048 -0.2032)
						)
						(arc
							(start -0.3048 0.2032)
							(mid -0.275042 0.275042)
							(end -0.2032 0.3048)
						)
						(arc
							(start 0.2032 0.3048)
							(mid 0.275042 0.275042)
							(end 0.3048 0.2032)
						)
					)
					(width 0)
					(fill yes)
				)
			)
		)
		(pad "2" smd custom
			(at 0 0.4445 270)
			(size 0.1524 0.1524)
			(layers "F.Cu" "F.Mask" "F.Paste")
			(net "GND")
			(options
				(clearance outline)
				(anchor circle)
			)
			(primitives
				(gr_poly
					(pts
						(arc
							(start 0.3048 -0.2032)
							(mid 0.275042 -0.275042)
							(end 0.2032 -0.3048)
						)
						(arc
							(start -0.2032 -0.3048)
							(mid -0.275042 -0.275042)
							(end -0.3048 -0.2032)
						)
						(arc
							(start -0.3048 0.2032)
							(mid -0.275042 0.275042)
							(end -0.2032 0.3048)
						)
						(arc
							(start 0.2032 0.3048)
							(mid 0.275042 0.275042)
							(end 0.3048 0.2032)
						)
					)
					(width 0)
					(fill yes)
				)
			)
		)
	)
	(footprint ""
		(layer "F.Cu")
		(at 50.82286 -120.977406)
		(property "Reference" "R1116"
			(at 0 0 0)
			(layer "F.SilkS")
			(hide yes)
			(effects
				(font
					(size 1.27 1.27)
				)
			)
		)
		(property "Value" "49K9R2F-L-GP"
			(at 0.064008 -3.993896 0)
			(unlocked yes)
			(layer "F.Fab")
			(hide yes)
			(effects
				(font
					(size 1.016 1.016)
					(thickness 0.1524)
				)
			)
		)
		(property "Device Type" "R402H16"
			(at 0.064008 -5.517896 0)
			(unlocked yes)
			(layer "F.Fab")
			(hide yes)
			(effects
				(font
					(size 1.016 1.016)
					(thickness 0.1524)
				)
			)
		)
		(duplicate_pad_numbers_are_jumpers no)
		(fp_line
			(start -0.508 -0.9398)
			(end -0.508 0.9398)
			(stroke
				(width 0.1524)
				(type default)
			)
			(layer "F.SilkS")
		)
		(fp_line
			(start 0.508 -0.9398)
			(end -0.508 -0.9398)
			(stroke
				(width 0.1524)
				(type default)
			)
			(layer "F.SilkS")
		)
		(fp_rect
			(start -0.508 0.9398)
			(end 0.508 -0.9398)
			(stroke
				(width 0)
				(type default)
			)
			(fill no)
			(layer "F.CrtYd")
		)
		(fp_rect
			(start -0.508 0.9398)
			(end 0.508 -0.9398)
			(stroke
				(width 0)
				(type default)
			)
			(fill no)
			(layer "F.Fab")
		)
		(pad "1" smd custom
			(at 0 -0.4445)
			(size 0.1397 0.1397)
			(layers "F.Cu" "F.Mask" "F.Paste")
			(net "P12V_B")
			(options
				(clearance outline)
				(anchor circle)
			)
			(primitives
				(gr_poly
					(pts
						(arc
							(start -0.1778 -0.2794)
							(mid -0.249642 -0.249642)
							(end -0.2794 -0.1778)
						)
						(arc
							(start -0.2794 0.1778)
							(mid -0.249642 0.249642)
							(end -0.1778 0.2794)
						)
						(arc
							(start 0.1778 0.2794)
							(mid 0.249642 0.249642)
							(end 0.2794 0.1778)
						)
						(arc
							(start 0.2794 -0.1778)
							(mid 0.249642 -0.249642)
							(end 0.1778 -0.2794)
						)
					)
					(width 0)
					(fill yes)
				)
			)
		)
		(pad "2" smd custom
			(at 0 0.4445)
			(size 0.1397 0.1397)
			(layers "F.Cu" "F.Mask" "F.Paste")
			(net "P5V_B_2_EN_R")
			(options
				(clearance outline)
				(anchor circle)
			)
			(primitives
				(gr_poly
					(pts
						(arc
							(start -0.1778 -0.2794)
							(mid -0.249642 -0.249642)
							(end -0.2794 -0.1778)
						)
						(arc
							(start -0.2794 0.1778)
							(mid -0.249642 0.249642)
							(end -0.1778 0.2794)
						)
						(arc
							(start 0.1778 0.2794)
							(mid 0.249642 0.249642)
							(end 0.2794 0.1778)
						)
						(arc
							(start 0.2794 -0.1778)
							(mid 0.249642 -0.249642)
							(end 0.1778 -0.2794)
						)
					)
					(width 0)
					(fill yes)
				)
			)
		)
	)
	(footprint ""
		(layer "F.Cu")
		(at 176.657 -35.687 90)
		(property "Reference" "R738"
			(at 0 0 90)
			(layer "F.SilkS")
			(hide yes)
			(effects
				(font
					(size 1.27 1.27)
				)
			)
		)
		(property "Value" "2R6F-GP"
			(at -0.0508 -4.8514 90)
			(unlocked yes)
			(layer "F.Fab")
			(hide yes)
			(effects
				(font
					(size 1.016 1.016)
					(thickness 0.1524)
				)
			)
		)
		(property "Device Type" "R1206H26"
			(at 0 -6.3754 90)
			(unlocked yes)
			(layer "F.Fab")
			(hide yes)
			(effects
				(font
					(size 1.016 1.016)
					(thickness 0.1524)
				)
			)
		)
		(duplicate_pad_numbers_are_jumpers no)
		(fp_line
			(start 1.016 -2.2352)
			(end 1.016 2.2352)
			(stroke
				(width 0.1524)
				(type default)
			)
			(layer "F.SilkS")
		)
		(fp_line
			(start -1.016 -2.2352)
			(end 1.016 -2.2352)
			(stroke
				(width 0.1524)
				(type default)
			)
			(layer "F.SilkS")
		)
		(fp_line
			(start 1.016 2.2352)
			(end -1.016 2.2352)
			(stroke
				(width 0.1524)
				(type default)
			)
			(layer "F.SilkS")
		)
		(fp_line
			(start -1.016 2.2352)
			(end -1.016 -2.2352)
			(stroke
				(width 0.1524)
				(type default)
			)
			(layer "F.SilkS")
		)
		(fp_rect
			(start -1.0922 2.3114)
			(end 1.0922 -2.3114)
			(stroke
				(width 0)
				(type default)
			)
			(fill no)
			(layer "F.CrtYd")
		)
		(fp_poly
			(pts
				(xy -1.0922 -2.3114) (xy 1.0922 -2.3114) (xy 1.0922 2.3114) (xy -1.0922 2.3114)
			)
			(stroke
				(width 0)
				(type default)
			)
			(fill no)
			(layer "F.Fab")
		)
		(pad "1" smd rect
			(at 0 -1.397 90)
			(size 1.651 1.27)
			(layers "F.Cu" "F.Mask" "F.Paste")
			(net "P12V_HDD29")
		)
		(pad "2" smd rect
			(at 0 1.397 90)
			(size 1.651 1.27)
			(layers "F.Cu" "F.Mask" "F.Paste")
			(net "12V_PRE_29")
		)
	)
	(footprint ""
		(layer "F.Cu")
		(at 446.9384 -31.6484 180)
		(property "Reference" "R852"
			(at 0 0 180)
			(layer "F.SilkS")
			(hide yes)
			(effects
				(font
					(size 1.27 1.27)
				)
			)
		)
		(property "Value" "10KR2F-2-GP"
			(at 0.064008 -3.993896 180)
			(unlocked yes)
			(layer "F.Fab")
			(hide yes)
			(effects
				(font
					(size 1.016 1.016)
					(thickness 0.1524)
				)
			)
		)
		(property "Device Type" "R402H16"
			(at 0.064008 -5.517896 180)
			(unlocked yes)
			(layer "F.Fab")
			(hide yes)
			(effects
				(font
					(size 1.016 1.016)
					(thickness 0.1524)
				)
			)
		)
		(duplicate_pad_numbers_are_jumpers no)
		(fp_line
			(start 0.508 -0.9398)
			(end -0.508 -0.9398)
			(stroke
				(width 0.1524)
				(type default)
			)
			(layer "F.SilkS")
		)
		(fp_line
			(start -0.508 -0.9398)
			(end -0.508 0.9398)
			(stroke
				(width 0.1524)
				(type default)
			)
			(layer "F.SilkS")
		)
		(fp_rect
			(start -0.508 0.9398)
			(end 0.508 -0.9398)
			(stroke
				(width 0)
				(type default)
			)
			(fill no)
			(layer "F.CrtYd")
		)
		(fp_rect
			(start -0.508 0.9398)
			(end 0.508 -0.9398)
			(stroke
				(width 0)
				(type default)
			)
			(fill no)
			(layer "F.Fab")
		)
		(pad "1" smd custom
			(at 0 -0.4445 180)
			(size 0.1397 0.1397)
			(layers "F.Cu" "F.Mask" "F.Paste")
			(net "P3V3_STBY_B")
			(options
				(clearance outline)
				(anchor circle)
			)
			(primitives
				(gr_poly
					(pts
						(arc
							(start -0.1778 -0.2794)
							(mid -0.249642 -0.249642)
							(end -0.2794 -0.1778)
						)
						(arc
							(start -0.2794 0.1778)
							(mid -0.249642 0.249642)
							(end -0.1778 0.2794)
						)
						(arc
							(start 0.1778 0.2794)
							(mid 0.249642 0.249642)
							(end 0.2794 0.1778)
						)
						(arc
							(start 0.2794 -0.1778)
							(mid 0.249642 -0.249642)
							(end 0.1778 -0.2794)
						)
					)
					(width 0)
					(fill yes)
				)
			)
		)
		(pad "2" smd custom
			(at 0 0.4445 180)
			(size 0.1397 0.1397)
			(layers "F.Cu" "F.Mask" "F.Paste")
			(net "HDD_PRSNT_34")
			(options
				(clearance outline)
				(anchor circle)
			)
			(primitives
				(gr_poly
					(pts
						(arc
							(start -0.1778 -0.2794)
							(mid -0.249642 -0.249642)
							(end -0.2794 -0.1778)
						)
						(arc
							(start -0.2794 0.1778)
							(mid -0.249642 0.249642)
							(end -0.1778 0.2794)
						)
						(arc
							(start 0.1778 0.2794)
							(mid 0.249642 0.249642)
							(end 0.2794 0.1778)
						)
						(arc
							(start 0.2794 -0.1778)
							(mid 0.249642 -0.249642)
							(end 0.1778 -0.2794)
						)
					)
					(width 0)
					(fill yes)
				)
			)
		)
	)
	(footprint ""
		(layer "F.Cu")
		(at 332.105 -246.253 -90)
		(property "Reference" "Q23"
			(at 0 0 270)
			(layer "F.SilkS")
			(hide yes)
			(effects
				(font
					(size 1.27 1.27)
				)
			)
		)
		(property "Value" "2N7002KDW-GP"
			(at -2.3622 -8.2042 270)
			(unlocked yes)
			(layer "F.Fab")
			(hide yes)
			(effects
				(font
					(size 1.016 1.016)
					(thickness 0.1524)
				)
			)
		)
		(property "Device Type" "SOT-363H44"
			(at -2.3622 -10.1092 270)
			(unlocked yes)
			(layer "F.Fab")
			(hide yes)
			(effects
				(font
					(size 1.016 1.016)
					(thickness 0.1524)
				)
			)
		)
		(duplicate_pad_numbers_are_jumpers no)
		(fp_line
			(start -1.4478 1.7018)
			(end 1.4478 1.7018)
			(stroke
				(width 0.1524)
				(type default)
			)
			(layer "F.SilkS")
		)
		(fp_line
			(start 1.4478 1.7018)
			(end 1.4478 -1.7018)
			(stroke
				(width 0.1524)
				(type default)
			)
			(layer "F.SilkS")
		)
		(fp_line
			(start -1.27 1.524)
			(end -1.27 0.6604)
			(stroke
				(width 0.4826)
				(type default)
			)
			(layer "F.SilkS")
		)
		(fp_line
			(start -1.4478 -1.7018)
			(end -1.4478 1.7018)
			(stroke
				(width 0.1524)
				(type default)
			)
			(layer "F.SilkS")
		)
		(fp_line
			(start 1.4478 -1.7018)
			(end -1.4478 -1.7018)
			(stroke
				(width 0.1524)
				(type default)
			)
			(layer "F.SilkS")
		)
		(fp_poly
			(pts
				(xy -1.524 -1.778) (xy 1.524 -1.778) (xy 1.524 1.778) (xy -1.524 1.778)
			)
			(stroke
				(width 0)
				(type default)
			)
			(fill no)
			(layer "F.CrtYd")
		)
		(fp_poly
			(pts
				(xy -1.524 -1.778) (xy 1.524 -1.778) (xy 1.524 1.778) (xy -1.524 1.778)
			)
			(stroke
				(width 0)
				(type default)
			)
			(fill no)
			(layer "F.Fab")
		)
		(pad "1" smd rect
			(at -0.65024 0.9398 270)
			(size 0.4064 1.016)
			(layers "F.Cu" "F.Mask" "F.Paste")
			(net "GND")
		)
		(pad "2" smd rect
			(at 0 0.9398 270)
			(size 0.4064 1.016)
			(layers "F.Cu" "F.Mask" "F.Paste")
			(net "SW_PWR_R_HDD6")
		)
		(pad "3" smd rect
			(at 0.65024 0.9398 270)
			(size 0.4064 1.016)
			(layers "F.Cu" "F.Mask" "F.Paste")
			(net "SW_HDD_P6")
		)
		(pad "4" smd rect
			(at 0.65024 -0.9398 270)
			(size 0.4064 1.016)
			(layers "F.Cu" "F.Mask" "F.Paste")
			(net "GND")
		)
		(pad "5" smd rect
			(at 0 -0.9398 270)
			(size 0.4064 1.016)
			(layers "F.Cu" "F.Mask" "F.Paste")
			(net "SW_HDD_G6")
		)
		(pad "6" smd rect
			(at -0.65024 -0.9398 270)
			(size 0.4064 1.016)
			(layers "F.Cu" "F.Mask" "F.Paste")
			(net "SW_HDD_R6")
		)
	)
	(footprint ""
		(layer "F.Cu")
		(at 77.978 -246.634 90)
		(property "Reference" "R200"
			(at 0 0 90)
			(layer "F.SilkS")
			(hide yes)
			(effects
				(font
					(size 1.27 1.27)
				)
			)
		)
		(property "Value" "4K7R2J-2-GP"
			(at 0.064008 -3.993896 90)
			(unlocked yes)
			(layer "F.Fab")
			(hide yes)
			(effects
				(font
					(size 1.016 1.016)
					(thickness 0.1524)
				)
			)
		)
		(property "Device Type" "R402H16"
			(at 0.064008 -5.517896 90)
			(unlocked yes)
			(layer "F.Fab")
			(hide yes)
			(effects
				(font
					(size 1.016 1.016)
					(thickness 0.1524)
				)
			)
		)
		(duplicate_pad_numbers_are_jumpers no)
		(fp_line
			(start 0.508 -0.9398)
			(end -0.508 -0.9398)
			(stroke
				(width 0.1524)
				(type default)
			)
			(layer "F.SilkS")
		)
		(fp_line
			(start -0.508 -0.9398)
			(end -0.508 0.9398)
			(stroke
				(width 0.1524)
				(type default)
			)
			(layer "F.SilkS")
		)
		(fp_rect
			(start -0.508 0.9398)
			(end 0.508 -0.9398)
			(stroke
				(width 0)
				(type default)
			)
			(fill no)
			(layer "F.CrtYd")
		)
		(fp_rect
			(start -0.508 0.9398)
			(end 0.508 -0.9398)
			(stroke
				(width 0)
				(type default)
			)
			(fill no)
			(layer "F.Fab")
		)
		(pad "1" smd custom
			(at 0 -0.4445 90)
			(size 0.1397 0.1397)
			(layers "F.Cu" "F.Mask" "F.Paste")
			(net "P12V_B")
			(options
				(clearance outline)
				(anchor circle)
			)
			(primitives
				(gr_poly
					(pts
						(arc
							(start -0.1778 -0.2794)
							(mid -0.249642 -0.249642)
							(end -0.2794 -0.1778)
						)
						(arc
							(start -0.2794 0.1778)
							(mid -0.249642 0.249642)
							(end -0.1778 0.2794)
						)
						(arc
							(start 0.1778 0.2794)
							(mid 0.249642 0.249642)
							(end 0.2794 0.1778)
						)
						(arc
							(start 0.2794 -0.1778)
							(mid 0.249642 -0.249642)
							(end 0.1778 -0.2794)
						)
					)
					(width 0)
					(fill yes)
				)
			)
		)
		(pad "2" smd custom
			(at 0 0.4445 90)
			(size 0.1397 0.1397)
			(layers "F.Cu" "F.Mask" "F.Paste")
			(net "SW_HDD_R2")
			(options
				(clearance outline)
				(anchor circle)
			)
			(primitives
				(gr_poly
					(pts
						(arc
							(start -0.1778 -0.2794)
							(mid -0.249642 -0.249642)
							(end -0.2794 -0.1778)
						)
						(arc
							(start -0.2794 0.1778)
							(mid -0.249642 0.249642)
							(end -0.1778 0.2794)
						)
						(arc
							(start 0.1778 0.2794)
							(mid 0.249642 0.249642)
							(end 0.2794 0.1778)
						)
						(arc
							(start 0.2794 -0.1778)
							(mid 0.249642 -0.249642)
							(end 0.1778 -0.2794)
						)
					)
					(width 0)
					(fill yes)
				)
			)
		)
	)
	(footprint ""
		(layer "F.Cu")
		(at 429.514 -253.873 -90)
		(property "Reference" "Q34"
			(at 0 0 270)
			(layer "F.SilkS")
			(hide yes)
			(effects
				(font
					(size 1.27 1.27)
				)
			)
		)
		(property "Value" "AO4406AL-GP"
			(at -3.707384 -1.5367 270)
			(unlocked yes)
			(layer "F.Fab")
			(hide yes)
			(effects
				(font
					(size 1.016 1.016)
					(thickness 0.1524)
				)
			)
		)
		(property "Device Type" "SOIC8H69"
			(at -3.707384 -3.0607 270)
			(unlocked yes)
			(layer "F.Fab")
			(hide yes)
			(effects
				(font
					(size 1.016 1.016)
					(thickness 0.1524)
				)
			)
		)
		(duplicate_pad_numbers_are_jumpers no)
		(fp_line
			(start -2.6289 3.4417)
			(end -2.6289 1.4732)
			(stroke
				(width 0.381)
				(type default)
			)
			(layer "F.SilkS")
		)
		(fp_line
			(start -2.7432 1.4224)
			(end -2.6416 1.4224)
			(stroke
				(width 0.1524)
				(type default)
			)
			(layer "F.SilkS")
		)
		(fp_line
			(start -2.7432 1.4224)
			(end 2.1336 1.4224)
			(stroke
				(width 0.1524)
				(type default)
			)
			(layer "F.SilkS")
		)
		(fp_line
			(start 2.1336 1.4224)
			(end 2.1336 -1.4224)
			(stroke
				(width 0.1524)
				(type default)
			)
			(layer "F.SilkS")
		)
		(fp_line
			(start -2.1844 -0.0508)
			(end -2.7178 0.508)
			(stroke
				(width 0.1524)
				(type default)
			)
			(layer "F.SilkS")
		)
		(fp_line
			(start -2.7178 -0.508)
			(end -2.1844 -0.0508)
			(stroke
				(width 0.1524)
				(type default)
			)
			(layer "F.SilkS")
		)
		(fp_line
			(start -2.7432 -1.4224)
			(end -2.7432 1.4224)
			(stroke
				(width 0.1524)
				(type default)
			)
			(layer "F.SilkS")
		)
		(fp_line
			(start 2.1336 -1.4224)
			(end -2.7432 -1.4224)
			(stroke
				(width 0.1524)
				(type default)
			)
			(layer "F.SilkS")
		)
		(fp_poly
			(pts
				(xy -2.2098 -1.4224) (xy -2.2098 1.4224) (xy 2.2098 1.4224) (xy 2.2098 -1.4224)
			)
			(stroke
				(width 0)
				(type default)
			)
			(fill yes)
			(layer "F.SilkS")
		)
		(fp_rect
			(start -2.450084 2.999994)
			(end 2.450084 -2.999994)
			(stroke
				(width 0)
				(type default)
			)
			(fill no)
			(layer "F.CrtYd")
		)
		(fp_poly
			(pts
				(xy -2.8194 3.6322) (xy -2.8194 -3.6322) (xy 2.8194 -3.6322) (xy 2.8194 1.18364) (xy 2.450084 1.18364)
				(xy 2.450084 -2.999994) (xy -2.450084 -2.999994) (xy -2.450084 2.999994) (xy 2.450084 2.999994)
				(xy 2.450084 1.18618) (xy 2.8194 1.18618) (xy 2.8194 3.6322)
			)
			(stroke
				(width 0)
				(type default)
			)
			(fill no)
			(layer "F.CrtYd")
		)
		(fp_rect
			(start -2.8194 3.6322)
			(end 2.8194 -3.6322)
			(stroke
				(width 0)
				(type default)
			)
			(fill no)
			(layer "F.Fab")
		)
		(pad "1" smd rect
			(at -1.905 2.54 270)
			(size 0.635 1.651)
			(layers "F.Cu" "F.Mask" "F.Paste")
			(net "P5V_HDD9")
		)
		(pad "2" smd rect
			(at -0.635 2.54 270)
			(size 0.635 1.651)
			(layers "F.Cu" "F.Mask" "F.Paste")
			(net "P5V_HDD9")
		)
		(pad "3" smd rect
			(at 0.635 2.54 270)
			(size 0.635 1.651)
			(layers "F.Cu" "F.Mask" "F.Paste")
			(net "P5V_HDD9")
		)
		(pad "4" smd rect
			(at 1.905 2.54 270)
			(size 0.635 1.651)
			(layers "F.Cu" "F.Mask" "F.Paste")
			(net "SW_HDD_P9")
		)
		(pad "5" smd rect
			(at 1.905 -2.54 270)
			(size 0.635 1.651)
			(layers "F.Cu" "F.Mask" "F.Paste")
			(net "P5V_B_3")
		)
		(pad "6" smd rect
			(at 0.635 -2.54 270)
			(size 0.635 1.651)
			(layers "F.Cu" "F.Mask" "F.Paste")
			(net "P5V_B_3")
		)
		(pad "7" smd rect
			(at -0.635 -2.54 270)
			(size 0.635 1.651)
			(layers "F.Cu" "F.Mask" "F.Paste")
			(net "P5V_B_3")
		)
		(pad "8" smd rect
			(at -1.905 -2.54 270)
			(size 0.635 1.651)
			(layers "F.Cu" "F.Mask" "F.Paste")
			(net "P5V_B_3")
		)
	)
	(footprint ""
		(layer "F.Cu")
		(at 282.829 -345.059 -90)
		(property "Reference" "R493"
			(at 0 0 270)
			(layer "F.SilkS")
			(hide yes)
			(effects
				(font
					(size 1.27 1.27)
				)
			)
		)
		(property "Value" "10KR2F-2-GP"
			(at 0.064008 -3.993896 270)
			(unlocked yes)
			(layer "F.Fab")
			(hide yes)
			(effects
				(font
					(size 1.016 1.016)
					(thickness 0.1524)
				)
			)
		)
		(property "Device Type" "R402H16"
			(at 0.064008 -5.517896 270)
			(unlocked yes)
			(layer "F.Fab")
			(hide yes)
			(effects
				(font
					(size 1.016 1.016)
					(thickness 0.1524)
				)
			)
		)
		(duplicate_pad_numbers_are_jumpers no)
		(fp_line
			(start -0.508 -0.9398)
			(end -0.508 0.9398)
			(stroke
				(width 0.1524)
				(type default)
			)
			(layer "F.SilkS")
		)
		(fp_line
			(start 0.508 -0.9398)
			(end -0.508 -0.9398)
			(stroke
				(width 0.1524)
				(type default)
			)
			(layer "F.SilkS")
		)
		(fp_rect
			(start -0.508 0.9398)
			(end 0.508 -0.9398)
			(stroke
				(width 0)
				(type default)
			)
			(fill no)
			(layer "F.CrtYd")
		)
		(fp_rect
			(start -0.508 0.9398)
			(end 0.508 -0.9398)
			(stroke
				(width 0)
				(type default)
			)
			(fill no)
			(layer "F.Fab")
		)
		(pad "1" smd custom
			(at 0 -0.4445 270)
			(size 0.1397 0.1397)
			(layers "F.Cu" "F.Mask" "F.Paste")
			(net "P12V_IN")
			(options
				(clearance outline)
				(anchor circle)
			)
			(primitives
				(gr_poly
					(pts
						(arc
							(start -0.1778 -0.2794)
							(mid -0.249642 -0.249642)
							(end -0.2794 -0.1778)
						)
						(arc
							(start -0.2794 0.1778)
							(mid -0.249642 0.249642)
							(end -0.1778 0.2794)
						)
						(arc
							(start 0.1778 0.2794)
							(mid 0.249642 0.249642)
							(end 0.2794 0.1778)
						)
						(arc
							(start 0.2794 -0.1778)
							(mid 0.249642 -0.249642)
							(end 0.1778 -0.2794)
						)
					)
					(width 0)
					(fill yes)
				)
			)
		)
		(pad "2" smd custom
			(at 0 0.4445 270)
			(size 0.1397 0.1397)
			(layers "F.Cu" "F.Mask" "F.Paste")
			(net "P3V3_IN_EN")
			(options
				(clearance outline)
				(anchor circle)
			)
			(primitives
				(gr_poly
					(pts
						(arc
							(start -0.1778 -0.2794)
							(mid -0.249642 -0.249642)
							(end -0.2794 -0.1778)
						)
						(arc
							(start -0.2794 0.1778)
							(mid -0.249642 0.249642)
							(end -0.1778 0.2794)
						)
						(arc
							(start 0.1778 0.2794)
							(mid 0.249642 0.249642)
							(end 0.2794 0.1778)
						)
						(arc
							(start 0.2794 -0.1778)
							(mid 0.249642 -0.249642)
							(end 0.1778 -0.2794)
						)
					)
					(width 0)
					(fill yes)
				)
			)
		)
	)
	(footprint ""
		(layer "F.Cu")
		(at 32.149796 -375.6914 -90)
		(property "Reference" "R1305"
			(at 0 0 270)
			(layer "F.SilkS")
			(hide yes)
			(effects
				(font
					(size 1.27 1.27)
				)
			)
		)
		(property "Value" "4K7R2F-GP"
			(at 0.064008 -3.993896 270)
			(unlocked yes)
			(layer "F.Fab")
			(hide yes)
			(effects
				(font
					(size 1.016 1.016)
					(thickness 0.1524)
				)
			)
		)
		(property "Device Type" "R402H16"
			(at 0.064008 -5.517896 270)
			(unlocked yes)
			(layer "F.Fab")
			(hide yes)
			(effects
				(font
					(size 1.016 1.016)
					(thickness 0.1524)
				)
			)
		)
		(duplicate_pad_numbers_are_jumpers no)
		(fp_line
			(start -0.508 -0.9398)
			(end -0.508 0.9398)
			(stroke
				(width 0.1524)
				(type default)
			)
			(layer "F.SilkS")
		)
		(fp_line
			(start 0.508 -0.9398)
			(end -0.508 -0.9398)
			(stroke
				(width 0.1524)
				(type default)
			)
			(layer "F.SilkS")
		)
		(fp_rect
			(start -0.508 0.9398)
			(end 0.508 -0.9398)
			(stroke
				(width 0)
				(type default)
			)
			(fill no)
			(layer "F.CrtYd")
		)
		(fp_rect
			(start -0.508 0.9398)
			(end 0.508 -0.9398)
			(stroke
				(width 0)
				(type default)
			)
			(fill no)
			(layer "F.Fab")
		)
		(pad "1" smd custom
			(at 0 -0.4445 270)
			(size 0.1397 0.1397)
			(layers "F.Cu" "F.Mask" "F.Paste")
			(net "FAN_YELLOW_LED0")
			(options
				(clearance outline)
				(anchor circle)
			)
			(primitives
				(gr_poly
					(pts
						(arc
							(start -0.1778 -0.2794)
							(mid -0.249642 -0.249642)
							(end -0.2794 -0.1778)
						)
						(arc
							(start -0.2794 0.1778)
							(mid -0.249642 0.249642)
							(end -0.1778 0.2794)
						)
						(arc
							(start 0.1778 0.2794)
							(mid 0.249642 0.249642)
							(end 0.2794 0.1778)
						)
						(arc
							(start 0.2794 -0.1778)
							(mid 0.249642 -0.249642)
							(end 0.1778 -0.2794)
						)
					)
					(width 0)
					(fill yes)
				)
			)
		)
		(pad "2" smd custom
			(at 0 0.4445 270)
			(size 0.1397 0.1397)
			(layers "F.Cu" "F.Mask" "F.Paste")
			(net "FAN_LED0_D2")
			(options
				(clearance outline)
				(anchor circle)
			)
			(primitives
				(gr_poly
					(pts
						(arc
							(start -0.1778 -0.2794)
							(mid -0.249642 -0.249642)
							(end -0.2794 -0.1778)
						)
						(arc
							(start -0.2794 0.1778)
							(mid -0.249642 0.249642)
							(end -0.1778 0.2794)
						)
						(arc
							(start 0.1778 0.2794)
							(mid 0.249642 0.249642)
							(end 0.2794 0.1778)
						)
						(arc
							(start 0.2794 -0.1778)
							(mid 0.249642 -0.249642)
							(end 0.1778 -0.2794)
						)
					)
					(width 0)
					(fill yes)
				)
			)
		)
	)
	(footprint ""
		(layer "F.Cu")
		(at 265.625072 -344.370406 90)
		(property "Reference" "R1053"
			(at 0 0 90)
			(layer "F.SilkS")
			(hide yes)
			(effects
				(font
					(size 1.27 1.27)
				)
			)
		)
		(property "Value" "10R5F-1-GP"
			(at 0 -8.9535 90)
			(unlocked yes)
			(layer "F.Fab")
			(hide yes)
			(effects
				(font
					(size 1.27 1.016)
					(thickness 0.1524)
				)
			)
		)
		(property "Device Type" "R805H24"
			(at 0 -10.6299 90)
			(unlocked yes)
			(layer "F.Fab")
			(hide yes)
			(effects
				(font
					(size 1.27 1.016)
					(thickness 0.1524)
				)
			)
		)
		(duplicate_pad_numbers_are_jumpers no)
		(fp_line
			(start 0.889 -1.7018)
			(end -0.889 -1.7018)
			(stroke
				(width 0.1524)
				(type default)
			)
			(layer "F.SilkS")
		)
		(fp_line
			(start 0.889 -1.7018)
			(end 0.889 -0.381)
			(stroke
				(width 0.1524)
				(type default)
			)
			(layer "F.SilkS")
		)
		(fp_line
			(start -0.889 -1.7018)
			(end -0.889 0.2794)
			(stroke
				(width 0.1524)
				(type default)
			)
			(layer "F.SilkS")
		)
		(fp_line
			(start -0.889 0.0762)
			(end -0.889 1.7018)
			(stroke
				(width 0.1524)
				(type default)
			)
			(layer "F.SilkS")
		)
		(fp_line
			(start 0.889 1.7018)
			(end 0.889 -0.508)
			(stroke
				(width 0.1524)
				(type default)
			)
			(layer "F.SilkS")
		)
		(fp_line
			(start -0.889 1.7018)
			(end 0.889 1.7018)
			(stroke
				(width 0.1524)
				(type default)
			)
			(layer "F.SilkS")
		)
		(fp_poly
			(pts
				(xy 0.9652 -1.778) (xy 0.9652 1.778) (xy -0.9652 1.778) (xy -0.9652 -1.778)
			)
			(stroke
				(width 0)
				(type default)
			)
			(fill no)
			(layer "F.CrtYd")
		)
		(fp_rect
			(start -0.9652 1.778)
			(end 0.9652 -1.778)
			(stroke
				(width 0)
				(type default)
			)
			(fill no)
			(layer "F.Fab")
		)
		(pad "1" smd rect
			(at 0 -0.9652 90)
			(size 1.397 1.143)
			(layers "F.Cu" "F.Mask" "F.Paste")
			(net "MB3_12V_CTRL_GATE2")
		)
		(pad "2" smd rect
			(at 0 0.9652 90)
			(size 1.397 1.143)
			(layers "F.Cu" "F.Mask" "F.Paste")
			(net "MB3_CM_GATE_R")
		)
	)
	(footprint ""
		(layer "F.Cu")
		(at 426.085 -44.958 180)
		(property "Reference" "C464"
			(at 0 0 180)
			(layer "F.SilkS")
			(hide yes)
			(effects
				(font
					(size 1.27 1.27)
				)
			)
		)
		(property "Value" "SC4D7U25V5KX-1-GP"
			(at -0.0762 -6.1214 180)
			(unlocked yes)
			(layer "F.Fab")
			(hide yes)
			(effects
				(font
					(size 1.016 1.016)
					(thickness 0.1524)
				)
			)
		)
		(property "Device Type" "C805H58"
			(at -0.0762 -8.1534 180)
			(unlocked yes)
			(layer "F.Fab")
			(hide yes)
			(effects
				(font
					(size 1.016 1.016)
					(thickness 0.1524)
				)
			)
		)
		(duplicate_pad_numbers_are_jumpers no)
		(fp_line
			(start 0.635 0)
			(end -0.635 0)
			(stroke
				(width 0.508)
				(type default)
			)
			(layer "F.SilkS")
		)
		(fp_rect
			(start -0.9652 1.778)
			(end 0.9652 -1.778)
			(stroke
				(width 0)
				(type default)
			)
			(fill no)
			(layer "F.CrtYd")
		)
		(fp_poly
			(pts
				(xy -0.9652 -1.778) (xy 0.9652 -1.778) (xy 0.9652 1.778) (xy -0.9652 1.778)
			)
			(stroke
				(width 0)
				(type default)
			)
			(fill no)
			(layer "F.Fab")
		)
		(pad "1" smd rect
			(at 0 -0.9652 180)
			(size 1.397 1.143)
			(layers "F.Cu" "F.Mask" "F.Paste")
			(net "P12V_HDD33")
		)
		(pad "2" smd rect
			(at 0 0.9652 180)
			(size 1.397 1.143)
			(layers "F.Cu" "F.Mask" "F.Paste")
			(net "GND")
		)
	)
	(footprint ""
		(layer "F.Cu")
		(at 457.935838 -228.930454 -90)
		(property "Reference" "R1145"
			(at 0 0 270)
			(layer "F.SilkS")
			(hide yes)
			(effects
				(font
					(size 1.27 1.27)
				)
			)
		)
		(property "Value" "200KR2F-L-GP"
			(at 0.064008 -3.993896 270)
			(unlocked yes)
			(layer "F.Fab")
			(hide yes)
			(effects
				(font
					(size 1.016 1.016)
					(thickness 0.1524)
				)
			)
		)
		(property "Device Type" "R402H16"
			(at 0.064008 -5.517896 270)
			(unlocked yes)
			(layer "F.Fab")
			(hide yes)
			(effects
				(font
					(size 1.016 1.016)
					(thickness 0.1524)
				)
			)
		)
		(duplicate_pad_numbers_are_jumpers no)
		(fp_line
			(start -0.508 -0.9398)
			(end -0.508 0.9398)
			(stroke
				(width 0.1524)
				(type default)
			)
			(layer "F.SilkS")
		)
		(fp_line
			(start 0.508 -0.9398)
			(end -0.508 -0.9398)
			(stroke
				(width 0.1524)
				(type default)
			)
			(layer "F.SilkS")
		)
		(fp_rect
			(start -0.508 0.9398)
			(end 0.508 -0.9398)
			(stroke
				(width 0)
				(type default)
			)
			(fill no)
			(layer "F.CrtYd")
		)
		(fp_rect
			(start -0.508 0.9398)
			(end 0.508 -0.9398)
			(stroke
				(width 0)
				(type default)
			)
			(fill no)
			(layer "F.Fab")
		)
		(pad "1" smd custom
			(at 0 -0.4445 270)
			(size 0.1397 0.1397)
			(layers "F.Cu" "F.Mask" "F.Paste")
			(net "P5V_B_3_MODE")
			(options
				(clearance outline)
				(anchor circle)
			)
			(primitives
				(gr_poly
					(pts
						(arc
							(start -0.1778 -0.2794)
							(mid -0.249642 -0.249642)
							(end -0.2794 -0.1778)
						)
						(arc
							(start -0.2794 0.1778)
							(mid -0.249642 0.249642)
							(end -0.1778 0.2794)
						)
						(arc
							(start 0.1778 0.2794)
							(mid 0.249642 0.249642)
							(end 0.2794 0.1778)
						)
						(arc
							(start 0.2794 -0.1778)
							(mid 0.249642 -0.249642)
							(end 0.1778 -0.2794)
						)
					)
					(width 0)
					(fill yes)
				)
			)
		)
		(pad "2" smd custom
			(at 0 0.4445 270)
			(size 0.1397 0.1397)
			(layers "F.Cu" "F.Mask" "F.Paste")
			(net "P5V_B_3_PGOOD")
			(options
				(clearance outline)
				(anchor circle)
			)
			(primitives
				(gr_poly
					(pts
						(arc
							(start -0.1778 -0.2794)
							(mid -0.249642 -0.249642)
							(end -0.2794 -0.1778)
						)
						(arc
							(start -0.2794 0.1778)
							(mid -0.249642 0.249642)
							(end -0.1778 0.2794)
						)
						(arc
							(start 0.1778 0.2794)
							(mid 0.249642 0.249642)
							(end 0.2794 0.1778)
						)
						(arc
							(start 0.2794 -0.1778)
							(mid 0.249642 -0.249642)
							(end 0.1778 -0.2794)
						)
					)
					(width 0)
					(fill yes)
				)
			)
		)
	)
	(footprint ""
		(layer "F.Cu")
		(at 431.451004 -362.077 180)
		(property "Reference" "Q214"
			(at 0 0 180)
			(layer "F.SilkS")
			(hide yes)
			(effects
				(font
					(size 1.27 1.27)
				)
			)
		)
		(property "Value" "2N7002K-2-GP"
			(at 0.127 -8.9662 180)
			(unlocked yes)
			(layer "F.Fab")
			(hide yes)
			(effects
				(font
					(size 1.016 1.016)
					(thickness 0.1524)
				)
			)
		)
		(property "Device Type" "SOT23DGS2D4H44"
			(at 0.127 -10.4902 180)
			(unlocked yes)
			(layer "F.Fab")
			(hide yes)
			(effects
				(font
					(size 1.016 1.016)
					(thickness 0.1524)
				)
			)
		)
		(duplicate_pad_numbers_are_jumpers no)
		(fp_line
			(start 1.651 1.778)
			(end 1.651 -1.778)
			(stroke
				(width 0.1524)
				(type default)
			)
			(layer "F.SilkS")
		)
		(fp_line
			(start 1.651 -1.778)
			(end -1.651 -1.778)
			(stroke
				(width 0.1524)
				(type default)
			)
			(layer "F.SilkS")
		)
		(fp_line
			(start -1.651 1.778)
			(end 1.651 1.778)
			(stroke
				(width 0.1524)
				(type default)
			)
			(layer "F.SilkS")
		)
		(fp_line
			(start -1.651 -1.778)
			(end -1.651 1.778)
			(stroke
				(width 0.1524)
				(type default)
			)
			(layer "F.SilkS")
		)
		(fp_poly
			(pts
				(xy -1.778 1.8796) (xy -1.778 -1.8796) (xy 1.778 -1.8796) (xy 1.778 1.8796)
			)
			(stroke
				(width 0)
				(type default)
			)
			(fill no)
			(layer "F.CrtYd")
		)
		(fp_poly
			(pts
				(xy -1.778 1.8796) (xy -1.778 -1.8796) (xy 1.778 -1.8796) (xy 1.778 1.8796)
			)
			(stroke
				(width 0)
				(type default)
			)
			(fill no)
			(layer "F.Fab")
		)
		(pad "D" smd custom
			(at 0 -0.9525 180)
			(size 0.1905 0.1905)
			(layers "F.Cu" "F.Mask" "F.Paste")
			(net "GATE_FAN3")
			(options
				(clearance outline)
				(anchor circle)
			)
			(primitives
				(gr_poly
					(pts
						(arc
							(start -0.1778 0.5715)
							(mid -0.321484 0.511984)
							(end -0.381 0.3683)
						)
						(arc
							(start -0.381 -0.3683)
							(mid -0.321484 -0.511984)
							(end -0.1778 -0.5715)
						)
						(arc
							(start 0.1778 -0.5715)
							(mid 0.321484 -0.511984)
							(end 0.381 -0.3683)
						)
						(arc
							(start 0.381 0.3683)
							(mid 0.321484 0.511984)
							(end 0.1778 0.5715)
						)
					)
					(width 0)
					(fill yes)
				)
			)
		)
		(pad "G" smd custom
			(at -0.98425 0.9525 180)
			(size 0.1905 0.1905)
			(layers "F.Cu" "F.Mask" "F.Paste")
			(net "FAN_EN")
			(options
				(clearance outline)
				(anchor circle)
			)
			(primitives
				(gr_poly
					(pts
						(arc
							(start -0.1778 0.5715)
							(mid -0.321484 0.511984)
							(end -0.381 0.3683)
						)
						(arc
							(start -0.381 -0.3683)
							(mid -0.321484 -0.511984)
							(end -0.1778 -0.5715)
						)
						(arc
							(start 0.1778 -0.5715)
							(mid 0.321484 -0.511984)
							(end 0.381 -0.3683)
						)
						(arc
							(start 0.381 0.3683)
							(mid 0.321484 0.511984)
							(end 0.1778 0.5715)
						)
					)
					(width 0)
					(fill yes)
				)
			)
		)
		(pad "S" smd custom
			(at 0.98425 0.9525 180)
			(size 0.1905 0.1905)
			(layers "F.Cu" "F.Mask" "F.Paste")
			(net "GND")
			(options
				(clearance outline)
				(anchor circle)
			)
			(primitives
				(gr_poly
					(pts
						(arc
							(start -0.1778 0.5715)
							(mid -0.321484 0.511984)
							(end -0.381 0.3683)
						)
						(arc
							(start -0.381 -0.3683)
							(mid -0.321484 -0.511984)
							(end -0.1778 -0.5715)
						)
						(arc
							(start 0.1778 -0.5715)
							(mid 0.321484 -0.511984)
							(end 0.381 -0.3683)
						)
						(arc
							(start 0.381 0.3683)
							(mid 0.321484 0.511984)
							(end 0.1778 0.5715)
						)
					)
					(width 0)
					(fill yes)
				)
			)
		)
	)
	(footprint ""
		(layer "F.Cu")
		(at 24.450802 -230.63835 -90)
		(property "Reference" "R1100"
			(at 0 0 270)
			(layer "F.SilkS")
			(hide yes)
			(effects
				(font
					(size 1.27 1.27)
				)
			)
		)
		(property "Value" "10KR2F-2-GP"
			(at 0.064008 -3.993896 270)
			(unlocked yes)
			(layer "F.Fab")
			(hide yes)
			(effects
				(font
					(size 1.016 1.016)
					(thickness 0.1524)
				)
			)
		)
		(property "Device Type" "R402H16"
			(at 0.064008 -5.517896 270)
			(unlocked yes)
			(layer "F.Fab")
			(hide yes)
			(effects
				(font
					(size 1.016 1.016)
					(thickness 0.1524)
				)
			)
		)
		(duplicate_pad_numbers_are_jumpers no)
		(fp_line
			(start -0.508 -0.9398)
			(end -0.508 0.9398)
			(stroke
				(width 0.1524)
				(type default)
			)
			(layer "F.SilkS")
		)
		(fp_line
			(start 0.508 -0.9398)
			(end -0.508 -0.9398)
			(stroke
				(width 0.1524)
				(type default)
			)
			(layer "F.SilkS")
		)
		(fp_rect
			(start -0.508 0.9398)
			(end 0.508 -0.9398)
			(stroke
				(width 0)
				(type default)
			)
			(fill no)
			(layer "F.CrtYd")
		)
		(fp_rect
			(start -0.508 0.9398)
			(end 0.508 -0.9398)
			(stroke
				(width 0)
				(type default)
			)
			(fill no)
			(layer "F.Fab")
		)
		(pad "1" smd custom
			(at 0 -0.4445 270)
			(size 0.1397 0.1397)
			(layers "F.Cu" "F.Mask" "F.Paste")
			(net "P5V_B_1_EN_R")
			(options
				(clearance outline)
				(anchor circle)
			)
			(primitives
				(gr_poly
					(pts
						(arc
							(start -0.1778 -0.2794)
							(mid -0.249642 -0.249642)
							(end -0.2794 -0.1778)
						)
						(arc
							(start -0.2794 0.1778)
							(mid -0.249642 0.249642)
							(end -0.1778 0.2794)
						)
						(arc
							(start 0.1778 0.2794)
							(mid 0.249642 0.249642)
							(end 0.2794 0.1778)
						)
						(arc
							(start 0.2794 -0.1778)
							(mid 0.249642 -0.249642)
							(end 0.1778 -0.2794)
						)
					)
					(width 0)
					(fill yes)
				)
			)
		)
		(pad "2" smd custom
			(at 0 0.4445 270)
			(size 0.1397 0.1397)
			(layers "F.Cu" "F.Mask" "F.Paste")
			(net "GND")
			(options
				(clearance outline)
				(anchor circle)
			)
			(primitives
				(gr_poly
					(pts
						(arc
							(start -0.1778 -0.2794)
							(mid -0.249642 -0.249642)
							(end -0.2794 -0.1778)
						)
						(arc
							(start -0.2794 0.1778)
							(mid -0.249642 0.249642)
							(end -0.1778 0.2794)
						)
						(arc
							(start 0.1778 0.2794)
							(mid 0.249642 0.249642)
							(end 0.2794 0.1778)
						)
						(arc
							(start 0.2794 -0.1778)
							(mid 0.249642 -0.249642)
							(end 0.1778 -0.2794)
						)
					)
					(width 0)
					(fill yes)
				)
			)
		)
	)
	(footprint ""
		(layer "F.Cu")
		(at 262.46201 -226.715574)
		(property "Reference" "R170"
			(at 0 0 0)
			(layer "F.SilkS")
			(hide yes)
			(effects
				(font
					(size 1.27 1.27)
				)
			)
		)
		(property "Value" "16K2R2F-GP"
			(at 0.064008 -3.993896 0)
			(unlocked yes)
			(layer "F.Fab")
			(hide yes)
			(effects
				(font
					(size 1.016 1.016)
					(thickness 0.1524)
				)
			)
		)
		(property "Device Type" "R402H16"
			(at 0.064008 -5.517896 0)
			(unlocked yes)
			(layer "F.Fab")
			(hide yes)
			(effects
				(font
					(size 1.016 1.016)
					(thickness 0.1524)
				)
			)
		)
		(duplicate_pad_numbers_are_jumpers no)
		(fp_line
			(start -0.508 -0.9398)
			(end -0.508 0.9398)
			(stroke
				(width 0.1524)
				(type default)
			)
			(layer "F.SilkS")
		)
		(fp_line
			(start 0.508 -0.9398)
			(end -0.508 -0.9398)
			(stroke
				(width 0.1524)
				(type default)
			)
			(layer "F.SilkS")
		)
		(fp_rect
			(start -0.508 0.9398)
			(end 0.508 -0.9398)
			(stroke
				(width 0)
				(type default)
			)
			(fill no)
			(layer "F.CrtYd")
		)
		(fp_rect
			(start -0.508 0.9398)
			(end 0.508 -0.9398)
			(stroke
				(width 0)
				(type default)
			)
			(fill no)
			(layer "F.Fab")
		)
		(pad "1" smd custom
			(at 0 -0.4445)
			(size 0.1397 0.1397)
			(layers "F.Cu" "F.Mask" "F.Paste")
			(net "P5V_B_4")
			(options
				(clearance outline)
				(anchor circle)
			)
			(primitives
				(gr_poly
					(pts
						(arc
							(start -0.1778 -0.2794)
							(mid -0.249642 -0.249642)
							(end -0.2794 -0.1778)
						)
						(arc
							(start -0.2794 0.1778)
							(mid -0.249642 0.249642)
							(end -0.1778 0.2794)
						)
						(arc
							(start 0.1778 0.2794)
							(mid 0.249642 0.249642)
							(end 0.2794 0.1778)
						)
						(arc
							(start 0.2794 -0.1778)
							(mid 0.249642 -0.249642)
							(end 0.1778 -0.2794)
						)
					)
					(width 0)
					(fill yes)
				)
			)
		)
		(pad "2" smd custom
			(at 0 0.4445)
			(size 0.1397 0.1397)
			(layers "F.Cu" "F.Mask" "F.Paste")
			(net "P5V_B_4_SENSE")
			(options
				(clearance outline)
				(anchor circle)
			)
			(primitives
				(gr_poly
					(pts
						(arc
							(start -0.1778 -0.2794)
							(mid -0.249642 -0.249642)
							(end -0.2794 -0.1778)
						)
						(arc
							(start -0.2794 0.1778)
							(mid -0.249642 0.249642)
							(end -0.1778 0.2794)
						)
						(arc
							(start 0.1778 0.2794)
							(mid 0.249642 0.249642)
							(end 0.2794 0.1778)
						)
						(arc
							(start 0.2794 -0.1778)
							(mid 0.249642 -0.249642)
							(end 0.1778 -0.2794)
						)
					)
					(width 0)
					(fill yes)
				)
			)
		)
	)
	(footprint ""
		(layer "F.Cu")
		(at 257.331972 -342.338406 90)
		(property "Reference" "Q202"
			(at 0 0 90)
			(layer "F.SilkS")
			(hide yes)
			(effects
				(font
					(size 1.27 1.27)
				)
			)
		)
		(property "Value" "IRFH8201TRPBF-GP"
			(at -4.2164 -4.3688 90)
			(unlocked yes)
			(layer "F.Fab")
			(hide yes)
			(effects
				(font
					(size 1.016 1.016)
					(thickness 0.1524)
				)
			)
		)
		(property "Device Type" "PPAK-5PH42"
			(at -4.2164 -5.8928 90)
			(unlocked yes)
			(layer "F.Fab")
			(hide yes)
			(effects
				(font
					(size 1.016 1.016)
					(thickness 0.1524)
				)
			)
		)
		(duplicate_pad_numbers_are_jumpers no)
		(fp_line
			(start 2.8956 -2.794)
			(end 2.8956 4.826)
			(stroke
				(width 0.1524)
				(type default)
			)
			(layer "F.SilkS")
		)
		(fp_line
			(start -2.8956 -2.794)
			(end 2.8956 -2.794)
			(stroke
				(width 0.1524)
				(type default)
			)
			(layer "F.SilkS")
		)
		(fp_line
			(start 2.8956 4.826)
			(end -2.8956 4.826)
			(stroke
				(width 0.1524)
				(type default)
			)
			(layer "F.SilkS")
		)
		(fp_line
			(start -2.8956 4.826)
			(end -2.8956 -2.794)
			(stroke
				(width 0.1524)
				(type default)
			)
			(layer "F.SilkS")
		)
		(fp_line
			(start -1.9431 4.9276)
			(end -3.0353 4.9276)
			(stroke
				(width 0.3302)
				(type default)
			)
			(layer "F.SilkS")
		)
		(fp_line
			(start -3.0353 4.9276)
			(end -3.0353 3.9624)
			(stroke
				(width 0.3302)
				(type default)
			)
			(layer "F.SilkS")
		)
		(fp_poly
			(pts
				(xy -2.3622 5.334) (xy -1.4986 5.334) (xy -1.9304 4.9022)
			)
			(stroke
				(width 0)
				(type default)
			)
			(fill yes)
			(layer "F.SilkS")
		)
		(fp_poly
			(pts
				(xy 0.3556 -0.3556) (xy 2.6416 -0.3556) (xy 2.6416 -2.54) (xy 0.3556 -2.54)
			)
			(stroke
				(width 0)
				(type default)
			)
			(fill yes)
			(layer "F.Paste")
		)
		(fp_poly
			(pts
				(xy -2.6416 -0.3556) (xy -0.3556 -0.3556) (xy -0.3556 -2.54) (xy -2.6416 -2.54)
			)
			(stroke
				(width 0)
				(type default)
			)
			(fill yes)
			(layer "F.Paste")
		)
		(fp_poly
			(pts
				(xy 0.3556 2.54) (xy 2.6416 2.54) (xy 2.6416 0.3556) (xy 0.3556 0.3556)
			)
			(stroke
				(width 0)
				(type default)
			)
			(fill yes)
			(layer "F.Paste")
		)
		(fp_poly
			(pts
				(xy -2.6416 2.54) (xy -0.3556 2.54) (xy -0.3556 0.3556) (xy -2.6416 0.3556)
			)
			(stroke
				(width 0)
				(type default)
			)
			(fill yes)
			(layer "F.Paste")
		)
		(fp_rect
			(start -2.5781 3.9878)
			(end 2.5781 -2.1082)
			(stroke
				(width 0)
				(type default)
			)
			(fill no)
			(layer "F.CrtYd")
		)
		(fp_poly
			(pts
				(xy -3.1496 5.08) (xy -3.1496 -3.048) (xy 3.1496 -3.048) (xy 3.1496 3.9751) (xy 2.5781 3.9751) (xy 2.5781 -2.1082)
				(xy -2.5781 -2.1082) (xy -2.5781 3.9878) (xy 3.1496 3.9878) (xy 3.1496 5.08)
			)
			(stroke
				(width 0)
				(type default)
			)
			(fill no)
			(layer "F.CrtYd")
		)
		(fp_rect
			(start -3.1496 5.08)
			(end 3.1496 -3.048)
			(stroke
				(width 0)
				(type default)
			)
			(fill no)
			(layer "F.Fab")
		)
		(pad "1" smd rect
			(at -1.905 3.81 90)
			(size 0.762 1.524)
			(layers "F.Cu" "F.Mask" "F.Paste")
			(net "P12V_B")
		)
		(pad "2" smd rect
			(at -0.635 3.81 90)
			(size 0.762 1.524)
			(layers "F.Cu" "F.Mask" "F.Paste")
			(net "P12V_B")
		)
		(pad "3" smd rect
			(at 0.635 3.81 90)
			(size 0.762 1.524)
			(layers "F.Cu" "F.Mask" "F.Paste")
			(net "P12V_B")
		)
		(pad "4" smd rect
			(at 1.905 3.81 90)
			(size 0.762 1.524)
			(layers "F.Cu" "F.Mask" "F.Paste")
			(net "MB3_12V_CTRL_GATE2")
		)
		(pad "5" smd rect
			(at 0 0 90)
			(size 5.2832 5.08)
			(layers "F.Cu" "F.Mask" "F.Paste")
			(net "MB3_P12V_IN_R")
		)
		(pad "6" smd rect
			(at 0.635 -2.032 90)
			(size 0.0254 0.0254)
			(layers "F.Cu" "F.Mask" "F.Paste")
			(net "MB3_P12V_IN_R")
		)
		(pad "7" smd rect
			(at -0.635 -2.032 90)
			(size 0.0254 0.0254)
			(layers "F.Cu" "F.Mask" "F.Paste")
			(net "MB3_P12V_IN_R")
		)
		(pad "8" smd rect
			(at -1.905 -2.032 90)
			(size 0.0254 0.0254)
			(layers "F.Cu" "F.Mask" "F.Paste")
			(net "MB3_P12V_IN_R")
		)
	)
	(footprint ""
		(layer "F.Cu")
		(at 470.662 -129.286 180)
		(property "Reference" "R607"
			(at 0 0 180)
			(layer "F.SilkS")
			(hide yes)
			(effects
				(font
					(size 1.27 1.27)
				)
			)
		)
		(property "Value" "1KR2F-3-GP"
			(at 0.064008 -3.993896 180)
			(unlocked yes)
			(layer "F.Fab")
			(hide yes)
			(effects
				(font
					(size 1.016 1.016)
					(thickness 0.1524)
				)
			)
		)
		(property "Device Type" "R402H16"
			(at 0.064008 -5.517896 180)
			(unlocked yes)
			(layer "F.Fab")
			(hide yes)
			(effects
				(font
					(size 1.016 1.016)
					(thickness 0.1524)
				)
			)
		)
		(duplicate_pad_numbers_are_jumpers no)
		(fp_line
			(start 0.508 -0.9398)
			(end -0.508 -0.9398)
			(stroke
				(width 0.1524)
				(type default)
			)
			(layer "F.SilkS")
		)
		(fp_line
			(start -0.508 -0.9398)
			(end -0.508 0.9398)
			(stroke
				(width 0.1524)
				(type default)
			)
			(layer "F.SilkS")
		)
		(fp_rect
			(start -0.508 0.9398)
			(end 0.508 -0.9398)
			(stroke
				(width 0)
				(type default)
			)
			(fill no)
			(layer "F.CrtYd")
		)
		(fp_rect
			(start -0.508 0.9398)
			(end 0.508 -0.9398)
			(stroke
				(width 0)
				(type default)
			)
			(fill no)
			(layer "F.Fab")
		)
		(pad "1" smd custom
			(at 0 -0.4445 180)
			(size 0.1397 0.1397)
			(layers "F.Cu" "F.Mask" "F.Paste")
			(net "P3V3_STBY_B")
			(options
				(clearance outline)
				(anchor circle)
			)
			(primitives
				(gr_poly
					(pts
						(arc
							(start -0.1778 -0.2794)
							(mid -0.249642 -0.249642)
							(end -0.2794 -0.1778)
						)
						(arc
							(start -0.2794 0.1778)
							(mid -0.249642 0.249642)
							(end -0.1778 0.2794)
						)
						(arc
							(start 0.1778 0.2794)
							(mid 0.249642 0.249642)
							(end 0.2794 0.1778)
						)
						(arc
							(start 0.2794 -0.1778)
							(mid 0.249642 -0.249642)
							(end 0.1778 -0.2794)
						)
					)
					(width 0)
					(fill yes)
				)
			)
		)
		(pad "2" smd custom
			(at 0 0.4445 180)
			(size 0.1397 0.1397)
			(layers "F.Cu" "F.Mask" "F.Paste")
			(net "SW_PWR_R_HDD23")
			(options
				(clearance outline)
				(anchor circle)
			)
			(primitives
				(gr_poly
					(pts
						(arc
							(start -0.1778 -0.2794)
							(mid -0.249642 -0.249642)
							(end -0.2794 -0.1778)
						)
						(arc
							(start -0.2794 0.1778)
							(mid -0.249642 0.249642)
							(end -0.1778 0.2794)
						)
						(arc
							(start 0.1778 0.2794)
							(mid 0.249642 0.249642)
							(end 0.2794 0.1778)
						)
						(arc
							(start 0.2794 -0.1778)
							(mid 0.249642 -0.249642)
							(end 0.1778 -0.2794)
						)
					)
					(width 0)
					(fill yes)
				)
			)
		)
	)
	(footprint ""
		(layer "F.Cu")
		(at 243.078 -306.705)
		(property "Reference" "U30"
			(at 0 0 0)
			(layer "F.SilkS")
			(hide yes)
			(effects
				(font
					(size 1.27 1.27)
				)
			)
		)
		(property "Value" "MAX31790ATI-T-GP"
			(at 4.1021 -3.7338 0)
			(unlocked yes)
			(layer "F.Fab")
			(hide yes)
			(effects
				(font
					(size 1.016 1.016)
					(thickness 0.1524)
				)
			)
		)
		(property "Device Type" "QFN28-G2D7H32"
			(at 4.1021 -5.2578 0)
			(unlocked yes)
			(layer "F.Fab")
			(hide yes)
			(effects
				(font
					(size 1.016 1.016)
					(thickness 0.1524)
				)
			)
		)
		(duplicate_pad_numbers_are_jumpers no)
		(fp_line
			(start -3.0099 -3.0099)
			(end -1.7399 -3.0099)
			(stroke
				(width 0.1524)
				(type default)
			)
			(layer "F.SilkS")
		)
		(fp_line
			(start -3.0099 -1.7399)
			(end -3.0099 -3.0099)
			(stroke
				(width 0.1524)
				(type default)
			)
			(layer "F.SilkS")
		)
		(fp_line
			(start -3.0099 1.7399)
			(end -3.0099 3.0099)
			(stroke
				(width 0.1524)
				(type default)
			)
			(layer "F.SilkS")
		)
		(fp_line
			(start -3.0099 3.0099)
			(end -1.7399 3.0099)
			(stroke
				(width 0.1524)
				(type default)
			)
			(layer "F.SilkS")
		)
		(fp_line
			(start -2.7813 -0.4064)
			(end -3.5433 -0.4064)
			(stroke
				(width 0.1524)
				(type default)
			)
			(layer "F.SilkS")
		)
		(fp_line
			(start -1.1938 2.7813)
			(end -1.1938 3.2893)
			(stroke
				(width 0.1524)
				(type default)
			)
			(layer "F.SilkS")
		)
		(fp_line
			(start -0.4064 -2.7813)
			(end -0.4064 -3.2893)
			(stroke
				(width 0.1524)
				(type default)
			)
			(layer "F.SilkS")
		)
		(fp_line
			(start 0.8128 2.7813)
			(end 0.8128 3.5433)
			(stroke
				(width 0.1524)
				(type default)
			)
			(layer "F.SilkS")
		)
		(fp_line
			(start 1.7399 3.0099)
			(end 3.0099 3.0099)
			(stroke
				(width 0.1524)
				(type default)
			)
			(layer "F.SilkS")
		)
		(fp_line
			(start 2.7813 0)
			(end 3.2893 0)
			(stroke
				(width 0.1524)
				(type default)
			)
			(layer "F.SilkS")
		)
		(fp_line
			(start 3.0099 3.0099)
			(end 3.0099 1.7399)
			(stroke
				(width 0.1524)
				(type default)
			)
			(layer "F.SilkS")
		)
		(fp_poly
			(pts
				(xy 3.0099 -1.7399) (xy 1.7399 -3.0099) (xy 3.0099 -3.0099)
			)
			(stroke
				(width 0)
				(type default)
			)
			(fill yes)
			(layer "F.SilkS")
		)
		(fp_rect
			(start -1.9939 1.9939)
			(end 1.9939 -1.9939)
			(stroke
				(width 0)
				(type default)
			)
			(fill no)
			(layer "F.CrtYd")
		)
		(fp_poly
			(pts
				(xy -3.0099 3.0099) (xy -3.0099 -3.0099) (xy 3.0099 -3.0099) (xy 3.0099 3.0099) (xy -1.98882 3.0099)
				(xy -1.98882 1.9939) (xy 1.9939 1.9939) (xy 1.9939 -1.9939) (xy -1.9939 -1.9939) (xy -1.9939 3.0099)
			)
			(stroke
				(width 0)
				(type default)
			)
			(fill no)
			(layer "F.CrtYd")
		)
		(fp_rect
			(start -3.0099 3.0099)
			(end 3.0099 -3.0099)
			(stroke
				(width 0)
				(type default)
			)
			(fill no)
			(layer "F.Fab")
		)
		(pad "1" smd rect
			(at 1.199896 -2.032)
			(size 0.2032 0.9398)
			(layers "F.Cu" "F.Mask" "F.Paste")
			(net "MAX31790_A_FREQ_ST")
		)
		(pad "2" smd rect
			(at 0.8001 -2.032)
			(size 0.2032 0.9398)
			(layers "F.Cu" "F.Mask" "F.Paste")
			(net "MAX31790_A_SPIN_ST")
		)
		(pad "3" smd rect
			(at 0.40005 -2.032)
			(size 0.2032 0.9398)
			(layers "F.Cu" "F.Mask" "F.Paste")
			(net "MAX31790_A_ADD1")
		)
		(pad "4" smd rect
			(at 0 -2.032)
			(size 0.2032 0.9398)
			(layers "F.Cu" "F.Mask" "F.Paste")
			(net "MAX31790_A_ADD0")
		)
		(pad "5" smd rect
			(at -0.40005 -2.032)
			(size 0.2032 0.9398)
			(layers "F.Cu" "F.Mask" "F.Paste")
			(net "MAX31790_A_WD_ST")
		)
		(pad "6" smd rect
			(at -0.8001 -2.032)
			(size 0.2032 0.9398)
			(layers "F.Cu" "F.Mask" "F.Paste")
			(net "Net_311")
		)
		(pad "7" smd rect
			(at -1.199896 -2.032)
			(size 0.2032 0.9398)
			(layers "F.Cu" "F.Mask" "F.Paste")
			(net "GND")
		)
		(pad "8" smd rect
			(at -2.032 -1.199896)
			(size 0.9398 0.2032)
			(layers "F.Cu" "F.Mask" "F.Paste")
			(net "GND")
		)
		(pad "9" smd rect
			(at -2.032 -0.8001)
			(size 0.9398 0.2032)
			(layers "F.Cu" "F.Mask" "F.Paste")
			(net "FANTACH_A_R3")
		)
		(pad "10" smd rect
			(at -2.032 -0.40005)
			(size 0.9398 0.2032)
			(layers "F.Cu" "F.Mask" "F.Paste")
			(net "Net_314")
		)
		(pad "11" smd rect
			(at -2.032 0)
			(size 0.9398 0.2032)
			(layers "F.Cu" "F.Mask" "F.Paste")
			(net "FANTACH_A_F3")
		)
		(pad "12" smd rect
			(at -2.032 0.40005)
			(size 0.9398 0.2032)
			(layers "F.Cu" "F.Mask" "F.Paste")
			(net "Net_315")
		)
		(pad "13" smd rect
			(at -2.032 0.8001)
			(size 0.9398 0.2032)
			(layers "F.Cu" "F.Mask" "F.Paste")
			(net "FANTACH_A_R2")
		)
		(pad "14" smd rect
			(at -2.032 1.199896)
			(size 0.9398 0.2032)
			(layers "F.Cu" "F.Mask" "F.Paste")
			(net "Net_316")
		)
		(pad "15" smd rect
			(at -1.199896 2.032)
			(size 0.2032 0.9398)
			(layers "F.Cu" "F.Mask" "F.Paste")
			(net "FANTACH_A_F2")
		)
		(pad "16" smd rect
			(at -0.8001 2.032)
			(size 0.2032 0.9398)
			(layers "F.Cu" "F.Mask" "F.Paste")
			(net "Net_313")
		)
		(pad "17" smd rect
			(at -0.40005 2.032)
			(size 0.2032 0.9398)
			(layers "F.Cu" "F.Mask" "F.Paste")
			(net "FANTACH_A_R1")
		)
		(pad "18" smd rect
			(at 0 2.032)
			(size 0.2032 0.9398)
			(layers "F.Cu" "F.Mask" "F.Paste")
			(net "FANTACH_A_R0")
		)
		(pad "19" smd rect
			(at 0.40005 2.032)
			(size 0.2032 0.9398)
			(layers "F.Cu" "F.Mask" "F.Paste")
			(net "FANTACH_A_F1")
		)
		(pad "20" smd rect
			(at 0.8001 2.032)
			(size 0.2032 0.9398)
			(layers "F.Cu" "F.Mask" "F.Paste")
			(net "FANTACH_A_F0")
		)
		(pad "21" smd rect
			(at 1.199896 2.032)
			(size 0.2032 0.9398)
			(layers "F.Cu" "F.Mask" "F.Paste")
			(net "P3V3_STBY_A")
		)
		(pad "22" smd rect
			(at 2.032 1.199896)
			(size 0.9398 0.2032)
			(layers "F.Cu" "F.Mask" "F.Paste")
			(net "MAX31790_A_SDA")
		)
		(pad "23" smd rect
			(at 2.032 0.8001)
			(size 0.9398 0.2032)
			(layers "F.Cu" "F.Mask" "F.Paste")
			(net "MAX31790_A_SCL")
		)
		(pad "24" smd rect
			(at 2.032 0.40005)
			(size 0.9398 0.2032)
			(layers "F.Cu" "F.Mask" "F.Paste")
			(net "MAX31790_A_FAIL")
		)
		(pad "25" smd rect
			(at 2.032 0)
			(size 0.9398 0.2032)
			(layers "F.Cu" "F.Mask" "F.Paste")
			(net "MAX31790_A_PWM_ST0")
		)
		(pad "26" smd rect
			(at 2.032 -0.40005)
			(size 0.9398 0.2032)
			(layers "F.Cu" "F.Mask" "F.Paste")
			(net "MAX31790_A_PWM_ST1")
		)
		(pad "27" smd rect
			(at 2.032 -0.8001)
			(size 0.9398 0.2032)
			(layers "F.Cu" "F.Mask" "F.Paste")
			(net "MAX31790_A_FULL_SPEED")
		)
		(pad "28" smd rect
			(at 2.032 -1.199896)
			(size 0.9398 0.2032)
			(layers "F.Cu" "F.Mask" "F.Paste")
			(net "Net_312")
		)
		(pad "29" smd rect
			(at 0 0)
			(size 2.6924 2.6924)
			(layers "F.Cu" "F.Mask" "F.Paste")
			(net "GND")
		)
	)
	(footprint ""
		(layer "F.Cu")
		(at 174.498 -254.127 -90)
		(property "Reference" "C103"
			(at 0 0 270)
			(layer "F.SilkS")
			(hide yes)
			(effects
				(font
					(size 1.27 1.27)
				)
			)
		)
		(property "Value" "SCD033U25V2KX-GP"
			(at 1.1811 -2.7051 270)
			(unlocked yes)
			(layer "F.Fab")
			(hide yes)
			(effects
				(font
					(size 1.016 1.016)
					(thickness 0.1524)
				)
			)
		)
		(property "Device Type" "C402H22"
			(at 1.1811 -4.2291 270)
			(unlocked yes)
			(layer "F.Fab")
			(hide yes)
			(effects
				(font
					(size 1.016 1.016)
					(thickness 0.1524)
				)
			)
		)
		(duplicate_pad_numbers_are_jumpers no)
		(fp_rect
			(start -0.4318 0.9525)
			(end 0.4318 -0.9525)
			(stroke
				(width 0)
				(type default)
			)
			(fill no)
			(layer "F.CrtYd")
		)
		(fp_rect
			(start -0.4318 0.9525)
			(end 0.4318 -0.9525)
			(stroke
				(width 0)
				(type default)
			)
			(fill no)
			(layer "F.Fab")
		)
		(pad "1" smd custom
			(at 0 -0.4445 270)
			(size 0.1524 0.1524)
			(layers "F.Cu" "F.Mask" "F.Paste")
			(net "SW_HDD_P5")
			(options
				(clearance outline)
				(anchor circle)
			)
			(primitives
				(gr_poly
					(pts
						(arc
							(start 0.3048 -0.2032)
							(mid 0.275042 -0.275042)
							(end 0.2032 -0.3048)
						)
						(arc
							(start -0.2032 -0.3048)
							(mid -0.275042 -0.275042)
							(end -0.3048 -0.2032)
						)
						(arc
							(start -0.3048 0.2032)
							(mid -0.275042 0.275042)
							(end -0.2032 0.3048)
						)
						(arc
							(start 0.2032 0.3048)
							(mid 0.275042 0.275042)
							(end 0.3048 0.2032)
						)
					)
					(width 0)
					(fill yes)
				)
			)
		)
		(pad "2" smd custom
			(at 0 0.4445 270)
			(size 0.1524 0.1524)
			(layers "F.Cu" "F.Mask" "F.Paste")
			(net "GND")
			(options
				(clearance outline)
				(anchor circle)
			)
			(primitives
				(gr_poly
					(pts
						(arc
							(start 0.3048 -0.2032)
							(mid 0.275042 -0.275042)
							(end 0.2032 -0.3048)
						)
						(arc
							(start -0.2032 -0.3048)
							(mid -0.275042 -0.275042)
							(end -0.3048 -0.2032)
						)
						(arc
							(start -0.3048 0.2032)
							(mid -0.275042 0.275042)
							(end -0.2032 0.3048)
						)
						(arc
							(start 0.2032 0.3048)
							(mid 0.275042 0.275042)
							(end 0.3048 0.2032)
						)
					)
					(width 0)
					(fill yes)
				)
			)
		)
	)
	(footprint ""
		(layer "F.Cu")
		(at 396.367 -243.586 180)
		(property "Reference" "R292"
			(at 0 0 180)
			(layer "F.SilkS")
			(hide yes)
			(effects
				(font
					(size 1.27 1.27)
				)
			)
		)
		(property "Value" "1KR2F-3-GP"
			(at 0.064008 -3.993896 180)
			(unlocked yes)
			(layer "F.Fab")
			(hide yes)
			(effects
				(font
					(size 1.016 1.016)
					(thickness 0.1524)
				)
			)
		)
		(property "Device Type" "R402H16"
			(at 0.064008 -5.517896 180)
			(unlocked yes)
			(layer "F.Fab")
			(hide yes)
			(effects
				(font
					(size 1.016 1.016)
					(thickness 0.1524)
				)
			)
		)
		(duplicate_pad_numbers_are_jumpers no)
		(fp_line
			(start 0.508 -0.9398)
			(end -0.508 -0.9398)
			(stroke
				(width 0.1524)
				(type default)
			)
			(layer "F.SilkS")
		)
		(fp_line
			(start -0.508 -0.9398)
			(end -0.508 0.9398)
			(stroke
				(width 0.1524)
				(type default)
			)
			(layer "F.SilkS")
		)
		(fp_rect
			(start -0.508 0.9398)
			(end 0.508 -0.9398)
			(stroke
				(width 0)
				(type default)
			)
			(fill no)
			(layer "F.CrtYd")
		)
		(fp_rect
			(start -0.508 0.9398)
			(end 0.508 -0.9398)
			(stroke
				(width 0)
				(type default)
			)
			(fill no)
			(layer "F.Fab")
		)
		(pad "1" smd custom
			(at 0 -0.4445 180)
			(size 0.1397 0.1397)
			(layers "F.Cu" "F.Mask" "F.Paste")
			(net "P3V3_STBY_B")
			(options
				(clearance outline)
				(anchor circle)
			)
			(primitives
				(gr_poly
					(pts
						(arc
							(start -0.1778 -0.2794)
							(mid -0.249642 -0.249642)
							(end -0.2794 -0.1778)
						)
						(arc
							(start -0.2794 0.1778)
							(mid -0.249642 0.249642)
							(end -0.1778 0.2794)
						)
						(arc
							(start 0.1778 0.2794)
							(mid 0.249642 0.249642)
							(end 0.2794 0.1778)
						)
						(arc
							(start 0.2794 -0.1778)
							(mid 0.249642 -0.249642)
							(end 0.1778 -0.2794)
						)
					)
					(width 0)
					(fill yes)
				)
			)
		)
		(pad "2" smd custom
			(at 0 0.4445 180)
			(size 0.1397 0.1397)
			(layers "F.Cu" "F.Mask" "F.Paste")
			(net "SW_PWR_R_HDD8")
			(options
				(clearance outline)
				(anchor circle)
			)
			(primitives
				(gr_poly
					(pts
						(arc
							(start -0.1778 -0.2794)
							(mid -0.249642 -0.249642)
							(end -0.2794 -0.1778)
						)
						(arc
							(start -0.2794 0.1778)
							(mid -0.249642 0.249642)
							(end -0.1778 0.2794)
						)
						(arc
							(start 0.1778 0.2794)
							(mid 0.249642 0.249642)
							(end 0.2794 0.1778)
						)
						(arc
							(start 0.2794 -0.1778)
							(mid 0.249642 -0.249642)
							(end 0.1778 -0.2794)
						)
					)
					(width 0)
					(fill yes)
				)
			)
		)
	)
	(footprint ""
		(layer "F.Cu")
		(at 456.674982 -293.799768)
		(property "Reference" ""
			(at 0 0 0)
			(layer "F.SilkS")
			(hide yes)
			(effects
				(font
					(size 1.27 1.27)
				)
			)
		)
		(property "Value" "*"
			(at -8.398764 -8.057642 0)
			(unlocked yes)
			(layer "F.Fab")
			(hide yes)
			(effects
				(font
					(size 1.016 1.016)
					(thickness 0.1524)
				)
			)
		)
		(duplicate_pad_numbers_are_jumpers no)
		(fp_poly
			(pts
				(arc
					(start 7.3152 0)
					(mid 0 7.3152)
					(end -7.3152 0)
				)
				(arc
					(start -7.3152 -5.9944)
					(mid 0 -13.3096)
					(end 7.3152 -5.9944)
				)
			)
			(stroke
				(width 0)
				(type default)
			)
			(fill no)
			(layer "B.CrtYd")
		)
		(fp_poly
			(pts
				(arc
					(start 7.3152 0)
					(mid 0 7.3152)
					(end -7.3152 0)
				)
				(arc
					(start -7.3152 -5.9944)
					(mid 0 -13.3096)
					(end 7.3152 -5.9944)
				)
			)
			(stroke
				(width 0)
				(type default)
			)
			(fill no)
			(layer "F.CrtYd")
		)
		(fp_poly
			(pts
				(arc
					(start 7.3152 0)
					(mid 0 7.3152)
					(end -7.3152 0)
				)
				(arc
					(start -7.3152 -5.9944)
					(mid 0 -13.3096)
					(end 7.3152 -5.9944)
				)
			)
			(stroke
				(width 0)
				(type default)
			)
			(fill no)
			(layer "B.Fab")
		)
		(fp_poly
			(pts
				(arc
					(start 7.3152 0)
					(mid 0 7.3152)
					(end -7.3152 0)
				)
				(arc
					(start -7.3152 -5.9944)
					(mid 0 -13.3096)
					(end 7.3152 -5.9944)
				)
			)
			(stroke
				(width 0)
				(type default)
			)
			(fill no)
			(layer "F.Fab")
		)
		(pad "1" thru_hole oval
			(at 0 0)
			(size 14.0208 20.0152)
			(drill 0.0254
				(offset 0 -2.9972)
			)
			(layers "*.Cu" "*.Mask")
			(remove_unused_layers no)
			(net "Net_13")
			(clearance -1.002284)
			(thermal_gap 0.1524)
			(padstack
				(mode front_inner_back)
				(layer "Inner"
					(shape custom)
					(size 2.928012 2.928012)
					(options
						(anchor circle)
					)
					(primitives
						(gr_poly
							(pts
								(arc
									(start 4.571746 -2.084324)
									(mid 0.000333 7.430372)
									(end -4.571492 -2.084324)
								)
								(arc
									(start -4.571492 -2.084324)
									(mid -3.570296 -3.611977)
									(end -2.875026 -5.30098)
								)
								(arc
									(start -2.875026 -5.30098)
									(mid 0.000217 -7.43089)
									(end 2.87528 -5.30098)
								)
								(arc
									(start 2.87528 -5.30098)
									(mid 3.570511 -3.611956)
									(end 4.571746 -2.084324)
								)
							)
							(width 0)
							(fill yes)
						)
					)
					(clearance 0.1524)
				)
				(layer "B.Cu"
					(shape oval)
					(size 14.0208 20.0152)
					(offset 0 -2.9972)
					(clearance -1.002284)
				)
			)
		)
		(zone
			(layers "F.Cu" "B.Cu" "In1.Cu" "In2.Cu" "In3.Cu" "In4.Cu" "In5.Cu" "In6.Cu")
			(hatch none 0.5)
			(connect_pads
				(clearance 0)
			)
			(min_thickness 0.25)
			(keepout
				(tracks not_allowed)
				(vias allowed)
				(pads allowed)
				(copperpour not_allowed)
				(footprints allowed)
			)
			(placement
				(enabled no)
				(sheetname "")
			)
			(fill
				(thermal_gap 0.5)
				(thermal_bridge_width 0.5)
				(island_removal_mode 0)
			)
			(polygon
				(pts
					(arc
						(start 449.664582 -299.794168)
						(mid 456.674982 -306.804568)
						(end 463.685382 -299.794168)
					)
					(arc
						(start 463.685382 -293.799768)
						(mid 456.674982 -286.789368)
						(end 449.664582 -293.799768)
					)
				)
			)
		)
	)
	(footprint ""
		(layer "F.Cu")
		(at 113.03 -131.572)
		(property "Reference" "R432"
			(at 0 0 0)
			(layer "F.SilkS")
			(hide yes)
			(effects
				(font
					(size 1.27 1.27)
				)
			)
		)
		(property "Value" "0R2J-2-GP"
			(at 0.064008 -3.993896 0)
			(unlocked yes)
			(layer "F.Fab")
			(hide yes)
			(effects
				(font
					(size 1.016 1.016)
					(thickness 0.1524)
				)
			)
		)
		(property "Device Type" "R402H16"
			(at 0.064008 -5.517896 0)
			(unlocked yes)
			(layer "F.Fab")
			(hide yes)
			(effects
				(font
					(size 1.016 1.016)
					(thickness 0.1524)
				)
			)
		)
		(duplicate_pad_numbers_are_jumpers no)
		(fp_line
			(start -0.508 -0.9398)
			(end -0.508 0.9398)
			(stroke
				(width 0.1524)
				(type default)
			)
			(layer "F.SilkS")
		)
		(fp_line
			(start 0.508 -0.9398)
			(end -0.508 -0.9398)
			(stroke
				(width 0.1524)
				(type default)
			)
			(layer "F.SilkS")
		)
		(fp_rect
			(start -0.508 0.9398)
			(end 0.508 -0.9398)
			(stroke
				(width 0)
				(type default)
			)
			(fill no)
			(layer "F.CrtYd")
		)
		(fp_rect
			(start -0.508 0.9398)
			(end 0.508 -0.9398)
			(stroke
				(width 0)
				(type default)
			)
			(fill no)
			(layer "F.Fab")
		)
		(pad "1" smd custom
			(at 0 -0.4445)
			(size 0.1397 0.1397)
			(layers "F.Cu" "F.Mask" "F.Paste")
			(net "SW_HDD_G15")
			(options
				(clearance outline)
				(anchor circle)
			)
			(primitives
				(gr_poly
					(pts
						(arc
							(start -0.1778 -0.2794)
							(mid -0.249642 -0.249642)
							(end -0.2794 -0.1778)
						)
						(arc
							(start -0.2794 0.1778)
							(mid -0.249642 0.249642)
							(end -0.1778 0.2794)
						)
						(arc
							(start 0.1778 0.2794)
							(mid 0.249642 0.249642)
							(end 0.2794 0.1778)
						)
						(arc
							(start 0.2794 -0.1778)
							(mid 0.249642 -0.249642)
							(end 0.1778 -0.2794)
						)
					)
					(width 0)
					(fill yes)
				)
			)
		)
		(pad "2" smd custom
			(at 0 0.4445)
			(size 0.1397 0.1397)
			(layers "F.Cu" "F.Mask" "F.Paste")
			(net "SW_HDD_R15")
			(options
				(clearance outline)
				(anchor circle)
			)
			(primitives
				(gr_poly
					(pts
						(arc
							(start -0.1778 -0.2794)
							(mid -0.249642 -0.249642)
							(end -0.2794 -0.1778)
						)
						(arc
							(start -0.2794 0.1778)
							(mid -0.249642 0.249642)
							(end -0.1778 0.2794)
						)
						(arc
							(start 0.1778 0.2794)
							(mid 0.249642 0.249642)
							(end 0.2794 0.1778)
						)
						(arc
							(start 0.2794 -0.1778)
							(mid 0.249642 -0.249642)
							(end 0.1778 -0.2794)
						)
					)
					(width 0)
					(fill yes)
				)
			)
		)
	)
	(footprint ""
		(layer "F.Cu")
		(at 48.387 -254.127 -90)
		(property "Reference" "C51"
			(at 0 0 270)
			(layer "F.SilkS")
			(hide yes)
			(effects
				(font
					(size 1.27 1.27)
				)
			)
		)
		(property "Value" "SCD033U25V2KX-GP"
			(at 1.1811 -2.7051 270)
			(unlocked yes)
			(layer "F.Fab")
			(hide yes)
			(effects
				(font
					(size 1.016 1.016)
					(thickness 0.1524)
				)
			)
		)
		(property "Device Type" "C402H22"
			(at 1.1811 -4.2291 270)
			(unlocked yes)
			(layer "F.Fab")
			(hide yes)
			(effects
				(font
					(size 1.016 1.016)
					(thickness 0.1524)
				)
			)
		)
		(duplicate_pad_numbers_are_jumpers no)
		(fp_rect
			(start -0.4318 0.9525)
			(end 0.4318 -0.9525)
			(stroke
				(width 0)
				(type default)
			)
			(fill no)
			(layer "F.CrtYd")
		)
		(fp_rect
			(start -0.4318 0.9525)
			(end 0.4318 -0.9525)
			(stroke
				(width 0)
				(type default)
			)
			(fill no)
			(layer "F.Fab")
		)
		(pad "1" smd custom
			(at 0 -0.4445 270)
			(size 0.1524 0.1524)
			(layers "F.Cu" "F.Mask" "F.Paste")
			(net "SW_HDD_P1")
			(options
				(clearance outline)
				(anchor circle)
			)
			(primitives
				(gr_poly
					(pts
						(arc
							(start 0.3048 -0.2032)
							(mid 0.275042 -0.275042)
							(end 0.2032 -0.3048)
						)
						(arc
							(start -0.2032 -0.3048)
							(mid -0.275042 -0.275042)
							(end -0.3048 -0.2032)
						)
						(arc
							(start -0.3048 0.2032)
							(mid -0.275042 0.275042)
							(end -0.2032 0.3048)
						)
						(arc
							(start 0.2032 0.3048)
							(mid 0.275042 0.275042)
							(end 0.3048 0.2032)
						)
					)
					(width 0)
					(fill yes)
				)
			)
		)
		(pad "2" smd custom
			(at 0 0.4445 270)
			(size 0.1524 0.1524)
			(layers "F.Cu" "F.Mask" "F.Paste")
			(net "GND")
			(options
				(clearance outline)
				(anchor circle)
			)
			(primitives
				(gr_poly
					(pts
						(arc
							(start 0.3048 -0.2032)
							(mid 0.275042 -0.275042)
							(end 0.2032 -0.3048)
						)
						(arc
							(start -0.2032 -0.3048)
							(mid -0.275042 -0.275042)
							(end -0.3048 -0.2032)
						)
						(arc
							(start -0.3048 0.2032)
							(mid -0.275042 0.275042)
							(end -0.2032 0.3048)
						)
						(arc
							(start 0.2032 0.3048)
							(mid 0.275042 0.275042)
							(end 0.3048 0.2032)
						)
					)
					(width 0)
					(fill yes)
				)
			)
		)
	)
	(footprint ""
		(layer "F.Cu")
		(at 460.5274 -6.2992 -90)
		(property "Reference" "C32"
			(at 0 0 270)
			(layer "F.SilkS")
			(hide yes)
			(effects
				(font
					(size 1.27 1.27)
				)
			)
		)
		(property "Value" "SCD1U16V2KX-3GP"
			(at 1.1811 -2.7051 270)
			(unlocked yes)
			(layer "F.Fab")
			(hide yes)
			(effects
				(font
					(size 1.016 1.016)
					(thickness 0.1524)
				)
			)
		)
		(property "Device Type" "C402H22"
			(at 1.1811 -4.2291 270)
			(unlocked yes)
			(layer "F.Fab")
			(hide yes)
			(effects
				(font
					(size 1.016 1.016)
					(thickness 0.1524)
				)
			)
		)
		(duplicate_pad_numbers_are_jumpers no)
		(fp_rect
			(start -0.4318 0.9525)
			(end 0.4318 -0.9525)
			(stroke
				(width 0)
				(type default)
			)
			(fill no)
			(layer "F.CrtYd")
		)
		(fp_rect
			(start -0.4318 0.9525)
			(end 0.4318 -0.9525)
			(stroke
				(width 0)
				(type default)
			)
			(fill no)
			(layer "F.Fab")
		)
		(pad "1" smd custom
			(at 0 -0.4445 270)
			(size 0.1524 0.1524)
			(layers "F.Cu" "F.Mask" "F.Paste")
			(net "GND")
			(options
				(clearance outline)
				(anchor circle)
			)
			(primitives
				(gr_poly
					(pts
						(arc
							(start 0.3048 -0.2032)
							(mid 0.275042 -0.275042)
							(end 0.2032 -0.3048)
						)
						(arc
							(start -0.2032 -0.3048)
							(mid -0.275042 -0.275042)
							(end -0.3048 -0.2032)
						)
						(arc
							(start -0.3048 0.2032)
							(mid -0.275042 0.275042)
							(end -0.2032 0.3048)
						)
						(arc
							(start 0.2032 0.3048)
							(mid 0.275042 0.275042)
							(end 0.3048 0.2032)
						)
					)
					(width 0)
					(fill yes)
				)
			)
		)
		(pad "2" smd custom
			(at 0 0.4445 270)
			(size 0.1524 0.1524)
			(layers "F.Cu" "F.Mask" "F.Paste")
			(net "P3V3_STBY_B")
			(options
				(clearance outline)
				(anchor circle)
			)
			(primitives
				(gr_poly
					(pts
						(arc
							(start 0.3048 -0.2032)
							(mid 0.275042 -0.275042)
							(end 0.2032 -0.3048)
						)
						(arc
							(start -0.2032 -0.3048)
							(mid -0.275042 -0.275042)
							(end -0.3048 -0.2032)
						)
						(arc
							(start -0.3048 0.2032)
							(mid -0.275042 0.275042)
							(end -0.2032 0.3048)
						)
						(arc
							(start 0.2032 0.3048)
							(mid 0.275042 0.275042)
							(end 0.3048 0.2032)
						)
					)
					(width 0)
					(fill yes)
				)
			)
		)
	)
	(footprint ""
		(layer "F.Cu")
		(at 479.384614 -129.66065 -90)
		(property "Reference" "C328"
			(at 0 0 270)
			(layer "F.SilkS")
			(hide yes)
			(effects
				(font
					(size 1.27 1.27)
				)
			)
		)
		(property "Value" "SCD01U16V1KX-GP"
			(at -2.8321 -1.7399 270)
			(unlocked yes)
			(layer "F.Fab")
			(hide yes)
			(effects
				(font
					(size 1.016 1.016)
					(thickness 0.1524)
				)
			)
		)
		(property "Device Type" "C0201H13"
			(at -2.8321 -3.2639 270)
			(unlocked yes)
			(layer "F.Fab")
			(hide yes)
			(effects
				(font
					(size 1.016 1.016)
					(thickness 0.1524)
				)
			)
		)
		(duplicate_pad_numbers_are_jumpers no)
		(fp_rect
			(start -0.2794 0.6477)
			(end 0.2794 -0.6477)
			(stroke
				(width 0)
				(type default)
			)
			(fill no)
			(layer "F.CrtYd")
		)
		(fp_rect
			(start -0.2794 0.6477)
			(end 0.2794 -0.6477)
			(stroke
				(width 0)
				(type default)
			)
			(fill no)
			(layer "F.Fab")
		)
		(pad "1" smd custom
			(at 0 -0.2794 270)
			(size 0.0762 0.0762)
			(layers "F.Cu" "F.Mask" "F.Paste")
			(net "SAS_HDD_RX_P23")
			(options
				(clearance outline)
				(anchor circle)
			)
			(primitives
				(gr_poly
					(pts
						(arc
							(start 0.1524 -0.127)
							(mid 0.137521 -0.162921)
							(end 0.1016 -0.1778)
						)
						(arc
							(start -0.1016 -0.1778)
							(mid -0.137521 -0.162921)
							(end -0.1524 -0.127)
						)
						(arc
							(start -0.1524 0.127)
							(mid -0.137521 0.162921)
							(end -0.1016 0.1778)
						)
						(arc
							(start 0.1016 0.1778)
							(mid 0.137521 0.162921)
							(end 0.1524 0.127)
						)
					)
					(width 0)
					(fill yes)
				)
			)
		)
		(pad "2" smd custom
			(at 0 0.2794 270)
			(size 0.0762 0.0762)
			(layers "F.Cu" "F.Mask" "F.Paste")
			(net "PHY_SCC_B_TO_DRV_B_23_DP")
			(options
				(clearance outline)
				(anchor circle)
			)
			(primitives
				(gr_poly
					(pts
						(arc
							(start 0.1524 -0.127)
							(mid 0.137521 -0.162921)
							(end 0.1016 -0.1778)
						)
						(arc
							(start -0.1016 -0.1778)
							(mid -0.137521 -0.162921)
							(end -0.1524 -0.127)
						)
						(arc
							(start -0.1524 0.127)
							(mid -0.137521 0.162921)
							(end -0.1016 0.1778)
						)
						(arc
							(start 0.1016 0.1778)
							(mid 0.137521 0.162921)
							(end 0.1524 0.127)
						)
					)
					(width 0)
					(fill yes)
				)
			)
		)
	)
	(footprint ""
		(layer "F.Cu")
		(at 420.200074 -258.910074 -90)
		(property "Reference" "HDDSAS9"
			(at 0 0 270)
			(layer "F.SilkS")
			(hide yes)
			(effects
				(font
					(size 1.27 1.27)
				)
			)
		)
		(property "Value" "SKT-SAS15P-14P-45-GP"
			(at -20.7645 -8.9789 270)
			(unlocked yes)
			(layer "F.Fab")
			(hide yes)
			(effects
				(font
					(size 1.016 1.016)
					(thickness 0.1524)
				)
			)
		)
		(property "Device Type" "10120818-001C-TRLF"
			(at -20.7645 -10.5029 270)
			(unlocked yes)
			(layer "F.Fab")
			(hide yes)
			(effects
				(font
					(size 1.016 1.016)
					(thickness 0.1524)
				)
			)
		)
		(duplicate_pad_numbers_are_jumpers no)
		(fp_line
			(start 1.651 4.2926)
			(end 1.651 3.0099)
			(stroke
				(width 0.1524)
				(type default)
			)
			(layer "F.SilkS")
		)
		(fp_line
			(start 8.509 4.2926)
			(end 1.651 4.2926)
			(stroke
				(width 0.1524)
				(type default)
			)
			(layer "F.SilkS")
		)
		(fp_line
			(start -23.4188 3.0099)
			(end -23.4188 -3.2512)
			(stroke
				(width 0.1524)
				(type default)
			)
			(layer "F.SilkS")
		)
		(fp_line
			(start 1.651 3.0099)
			(end -23.4188 3.0099)
			(stroke
				(width 0.1524)
				(type default)
			)
			(layer "F.SilkS")
		)
		(fp_line
			(start 8.509 3.0099)
			(end 8.509 4.2926)
			(stroke
				(width 0.1524)
				(type default)
			)
			(layer "F.SilkS")
		)
		(fp_line
			(start 23.4188 3.0099)
			(end 8.509 3.0099)
			(stroke
				(width 0.1524)
				(type default)
			)
			(layer "F.SilkS")
		)
		(fp_line
			(start -23.4188 -3.2512)
			(end 23.4188 -3.2512)
			(stroke
				(width 0.1524)
				(type default)
			)
			(layer "F.SilkS")
		)
		(fp_line
			(start 23.4188 -3.2512)
			(end 23.4188 3.0099)
			(stroke
				(width 0.1524)
				(type default)
			)
			(layer "F.SilkS")
		)
		(fp_line
			(start 15.5067 -3.3401)
			(end 16.2687 -3.3401)
			(stroke
				(width 0.3302)
				(type default)
			)
			(layer "F.SilkS")
		)
		(fp_poly
			(pts
				(xy 15.868904 -3.230372) (xy 16.503904 -3.865372) (xy 15.233904 -3.865372)
			)
			(stroke
				(width 0)
				(type default)
			)
			(fill yes)
			(layer "F.SilkS")
		)
		(fp_poly
			(pts
				(xy -22.8727 -2.7559) (xy 22.8727 -2.7559) (xy 22.8727 2.7559) (xy 8.255 2.7559) (xy 8.255 3.5179)
				(xy 1.905 3.5179) (xy 1.905 2.7559) (xy -22.8727 2.7559)
			)
			(stroke
				(width 0)
				(type default)
			)
			(fill no)
			(layer "F.CrtYd")
		)
		(fp_poly
			(pts
				(xy 1.397 4.5466) (xy 1.397 3.2639) (xy -23.6728 3.2639) (xy -23.6728 -3.5052) (xy 23.6728 -3.5052)
				(xy 23.6728 -0.00635) (xy 22.8727 -0.00635) (xy 22.8727 -2.7559) (xy -22.8727 -2.7559) (xy -22.8727 2.7559)
				(xy 1.905 2.7559) (xy 1.905 3.5179) (xy 8.255 3.5179) (xy 8.255 2.7559) (xy 22.8727 2.7559) (xy 22.8727 0.00635)
				(xy 23.6728 0.00635) (xy 23.6728 3.2639) (xy 8.763 3.2639) (xy 8.763 4.5466)
			)
			(stroke
				(width 0)
				(type default)
			)
			(fill no)
			(layer "F.CrtYd")
		)
		(fp_poly
			(pts
				(xy 1.397 4.5466) (xy 1.397 3.2639) (xy -23.6728 3.2639) (xy -23.6728 -3.5052) (xy 23.6728 -3.5052)
				(xy 23.6728 3.2639) (xy 8.763 3.2639) (xy 8.763 4.5466)
			)
			(stroke
				(width 0)
				(type default)
			)
			(fill no)
			(layer "F.Fab")
		)
		(pad "" np_thru_hole circle
			(at -18.874994 0 270)
			(size 0.254 0.254)
			(drill 1.3462)
			(layers "*.Cu" "*.Mask")
			(clearance 0.9017)
			(thermal_gap 0.9017)
		)
		(pad "" np_thru_hole circle
			(at 18.874994 0 270)
			(size 0.254 0.254)
			(drill 0.9398)
			(layers "*.Cu" "*.Mask")
			(clearance 0.6985)
			(thermal_gap 0.6985)
		)
		(pad "G1" smd rect
			(at 21.874988 0 270)
			(size 2.5908 2.5908)
			(layers "F.Cu" "F.Mask" "F.Paste")
			(net "GND")
		)
		(pad "G2" smd rect
			(at -21.874988 0 270)
			(size 2.5908 2.5908)
			(layers "F.Cu" "F.Mask" "F.Paste")
			(net "GND")
		)
		(pad "P1" smd rect
			(at 1.905 -1.82499 270)
			(size 0.6096 2.3622)
			(layers "F.Cu" "F.Mask" "F.Paste")
			(net "Net_1759")
		)
		(pad "P2" smd rect
			(at 0.635 -1.82499 270)
			(size 0.6096 2.3622)
			(layers "F.Cu" "F.Mask" "F.Paste")
			(net "Net_1760")
		)
		(pad "P3" smd rect
			(at -0.635 -1.82499 270)
			(size 0.6096 2.3622)
			(layers "F.Cu" "F.Mask" "F.Paste")
			(net "Net_1761")
		)
		(pad "P4" smd rect
			(at -1.905 -1.82499 270)
			(size 0.6096 2.3622)
			(layers "F.Cu" "F.Mask" "F.Paste")
			(net "GND")
		)
		(pad "P5" smd rect
			(at -3.175 -1.82499 270)
			(size 0.6096 2.3622)
			(layers "F.Cu" "F.Mask" "F.Paste")
			(net "HDD_PRSNT_9")
		)
		(pad "P6" smd rect
			(at -4.445 -1.82499 270)
			(size 0.6096 2.3622)
			(layers "F.Cu" "F.Mask" "F.Paste")
			(net "GND")
		)
		(pad "P7" smd rect
			(at -5.715 -1.82499 270)
			(size 0.6096 2.3622)
			(layers "F.Cu" "F.Mask" "F.Paste")
			(net "5V_PRE_9")
		)
		(pad "P8" smd rect
			(at -6.985 -1.82499 270)
			(size 0.6096 2.3622)
			(layers "F.Cu" "F.Mask" "F.Paste")
			(net "P5V_HDD9")
		)
		(pad "P9" smd rect
			(at -8.255 -1.82499 270)
			(size 0.6096 2.3622)
			(layers "F.Cu" "F.Mask" "F.Paste")
			(net "P5V_HDD9")
		)
		(pad "P10" smd rect
			(at -9.525 -1.82499 270)
			(size 0.6096 2.3622)
			(layers "F.Cu" "F.Mask" "F.Paste")
			(net "GND")
		)
		(pad "P11" smd rect
			(at -10.795 -1.82499 270)
			(size 0.6096 2.3622)
			(layers "F.Cu" "F.Mask" "F.Paste")
			(net "ACT_HDD_9")
		)
		(pad "P12" smd rect
			(at -12.065 -1.82499 270)
			(size 0.6096 2.3622)
			(layers "F.Cu" "F.Mask" "F.Paste")
			(net "GND")
		)
		(pad "P13" smd rect
			(at -13.335 -1.82499 270)
			(size 0.6096 2.3622)
			(layers "F.Cu" "F.Mask" "F.Paste")
			(net "12V_PRE_9")
		)
		(pad "P14" smd rect
			(at -14.605 -1.82499 270)
			(size 0.6096 2.3622)
			(layers "F.Cu" "F.Mask" "F.Paste")
			(net "P12V_HDD9")
		)
		(pad "P15" smd rect
			(at -15.875 -1.82499 270)
			(size 0.6096 2.3622)
			(layers "F.Cu" "F.Mask" "F.Paste")
			(net "P12V_HDD9")
		)
		(pad "S1" smd rect
			(at 15.875 -1.82499 270)
			(size 0.6096 2.3622)
			(layers "F.Cu" "F.Mask" "F.Paste")
			(net "GND")
		)
		(pad "S2" smd rect
			(at 14.605 -1.82499 270)
			(size 0.6096 2.3622)
			(layers "F.Cu" "F.Mask" "F.Paste")
			(net "SAS_HDD_RX_P9")
		)
		(pad "S3" smd rect
			(at 13.335 -1.82499 270)
			(size 0.6096 2.3622)
			(layers "F.Cu" "F.Mask" "F.Paste")
			(net "SAS_HDD_RX_N9")
		)
		(pad "S4" smd rect
			(at 12.065 -1.82499 270)
			(size 0.6096 2.3622)
			(layers "F.Cu" "F.Mask" "F.Paste")
			(net "GND")
		)
		(pad "S5" smd rect
			(at 10.795 -1.82499 270)
			(size 0.6096 2.3622)
			(layers "F.Cu" "F.Mask" "F.Paste")
			(net "PHY_DRV_B_TO_SCC_B_9_DN")
		)
		(pad "S6" smd rect
			(at 9.525 -1.82499 270)
			(size 0.6096 2.3622)
			(layers "F.Cu" "F.Mask" "F.Paste")
			(net "PHY_DRV_B_TO_SCC_B_9_DP")
		)
		(pad "S7" smd rect
			(at 8.255 -1.82499 270)
			(size 0.6096 2.3622)
			(layers "F.Cu" "F.Mask" "F.Paste")
			(net "GND")
		)
		(pad "S8" smd rect
			(at 7.480046 2.845054 270)
			(size 0.508 2.3622)
			(layers "F.Cu" "F.Mask" "F.Paste")
			(net "GND")
		)
		(pad "S9" smd rect
			(at 6.679946 2.845054 270)
			(size 0.508 2.3622)
			(layers "F.Cu" "F.Mask" "F.Paste")
			(net "Net_432")
		)
		(pad "S10" smd rect
			(at 5.8801 2.845054 270)
			(size 0.508 2.3622)
			(layers "F.Cu" "F.Mask" "F.Paste")
			(net "Net_324")
		)
		(pad "S11" smd rect
			(at 5.08 2.845054 270)
			(size 0.508 2.3622)
			(layers "F.Cu" "F.Mask" "F.Paste")
			(net "GND")
		)
		(pad "S12" smd rect
			(at 4.2799 2.845054 270)
			(size 0.508 2.3622)
			(layers "F.Cu" "F.Mask" "F.Paste")
			(net "Net_360")
		)
		(pad "S13" smd rect
			(at 3.480054 2.845054 270)
			(size 0.508 2.3622)
			(layers "F.Cu" "F.Mask" "F.Paste")
			(net "Net_396")
		)
		(pad "S14" smd rect
			(at 2.679954 2.845054 270)
			(size 0.508 2.3622)
			(layers "F.Cu" "F.Mask" "F.Paste")
			(net "GND")
		)
		(zone
			(layer "F.Cu")
			(hatch none 0.5)
			(connect_pads
				(clearance 0)
			)
			(min_thickness 0.25)
			(keepout
				(tracks allowed)
				(vias not_allowed)
				(pads allowed)
				(copperpour not_allowed)
				(footprints allowed)
			)
			(placement
				(enabled no)
				(sheetname "")
			)
			(fill
				(thermal_gap 0.5)
				(thermal_bridge_width 0.5)
				(island_removal_mode 0)
			)
			(polygon
				(pts
					(xy 423.857674 -275.648674) (xy 416.783774 -275.648674) (xy 416.783774 -282.582874) (xy 417.888674 -282.582874)
					(xy 417.888674 -278.468074) (xy 422.511474 -278.468074) (xy 422.511474 -282.582874) (xy 423.857674 -282.582874)
				)
			)
		)
		(zone
			(layer "F.Cu")
			(hatch none 0.5)
			(connect_pads
				(clearance 0)
			)
			(min_thickness 0.25)
			(keepout
				(tracks not_allowed)
				(vias allowed)
				(pads allowed)
				(copperpour not_allowed)
				(footprints allowed)
			)
			(placement
				(enabled no)
				(sheetname "")
			)
			(fill
				(thermal_gap 0.5)
				(thermal_bridge_width 0.5)
				(island_removal_mode 0)
			)
			(polygon
				(pts
					(xy 423.857674 -275.648674) (xy 416.783774 -275.648674) (xy 416.783774 -282.582874) (xy 417.888674 -282.582874)
					(xy 417.888674 -278.468074) (xy 422.511474 -278.468074) (xy 422.511474 -282.582874) (xy 423.857674 -282.582874)
				)
			)
		)
		(zone
			(layer "F.Cu")
			(hatch none 0.5)
			(connect_pads
				(clearance 0)
			)
			(min_thickness 0.25)
			(keepout
				(tracks allowed)
				(vias not_allowed)
				(pads allowed)
				(copperpour not_allowed)
				(footprints allowed)
			)
			(placement
				(enabled no)
				(sheetname "")
			)
			(fill
				(thermal_gap 0.5)
				(thermal_bridge_width 0.5)
				(island_removal_mode 0)
			)
			(polygon
				(pts
					(xy 423.857674 -242.171474) (xy 416.783774 -242.171474) (xy 416.783774 -235.237274) (xy 417.888674 -235.237274)
					(xy 417.888674 -239.352074) (xy 422.511474 -239.352074) (xy 422.511474 -235.237274) (xy 423.857674 -235.237274)
				)
			)
		)
		(zone
			(layer "F.Cu")
			(hatch none 0.5)
			(connect_pads
				(clearance 0)
			)
			(min_thickness 0.25)
			(keepout
				(tracks not_allowed)
				(vias allowed)
				(pads allowed)
				(copperpour not_allowed)
				(footprints allowed)
			)
			(placement
				(enabled no)
				(sheetname "")
			)
			(fill
				(thermal_gap 0.5)
				(thermal_bridge_width 0.5)
				(island_removal_mode 0)
			)
			(polygon
				(pts
					(xy 423.857674 -242.171474) (xy 416.783774 -242.171474) (xy 416.783774 -235.237274) (xy 417.888674 -235.237274)
					(xy 417.888674 -239.352074) (xy 422.511474 -239.352074) (xy 422.511474 -235.237274) (xy 423.857674 -235.237274)
				)
			)
		)
		(zone
			(layers "F.Cu" "B.Cu" "In1.Cu" "In2.Cu" "In3.Cu" "In4.Cu" "In5.Cu" "In6.Cu")
			(hatch none 0.5)
			(connect_pads
				(clearance 0)
			)
			(min_thickness 0.25)
			(keepout
				(tracks not_allowed)
				(vias allowed)
				(pads allowed)
				(copperpour not_allowed)
				(footprints allowed)
			)
			(placement
				(enabled no)
				(sheetname "")
			)
			(fill
				(thermal_gap 0.5)
				(thermal_bridge_width 0.5)
				(island_removal_mode 0)
			)
			(polygon
				(pts
					(arc
						(start 420.974774 -240.03508)
						(mid 419.425374 -240.03508)
						(end 420.974774 -240.03508)
					)
				)
			)
		)
		(zone
			(layers "F.Cu" "B.Cu" "In1.Cu" "In2.Cu" "In3.Cu" "In4.Cu" "In5.Cu" "In6.Cu")
			(hatch none 0.5)
			(connect_pads
				(clearance 0)
			)
			(min_thickness 0.25)
			(keepout
				(tracks not_allowed)
				(vias allowed)
				(pads allowed)
				(copperpour not_allowed)
				(footprints allowed)
			)
			(placement
				(enabled no)
				(sheetname "")
			)
			(fill
				(thermal_gap 0.5)
				(thermal_bridge_width 0.5)
				(island_removal_mode 0)
			)
			(polygon
				(pts
					(arc
						(start 421.177974 -277.785068)
						(mid 419.222174 -277.785068)
						(end 421.177974 -277.785068)
					)
				)
			)
		)
	)
	(footprint ""
		(layer "F.Cu")
		(at 481.066602 -17.4371)
		(property "Reference" "VIA72"
			(at 0 0 0)
			(layer "F.SilkS")
			(hide yes)
			(effects
				(font
					(size 1.27 1.27)
				)
			)
		)
		(property "Value" "100OHM-8L-2D36MM-L16-GP"
			(at -3.4036 -0.4572 0)
			(unlocked yes)
			(layer "F.Fab")
			(hide yes)
			(effects
				(font
					(size 1.016 1.016)
					(thickness 0.1524)
				)
			)
		)
		(property "Device Type" "VIA-PCIE-4P-427097"
			(at -3.4036 -1.9812 0)
			(unlocked yes)
			(layer "F.Fab")
			(hide yes)
			(effects
				(font
					(size 1.016 1.016)
					(thickness 0.1524)
				)
			)
		)
		(duplicate_pad_numbers_are_jumpers no)
		(fp_rect
			(start -2.1336 0.4826)
			(end 2.1336 -0.4826)
			(stroke
				(width 0)
				(type default)
			)
			(fill no)
			(layer "F.CrtYd")
		)
		(fp_rect
			(start -2.1336 0.4826)
			(end 2.1336 -0.4826)
			(stroke
				(width 0)
				(type default)
			)
			(fill no)
			(layer "F.Fab")
		)
		(pad "1" thru_hole circle
			(at -1.651 0)
			(size 0.508 0.508)
			(drill 0.254)
			(layers "*.Cu" "*.Mask")
			(remove_unused_layers no)
			(net "GND")
			(clearance 0.2286)
			(thermal_gap 0.2286)
		)
		(pad "2" thru_hole circle
			(at -0.635 0)
			(size 0.508 0.508)
			(drill 0.254)
			(layers "*.Cu" "*.Mask")
			(remove_unused_layers no)
			(net "PHY_DRV_B_TO_SCC_B_35_DP")
			(clearance 0.2286)
			(thermal_gap 0.2286)
		)
		(pad "3" thru_hole circle
			(at 0.635 0)
			(size 0.508 0.508)
			(drill 0.254)
			(layers "*.Cu" "*.Mask")
			(remove_unused_layers no)
			(net "PHY_DRV_B_TO_SCC_B_35_DN")
			(clearance 0.2286)
			(thermal_gap 0.2286)
		)
		(pad "4" thru_hole circle
			(at 1.651 0)
			(size 0.508 0.508)
			(drill 0.254)
			(layers "*.Cu" "*.Mask")
			(remove_unused_layers no)
			(net "GND")
			(clearance 0.2286)
			(thermal_gap 0.2286)
		)
	)
	(footprint ""
		(layer "F.Cu")
		(at 330.294996 -364.998)
		(property "Reference" "C533"
			(at 0 0 0)
			(layer "F.SilkS")
			(hide yes)
			(effects
				(font
					(size 1.27 1.27)
				)
			)
		)
		(property "Value" "SCD1U25V2KX-2-GP"
			(at 1.1811 -2.7051 0)
			(unlocked yes)
			(layer "F.Fab")
			(hide yes)
			(effects
				(font
					(size 1.016 1.016)
					(thickness 0.1524)
				)
			)
		)
		(property "Device Type" "C402H22"
			(at 1.1811 -4.2291 0)
			(unlocked yes)
			(layer "F.Fab")
			(hide yes)
			(effects
				(font
					(size 1.016 1.016)
					(thickness 0.1524)
				)
			)
		)
		(duplicate_pad_numbers_are_jumpers no)
		(fp_rect
			(start -0.4318 0.9525)
			(end 0.4318 -0.9525)
			(stroke
				(width 0)
				(type default)
			)
			(fill no)
			(layer "F.CrtYd")
		)
		(fp_rect
			(start -0.4318 0.9525)
			(end 0.4318 -0.9525)
			(stroke
				(width 0)
				(type default)
			)
			(fill no)
			(layer "F.Fab")
		)
		(pad "1" smd custom
			(at 0 -0.4445)
			(size 0.1524 0.1524)
			(layers "F.Cu" "F.Mask" "F.Paste")
			(net "FAN_2_TACH1")
			(options
				(clearance outline)
				(anchor circle)
			)
			(primitives
				(gr_poly
					(pts
						(arc
							(start 0.3048 -0.2032)
							(mid 0.275042 -0.275042)
							(end 0.2032 -0.3048)
						)
						(arc
							(start -0.2032 -0.3048)
							(mid -0.275042 -0.275042)
							(end -0.3048 -0.2032)
						)
						(arc
							(start -0.3048 0.2032)
							(mid -0.275042 0.275042)
							(end -0.2032 0.3048)
						)
						(arc
							(start 0.2032 0.3048)
							(mid 0.275042 0.275042)
							(end 0.3048 0.2032)
						)
					)
					(width 0)
					(fill yes)
				)
			)
		)
		(pad "2" smd custom
			(at 0 0.4445)
			(size 0.1524 0.1524)
			(layers "F.Cu" "F.Mask" "F.Paste")
			(net "GND")
			(options
				(clearance outline)
				(anchor circle)
			)
			(primitives
				(gr_poly
					(pts
						(arc
							(start 0.3048 -0.2032)
							(mid 0.275042 -0.275042)
							(end 0.2032 -0.3048)
						)
						(arc
							(start -0.2032 -0.3048)
							(mid -0.275042 -0.275042)
							(end -0.3048 -0.2032)
						)
						(arc
							(start -0.3048 0.2032)
							(mid -0.275042 0.275042)
							(end -0.2032 0.3048)
						)
						(arc
							(start 0.2032 0.3048)
							(mid 0.275042 0.275042)
							(end 0.3048 0.2032)
						)
					)
					(width 0)
					(fill yes)
				)
			)
		)
	)
	(footprint ""
		(layer "F.Cu")
		(at 14.732 -150.622 -90)
		(property "Reference" "C191"
			(at 0 0 270)
			(layer "F.SilkS")
			(hide yes)
			(effects
				(font
					(size 1.27 1.27)
				)
			)
		)
		(property "Value" "SC4D7U25V5KX-1-GP"
			(at -0.0762 -6.1214 270)
			(unlocked yes)
			(layer "F.Fab")
			(hide yes)
			(effects
				(font
					(size 1.016 1.016)
					(thickness 0.1524)
				)
			)
		)
		(property "Device Type" "C805H58"
			(at -0.0762 -8.1534 270)
			(unlocked yes)
			(layer "F.Fab")
			(hide yes)
			(effects
				(font
					(size 1.016 1.016)
					(thickness 0.1524)
				)
			)
		)
		(duplicate_pad_numbers_are_jumpers no)
		(fp_line
			(start 0.635 0)
			(end -0.635 0)
			(stroke
				(width 0.508)
				(type default)
			)
			(layer "F.SilkS")
		)
		(fp_rect
			(start -0.9652 1.778)
			(end 0.9652 -1.778)
			(stroke
				(width 0)
				(type default)
			)
			(fill no)
			(layer "F.CrtYd")
		)
		(fp_poly
			(pts
				(xy -0.9652 -1.778) (xy 0.9652 -1.778) (xy 0.9652 1.778) (xy -0.9652 1.778)
			)
			(stroke
				(width 0)
				(type default)
			)
			(fill no)
			(layer "F.Fab")
		)
		(pad "1" smd rect
			(at 0 -0.9652 270)
			(size 1.397 1.143)
			(layers "F.Cu" "F.Mask" "F.Paste")
			(net "P12V_HDD12")
		)
		(pad "2" smd rect
			(at 0 0.9652 270)
			(size 1.397 1.143)
			(layers "F.Cu" "F.Mask" "F.Paste")
			(net "GND")
		)
	)
	(footprint ""
		(layer "F.Cu")
		(at 127.113284 -129.66065 90)
		(property "Reference" "C224"
			(at 0 0 90)
			(layer "F.SilkS")
			(hide yes)
			(effects
				(font
					(size 1.27 1.27)
				)
			)
		)
		(property "Value" "SCD01U16V1KX-GP"
			(at -2.8321 -1.7399 90)
			(unlocked yes)
			(layer "F.Fab")
			(hide yes)
			(effects
				(font
					(size 1.016 1.016)
					(thickness 0.1524)
				)
			)
		)
		(property "Device Type" "C0201H13"
			(at -2.8321 -3.2639 90)
			(unlocked yes)
			(layer "F.Fab")
			(hide yes)
			(effects
				(font
					(size 1.016 1.016)
					(thickness 0.1524)
				)
			)
		)
		(duplicate_pad_numbers_are_jumpers no)
		(fp_rect
			(start -0.2794 0.6477)
			(end 0.2794 -0.6477)
			(stroke
				(width 0)
				(type default)
			)
			(fill no)
			(layer "F.CrtYd")
		)
		(fp_rect
			(start -0.2794 0.6477)
			(end 0.2794 -0.6477)
			(stroke
				(width 0)
				(type default)
			)
			(fill no)
			(layer "F.Fab")
		)
		(pad "1" smd custom
			(at 0 -0.2794 90)
			(size 0.0762 0.0762)
			(layers "F.Cu" "F.Mask" "F.Paste")
			(net "SAS_HDD_RX_P15")
			(options
				(clearance outline)
				(anchor circle)
			)
			(primitives
				(gr_poly
					(pts
						(arc
							(start 0.1524 -0.127)
							(mid 0.137521 -0.162921)
							(end 0.1016 -0.1778)
						)
						(arc
							(start -0.1016 -0.1778)
							(mid -0.137521 -0.162921)
							(end -0.1524 -0.127)
						)
						(arc
							(start -0.1524 0.127)
							(mid -0.137521 0.162921)
							(end -0.1016 0.1778)
						)
						(arc
							(start 0.1016 0.1778)
							(mid 0.137521 0.162921)
							(end 0.1524 0.127)
						)
					)
					(width 0)
					(fill yes)
				)
			)
		)
		(pad "2" smd custom
			(at 0 0.2794 90)
			(size 0.0762 0.0762)
			(layers "F.Cu" "F.Mask" "F.Paste")
			(net "PHY_SCC_B_TO_DRV_B_15_DP")
			(options
				(clearance outline)
				(anchor circle)
			)
			(primitives
				(gr_poly
					(pts
						(arc
							(start 0.1524 -0.127)
							(mid 0.137521 -0.162921)
							(end 0.1016 -0.1778)
						)
						(arc
							(start -0.1016 -0.1778)
							(mid -0.137521 -0.162921)
							(end -0.1524 -0.127)
						)
						(arc
							(start -0.1524 0.127)
							(mid -0.137521 0.162921)
							(end -0.1016 0.1778)
						)
						(arc
							(start 0.1016 0.1778)
							(mid 0.137521 0.162921)
							(end 0.1524 0.127)
						)
					)
					(width 0)
					(fill yes)
				)
			)
		)
	)
	(footprint ""
		(layer "F.Cu")
		(at 430.403 -128.651 180)
		(property "Reference" "R564"
			(at 0 0 180)
			(layer "F.SilkS")
			(hide yes)
			(effects
				(font
					(size 1.27 1.27)
				)
			)
		)
		(property "Value" "0R2J-2-GP"
			(at 0.064008 -3.993896 180)
			(unlocked yes)
			(layer "F.Fab")
			(hide yes)
			(effects
				(font
					(size 1.016 1.016)
					(thickness 0.1524)
				)
			)
		)
		(property "Device Type" "R402H16"
			(at 0.064008 -5.517896 180)
			(unlocked yes)
			(layer "F.Fab")
			(hide yes)
			(effects
				(font
					(size 1.016 1.016)
					(thickness 0.1524)
				)
			)
		)
		(duplicate_pad_numbers_are_jumpers no)
		(fp_line
			(start 0.508 -0.9398)
			(end -0.508 -0.9398)
			(stroke
				(width 0.1524)
				(type default)
			)
			(layer "F.SilkS")
		)
		(fp_line
			(start -0.508 -0.9398)
			(end -0.508 0.9398)
			(stroke
				(width 0.1524)
				(type default)
			)
			(layer "F.SilkS")
		)
		(fp_rect
			(start -0.508 0.9398)
			(end 0.508 -0.9398)
			(stroke
				(width 0)
				(type default)
			)
			(fill no)
			(layer "F.CrtYd")
		)
		(fp_rect
			(start -0.508 0.9398)
			(end 0.508 -0.9398)
			(stroke
				(width 0)
				(type default)
			)
			(fill no)
			(layer "F.Fab")
		)
		(pad "1" smd custom
			(at 0 -0.4445 180)
			(size 0.1397 0.1397)
			(layers "F.Cu" "F.Mask" "F.Paste")
			(net "DRIVE_B_21_PWR")
			(options
				(clearance outline)
				(anchor circle)
			)
			(primitives
				(gr_poly
					(pts
						(arc
							(start -0.1778 -0.2794)
							(mid -0.249642 -0.249642)
							(end -0.2794 -0.1778)
						)
						(arc
							(start -0.2794 0.1778)
							(mid -0.249642 0.249642)
							(end -0.1778 0.2794)
						)
						(arc
							(start 0.1778 0.2794)
							(mid 0.249642 0.249642)
							(end 0.2794 0.1778)
						)
						(arc
							(start 0.2794 -0.1778)
							(mid 0.249642 -0.249642)
							(end 0.1778 -0.2794)
						)
					)
					(width 0)
					(fill yes)
				)
			)
		)
		(pad "2" smd custom
			(at 0 0.4445 180)
			(size 0.1397 0.1397)
			(layers "F.Cu" "F.Mask" "F.Paste")
			(net "SW_PWR_R_HDD21")
			(options
				(clearance outline)
				(anchor circle)
			)
			(primitives
				(gr_poly
					(pts
						(arc
							(start -0.1778 -0.2794)
							(mid -0.249642 -0.249642)
							(end -0.2794 -0.1778)
						)
						(arc
							(start -0.2794 0.1778)
							(mid -0.249642 0.249642)
							(end -0.1778 0.2794)
						)
						(arc
							(start 0.1778 0.2794)
							(mid 0.249642 0.249642)
							(end 0.2794 0.1778)
						)
						(arc
							(start 0.2794 -0.1778)
							(mid 0.249642 -0.249642)
							(end 0.1778 -0.2794)
						)
					)
					(width 0)
					(fill yes)
				)
			)
		)
	)
	(footprint ""
		(layer "F.Cu")
		(at 412.8516 -261.3406)
		(property "Reference" "R305"
			(at 0 0 0)
			(layer "F.SilkS")
			(hide yes)
			(effects
				(font
					(size 1.27 1.27)
				)
			)
		)
		(property "Value" "220R3F-1-GP"
			(at -0.0254 -2.5146 0)
			(unlocked yes)
			(layer "F.Fab")
			(hide yes)
			(effects
				(font
					(size 1.016 1.016)
					(thickness 0.1524)
				)
			)
		)
		(property "Device Type" "R603H22"
			(at -0.0254 -4.0386 0)
			(unlocked yes)
			(layer "F.Fab")
			(hide yes)
			(effects
				(font
					(size 1.016 1.016)
					(thickness 0.1524)
				)
			)
		)
		(duplicate_pad_numbers_are_jumpers no)
		(fp_line
			(start -0.4826 0)
			(end -0.2032 0)
			(stroke
				(width 0.2032)
				(type default)
			)
			(layer "F.SilkS")
		)
		(fp_line
			(start 0.2032 0)
			(end 0.4826 0)
			(stroke
				(width 0.2032)
				(type default)
			)
			(layer "F.SilkS")
		)
		(fp_rect
			(start -0.5842 1.3335)
			(end 0.5842 -1.3335)
			(stroke
				(width 0)
				(type default)
			)
			(fill no)
			(layer "F.CrtYd")
		)
		(fp_rect
			(start -0.5842 1.3335)
			(end 0.5842 -1.3335)
			(stroke
				(width 0)
				(type default)
			)
			(fill no)
			(layer "F.Fab")
		)
		(pad "1" smd custom
			(at 0 -0.762)
			(size 0.2159 0.2159)
			(layers "F.Cu" "F.Mask" "F.Paste")
			(net "HDD_PRSNT_9")
			(options
				(clearance outline)
				(anchor circle)
			)
			(primitives
				(gr_poly
					(pts
						(arc
							(start -0.3302 -0.4318)
							(mid -0.402042 -0.402042)
							(end -0.4318 -0.3302)
						)
						(arc
							(start -0.4318 0.3302)
							(mid -0.402042 0.402042)
							(end -0.3302 0.4318)
						)
						(arc
							(start 0.3302 0.4318)
							(mid 0.402042 0.402042)
							(end 0.4318 0.3302)
						)
						(arc
							(start 0.4318 -0.3302)
							(mid 0.402042 -0.402042)
							(end 0.3302 -0.4318)
						)
					)
					(width 0)
					(fill yes)
				)
			)
		)
		(pad "2" smd custom
			(at 0 0.762)
			(size 0.2159 0.2159)
			(layers "F.Cu" "F.Mask" "F.Paste")
			(net "DRIVE_B_9_INS")
			(options
				(clearance outline)
				(anchor circle)
			)
			(primitives
				(gr_poly
					(pts
						(arc
							(start -0.3302 -0.4318)
							(mid -0.402042 -0.402042)
							(end -0.4318 -0.3302)
						)
						(arc
							(start -0.4318 0.3302)
							(mid -0.402042 0.402042)
							(end -0.3302 0.4318)
						)
						(arc
							(start 0.3302 0.4318)
							(mid 0.402042 0.402042)
							(end 0.4318 0.3302)
						)
						(arc
							(start 0.4318 -0.3302)
							(mid 0.402042 -0.402042)
							(end 0.3302 -0.4318)
						)
					)
					(width 0)
					(fill yes)
				)
			)
		)
	)
	(footprint ""
		(layer "F.Cu")
		(at 176.149 -246.634)
		(property "Reference" "R251"
			(at 0 0 0)
			(layer "F.SilkS")
			(hide yes)
			(effects
				(font
					(size 1.27 1.27)
				)
			)
		)
		(property "Value" "0R2J-2-GP"
			(at 0.064008 -3.993896 0)
			(unlocked yes)
			(layer "F.Fab")
			(hide yes)
			(effects
				(font
					(size 1.016 1.016)
					(thickness 0.1524)
				)
			)
		)
		(property "Device Type" "R402H16"
			(at 0.064008 -5.517896 0)
			(unlocked yes)
			(layer "F.Fab")
			(hide yes)
			(effects
				(font
					(size 1.016 1.016)
					(thickness 0.1524)
				)
			)
		)
		(duplicate_pad_numbers_are_jumpers no)
		(fp_line
			(start -0.508 -0.9398)
			(end -0.508 0.9398)
			(stroke
				(width 0.1524)
				(type default)
			)
			(layer "F.SilkS")
		)
		(fp_line
			(start 0.508 -0.9398)
			(end -0.508 -0.9398)
			(stroke
				(width 0.1524)
				(type default)
			)
			(layer "F.SilkS")
		)
		(fp_rect
			(start -0.508 0.9398)
			(end 0.508 -0.9398)
			(stroke
				(width 0)
				(type default)
			)
			(fill no)
			(layer "F.CrtYd")
		)
		(fp_rect
			(start -0.508 0.9398)
			(end 0.508 -0.9398)
			(stroke
				(width 0)
				(type default)
			)
			(fill no)
			(layer "F.Fab")
		)
		(pad "1" smd custom
			(at 0 -0.4445)
			(size 0.1397 0.1397)
			(layers "F.Cu" "F.Mask" "F.Paste")
			(net "SW_HDD_G5")
			(options
				(clearance outline)
				(anchor circle)
			)
			(primitives
				(gr_poly
					(pts
						(arc
							(start -0.1778 -0.2794)
							(mid -0.249642 -0.249642)
							(end -0.2794 -0.1778)
						)
						(arc
							(start -0.2794 0.1778)
							(mid -0.249642 0.249642)
							(end -0.1778 0.2794)
						)
						(arc
							(start 0.1778 0.2794)
							(mid 0.249642 0.249642)
							(end 0.2794 0.1778)
						)
						(arc
							(start 0.2794 -0.1778)
							(mid 0.249642 -0.249642)
							(end 0.1778 -0.2794)
						)
					)
					(width 0)
					(fill yes)
				)
			)
		)
		(pad "2" smd custom
			(at 0 0.4445)
			(size 0.1397 0.1397)
			(layers "F.Cu" "F.Mask" "F.Paste")
			(net "SW_HDD_R5")
			(options
				(clearance outline)
				(anchor circle)
			)
			(primitives
				(gr_poly
					(pts
						(arc
							(start -0.1778 -0.2794)
							(mid -0.249642 -0.249642)
							(end -0.2794 -0.1778)
						)
						(arc
							(start -0.2794 0.1778)
							(mid -0.249642 0.249642)
							(end -0.1778 0.2794)
						)
						(arc
							(start 0.1778 0.2794)
							(mid 0.249642 0.249642)
							(end 0.2794 0.1778)
						)
						(arc
							(start 0.2794 -0.1778)
							(mid 0.249642 -0.249642)
							(end 0.1778 -0.2794)
						)
					)
					(width 0)
					(fill yes)
				)
			)
		)
	)
	(footprint ""
		(layer "F.Cu")
		(at 160.485582 -14.990826 90)
		(property "Reference" "VIA57"
			(at 0 0 90)
			(layer "F.SilkS")
			(hide yes)
			(effects
				(font
					(size 1.27 1.27)
				)
			)
		)
		(property "Value" "100OHM-8L-2D36MM-L18-GP"
			(at 3.8989 0.5715 90)
			(unlocked yes)
			(layer "F.Fab")
			(hide yes)
			(effects
				(font
					(size 1.016 1.016)
					(thickness 0.1524)
				)
			)
		)
		(property "Device Type" "VIA-PCIE-4P-414097"
			(at 3.8989 -0.9525 90)
			(unlocked yes)
			(layer "F.Fab")
			(hide yes)
			(effects
				(font
					(size 1.016 1.016)
					(thickness 0.1524)
				)
			)
		)
		(duplicate_pad_numbers_are_jumpers no)
		(fp_rect
			(start -2.0701 0.4826)
			(end 2.0701 -0.4826)
			(stroke
				(width 0)
				(type default)
			)
			(fill no)
			(layer "F.CrtYd")
		)
		(fp_rect
			(start -2.0701 0.4826)
			(end 2.0701 -0.4826)
			(stroke
				(width 0)
				(type default)
			)
			(fill no)
			(layer "F.Fab")
		)
		(pad "1" thru_hole circle
			(at -1.5875 0 90)
			(size 0.508 0.508)
			(drill 0.254)
			(layers "*.Cu" "*.Mask")
			(remove_unused_layers no)
			(net "GND")
			(clearance 0.2286)
			(thermal_gap 0.2286)
		)
		(pad "2" thru_hole circle
			(at -0.5715 0 90)
			(size 0.508 0.508)
			(drill 0.254)
			(layers "*.Cu" "*.Mask")
			(remove_unused_layers no)
			(net "PHY_SCC_B_TO_DRV_B_28_DP")
			(clearance 0.2286)
			(thermal_gap 0.2286)
		)
		(pad "3" thru_hole circle
			(at 0.5715 0 90)
			(size 0.508 0.508)
			(drill 0.254)
			(layers "*.Cu" "*.Mask")
			(remove_unused_layers no)
			(net "PHY_SCC_B_TO_DRV_B_28_DN")
			(clearance 0.2286)
			(thermal_gap 0.2286)
		)
		(pad "4" thru_hole circle
			(at 1.5875 0 90)
			(size 0.508 0.508)
			(drill 0.254)
			(layers "*.Cu" "*.Mask")
			(remove_unused_layers no)
			(net "GND")
			(clearance 0.2286)
			(thermal_gap 0.2286)
		)
	)
	(footprint ""
		(layer "F.Cu")
		(at 140.97 -150.622 -90)
		(property "Reference" "C241"
			(at 0 0 270)
			(layer "F.SilkS")
			(hide yes)
			(effects
				(font
					(size 1.27 1.27)
				)
			)
		)
		(property "Value" "SC4D7U25V5KX-1-GP"
			(at -0.0762 -6.1214 270)
			(unlocked yes)
			(layer "F.Fab")
			(hide yes)
			(effects
				(font
					(size 1.016 1.016)
					(thickness 0.1524)
				)
			)
		)
		(property "Device Type" "C805H58"
			(at -0.0762 -8.1534 270)
			(unlocked yes)
			(layer "F.Fab")
			(hide yes)
			(effects
				(font
					(size 1.016 1.016)
					(thickness 0.1524)
				)
			)
		)
		(duplicate_pad_numbers_are_jumpers no)
		(fp_line
			(start 0.635 0)
			(end -0.635 0)
			(stroke
				(width 0.508)
				(type default)
			)
			(layer "F.SilkS")
		)
		(fp_rect
			(start -0.9652 1.778)
			(end 0.9652 -1.778)
			(stroke
				(width 0)
				(type default)
			)
			(fill no)
			(layer "F.CrtYd")
		)
		(fp_poly
			(pts
				(xy -0.9652 -1.778) (xy 0.9652 -1.778) (xy 0.9652 1.778) (xy -0.9652 1.778)
			)
			(stroke
				(width 0)
				(type default)
			)
			(fill no)
			(layer "F.Fab")
		)
		(pad "1" smd rect
			(at 0 -0.9652 270)
			(size 1.397 1.143)
			(layers "F.Cu" "F.Mask" "F.Paste")
			(net "P12V_HDD16")
		)
		(pad "2" smd rect
			(at 0 0.9652 270)
			(size 1.397 1.143)
			(layers "F.Cu" "F.Mask" "F.Paste")
			(net "GND")
		)
	)
	(footprint ""
		(layer "F.Cu")
		(at 79.883 -139.065 -90)
		(property "Reference" "C220"
			(at 0 0 270)
			(layer "F.SilkS")
			(hide yes)
			(effects
				(font
					(size 1.27 1.27)
				)
			)
		)
		(property "Value" "SCD033U25V2KX-GP"
			(at 1.1811 -2.7051 270)
			(unlocked yes)
			(layer "F.Fab")
			(hide yes)
			(effects
				(font
					(size 1.016 1.016)
					(thickness 0.1524)
				)
			)
		)
		(property "Device Type" "C402H22"
			(at 1.1811 -4.2291 270)
			(unlocked yes)
			(layer "F.Fab")
			(hide yes)
			(effects
				(font
					(size 1.016 1.016)
					(thickness 0.1524)
				)
			)
		)
		(duplicate_pad_numbers_are_jumpers no)
		(fp_rect
			(start -0.4318 0.9525)
			(end 0.4318 -0.9525)
			(stroke
				(width 0)
				(type default)
			)
			(fill no)
			(layer "F.CrtYd")
		)
		(fp_rect
			(start -0.4318 0.9525)
			(end 0.4318 -0.9525)
			(stroke
				(width 0)
				(type default)
			)
			(fill no)
			(layer "F.Fab")
		)
		(pad "1" smd custom
			(at 0 -0.4445 270)
			(size 0.1524 0.1524)
			(layers "F.Cu" "F.Mask" "F.Paste")
			(net "SW_HDD_P14")
			(options
				(clearance outline)
				(anchor circle)
			)
			(primitives
				(gr_poly
					(pts
						(arc
							(start 0.3048 -0.2032)
							(mid 0.275042 -0.275042)
							(end 0.2032 -0.3048)
						)
						(arc
							(start -0.2032 -0.3048)
							(mid -0.275042 -0.275042)
							(end -0.3048 -0.2032)
						)
						(arc
							(start -0.3048 0.2032)
							(mid -0.275042 0.275042)
							(end -0.2032 0.3048)
						)
						(arc
							(start 0.2032 0.3048)
							(mid 0.275042 0.275042)
							(end 0.3048 0.2032)
						)
					)
					(width 0)
					(fill yes)
				)
			)
		)
		(pad "2" smd custom
			(at 0 0.4445 270)
			(size 0.1524 0.1524)
			(layers "F.Cu" "F.Mask" "F.Paste")
			(net "GND")
			(options
				(clearance outline)
				(anchor circle)
			)
			(primitives
				(gr_poly
					(pts
						(arc
							(start 0.3048 -0.2032)
							(mid 0.275042 -0.275042)
							(end 0.2032 -0.3048)
						)
						(arc
							(start -0.2032 -0.3048)
							(mid -0.275042 -0.275042)
							(end -0.3048 -0.2032)
						)
						(arc
							(start -0.3048 0.2032)
							(mid -0.275042 0.275042)
							(end -0.2032 0.3048)
						)
						(arc
							(start 0.2032 0.3048)
							(mid 0.275042 0.275042)
							(end 0.3048 0.2032)
						)
					)
					(width 0)
					(fill yes)
				)
			)
		)
	)
	(footprint ""
		(layer "F.Cu")
		(at 236.728 -222.377 90)
		(property "Reference" "R510"
			(at 0 0 90)
			(layer "F.SilkS")
			(hide yes)
			(effects
				(font
					(size 1.27 1.27)
				)
			)
		)
		(property "Value" "100KR2F-L1-GP"
			(at 0.064008 -3.993896 90)
			(unlocked yes)
			(layer "F.Fab")
			(hide yes)
			(effects
				(font
					(size 1.016 1.016)
					(thickness 0.1524)
				)
			)
		)
		(property "Device Type" "R402H16"
			(at 0.064008 -5.517896 90)
			(unlocked yes)
			(layer "F.Fab")
			(hide yes)
			(effects
				(font
					(size 1.016 1.016)
					(thickness 0.1524)
				)
			)
		)
		(duplicate_pad_numbers_are_jumpers no)
		(fp_line
			(start 0.508 -0.9398)
			(end -0.508 -0.9398)
			(stroke
				(width 0.1524)
				(type default)
			)
			(layer "F.SilkS")
		)
		(fp_line
			(start -0.508 -0.9398)
			(end -0.508 0.9398)
			(stroke
				(width 0.1524)
				(type default)
			)
			(layer "F.SilkS")
		)
		(fp_rect
			(start -0.508 0.9398)
			(end 0.508 -0.9398)
			(stroke
				(width 0)
				(type default)
			)
			(fill no)
			(layer "F.CrtYd")
		)
		(fp_rect
			(start -0.508 0.9398)
			(end 0.508 -0.9398)
			(stroke
				(width 0)
				(type default)
			)
			(fill no)
			(layer "F.Fab")
		)
		(pad "1" smd custom
			(at 0 -0.4445 90)
			(size 0.1397 0.1397)
			(layers "F.Cu" "F.Mask" "F.Paste")
			(net "GPIO_VCC_U8")
			(options
				(clearance outline)
				(anchor circle)
			)
			(primitives
				(gr_poly
					(pts
						(arc
							(start -0.1778 -0.2794)
							(mid -0.249642 -0.249642)
							(end -0.2794 -0.1778)
						)
						(arc
							(start -0.2794 0.1778)
							(mid -0.249642 0.249642)
							(end -0.1778 0.2794)
						)
						(arc
							(start 0.1778 0.2794)
							(mid 0.249642 0.249642)
							(end 0.2794 0.1778)
						)
						(arc
							(start 0.2794 -0.1778)
							(mid 0.249642 -0.249642)
							(end 0.1778 -0.2794)
						)
					)
					(width 0)
					(fill yes)
				)
			)
		)
		(pad "2" smd custom
			(at 0 0.4445 90)
			(size 0.1397 0.1397)
			(layers "F.Cu" "F.Mask" "F.Paste")
			(net "GND")
			(options
				(clearance outline)
				(anchor circle)
			)
			(primitives
				(gr_poly
					(pts
						(arc
							(start -0.1778 -0.2794)
							(mid -0.249642 -0.249642)
							(end -0.2794 -0.1778)
						)
						(arc
							(start -0.2794 0.1778)
							(mid -0.249642 0.249642)
							(end -0.1778 0.2794)
						)
						(arc
							(start 0.1778 0.2794)
							(mid 0.249642 0.249642)
							(end 0.2794 0.1778)
						)
						(arc
							(start 0.2794 -0.1778)
							(mid 0.249642 -0.249642)
							(end 0.1778 -0.2794)
						)
					)
					(width 0)
					(fill yes)
				)
			)
		)
	)
	(footprint ""
		(layer "F.Cu")
		(at 95.608902 -133.75005 -90)
		(property "Reference" "VIA30"
			(at 0 0 270)
			(layer "F.SilkS")
			(hide yes)
			(effects
				(font
					(size 1.27 1.27)
				)
			)
		)
		(property "Value" "100OHM-8L-2D36MM-L16-GP"
			(at -3.4036 -0.4572 270)
			(unlocked yes)
			(layer "F.Fab")
			(hide yes)
			(effects
				(font
					(size 1.016 1.016)
					(thickness 0.1524)
				)
			)
		)
		(property "Device Type" "VIA-PCIE-4P-427097"
			(at -3.4036 -1.9812 270)
			(unlocked yes)
			(layer "F.Fab")
			(hide yes)
			(effects
				(font
					(size 1.016 1.016)
					(thickness 0.1524)
				)
			)
		)
		(duplicate_pad_numbers_are_jumpers no)
		(fp_rect
			(start -2.1336 0.4826)
			(end 2.1336 -0.4826)
			(stroke
				(width 0)
				(type default)
			)
			(fill no)
			(layer "F.CrtYd")
		)
		(fp_rect
			(start -2.1336 0.4826)
			(end 2.1336 -0.4826)
			(stroke
				(width 0)
				(type default)
			)
			(fill no)
			(layer "F.Fab")
		)
		(pad "1" thru_hole circle
			(at -1.651 0 270)
			(size 0.508 0.508)
			(drill 0.254)
			(layers "*.Cu" "*.Mask")
			(remove_unused_layers no)
			(net "GND")
			(clearance 0.2286)
			(thermal_gap 0.2286)
		)
		(pad "2" thru_hole circle
			(at -0.635 0 270)
			(size 0.508 0.508)
			(drill 0.254)
			(layers "*.Cu" "*.Mask")
			(remove_unused_layers no)
			(net "PHY_DRV_B_TO_SCC_B_14_DP")
			(clearance 0.2286)
			(thermal_gap 0.2286)
		)
		(pad "3" thru_hole circle
			(at 0.635 0 270)
			(size 0.508 0.508)
			(drill 0.254)
			(layers "*.Cu" "*.Mask")
			(remove_unused_layers no)
			(net "PHY_DRV_B_TO_SCC_B_14_DN")
			(clearance 0.2286)
			(thermal_gap 0.2286)
		)
		(pad "4" thru_hole circle
			(at 1.651 0 270)
			(size 0.508 0.508)
			(drill 0.254)
			(layers "*.Cu" "*.Mask")
			(remove_unused_layers no)
			(net "GND")
			(clearance 0.2286)
			(thermal_gap 0.2286)
		)
	)
	(footprint ""
		(layer "F.Cu")
		(at 109.474 -145.796)
		(property "Reference" "Q66"
			(at 0 0 0)
			(layer "F.SilkS")
			(hide yes)
			(effects
				(font
					(size 1.27 1.27)
				)
			)
		)
		(property "Value" "AO4407AL-GP"
			(at -3.707384 -1.5367 0)
			(unlocked yes)
			(layer "F.Fab")
			(hide yes)
			(effects
				(font
					(size 1.016 1.016)
					(thickness 0.1524)
				)
			)
		)
		(property "Device Type" "SOIC8H69"
			(at -3.707384 -3.0607 0)
			(unlocked yes)
			(layer "F.Fab")
			(hide yes)
			(effects
				(font
					(size 1.016 1.016)
					(thickness 0.1524)
				)
			)
		)
		(duplicate_pad_numbers_are_jumpers no)
		(fp_line
			(start -2.7432 -1.4224)
			(end -2.7432 1.4224)
			(stroke
				(width 0.1524)
				(type default)
			)
			(layer "F.SilkS")
		)
		(fp_line
			(start -2.7432 1.4224)
			(end -2.6416 1.4224)
			(stroke
				(width 0.1524)
				(type default)
			)
			(layer "F.SilkS")
		)
		(fp_line
			(start -2.7432 1.4224)
			(end 2.1336 1.4224)
			(stroke
				(width 0.1524)
				(type default)
			)
			(layer "F.SilkS")
		)
		(fp_line
			(start -2.7178 -0.508)
			(end -2.1844 -0.0508)
			(stroke
				(width 0.1524)
				(type default)
			)
			(layer "F.SilkS")
		)
		(fp_line
			(start -2.6289 3.4417)
			(end -2.6289 1.4732)
			(stroke
				(width 0.381)
				(type default)
			)
			(layer "F.SilkS")
		)
		(fp_line
			(start -2.1844 -0.0508)
			(end -2.7178 0.508)
			(stroke
				(width 0.1524)
				(type default)
			)
			(layer "F.SilkS")
		)
		(fp_line
			(start 2.1336 -1.4224)
			(end -2.7432 -1.4224)
			(stroke
				(width 0.1524)
				(type default)
			)
			(layer "F.SilkS")
		)
		(fp_line
			(start 2.1336 1.4224)
			(end 2.1336 -1.4224)
			(stroke
				(width 0.1524)
				(type default)
			)
			(layer "F.SilkS")
		)
		(fp_poly
			(pts
				(xy -2.2098 -1.4224) (xy -2.2098 1.4224) (xy 2.2098 1.4224) (xy 2.2098 -1.4224)
			)
			(stroke
				(width 0)
				(type default)
			)
			(fill yes)
			(layer "F.SilkS")
		)
		(fp_rect
			(start -2.450084 2.999994)
			(end 2.450084 -2.999994)
			(stroke
				(width 0)
				(type default)
			)
			(fill no)
			(layer "F.CrtYd")
		)
		(fp_poly
			(pts
				(xy -2.8194 3.6322) (xy -2.8194 -3.6322) (xy 2.8194 -3.6322) (xy 2.8194 1.18364) (xy 2.450084 1.18364)
				(xy 2.450084 -2.999994) (xy -2.450084 -2.999994) (xy -2.450084 2.999994) (xy 2.450084 2.999994)
				(xy 2.450084 1.18618) (xy 2.8194 1.18618) (xy 2.8194 3.6322)
			)
			(stroke
				(width 0)
				(type default)
			)
			(fill no)
			(layer "F.CrtYd")
		)
		(fp_rect
			(start -2.8194 3.6322)
			(end 2.8194 -3.6322)
			(stroke
				(width 0)
				(type default)
			)
			(fill no)
			(layer "F.Fab")
		)
		(pad "1" smd rect
			(at -1.905 2.54)
			(size 0.635 1.651)
			(layers "F.Cu" "F.Mask" "F.Paste")
			(net "P12V_B")
		)
		(pad "2" smd rect
			(at -0.635 2.54)
			(size 0.635 1.651)
			(layers "F.Cu" "F.Mask" "F.Paste")
			(net "P12V_B")
		)
		(pad "3" smd rect
			(at 0.635 2.54)
			(size 0.635 1.651)
			(layers "F.Cu" "F.Mask" "F.Paste")
			(net "P12V_B")
		)
		(pad "4" smd rect
			(at 1.905 2.54)
			(size 0.635 1.651)
			(layers "F.Cu" "F.Mask" "F.Paste")
			(net "SW_HDD_N15")
		)
		(pad "5" smd rect
			(at 1.905 -2.54)
			(size 0.635 1.651)
			(layers "F.Cu" "F.Mask" "F.Paste")
			(net "P12V_HDD15")
		)
		(pad "6" smd rect
			(at 0.635 -2.54)
			(size 0.635 1.651)
			(layers "F.Cu" "F.Mask" "F.Paste")
			(net "P12V_HDD15")
		)
		(pad "7" smd rect
			(at -0.635 -2.54)
			(size 0.635 1.651)
			(layers "F.Cu" "F.Mask" "F.Paste")
			(net "P12V_HDD15")
		)
		(pad "8" smd rect
			(at -1.905 -2.54)
			(size 0.635 1.651)
			(layers "F.Cu" "F.Mask" "F.Paste")
			(net "P12V_HDD15")
		)
	)
	(footprint ""
		(layer "F.Cu")
		(at 18.415 -131.572)
		(property "Reference" "R363"
			(at 0 0 0)
			(layer "F.SilkS")
			(hide yes)
			(effects
				(font
					(size 1.27 1.27)
				)
			)
		)
		(property "Value" "0R2J-2-GP"
			(at 0.064008 -3.993896 0)
			(unlocked yes)
			(layer "F.Fab")
			(hide yes)
			(effects
				(font
					(size 1.016 1.016)
					(thickness 0.1524)
				)
			)
		)
		(property "Device Type" "R402H16"
			(at 0.064008 -5.517896 0)
			(unlocked yes)
			(layer "F.Fab")
			(hide yes)
			(effects
				(font
					(size 1.016 1.016)
					(thickness 0.1524)
				)
			)
		)
		(duplicate_pad_numbers_are_jumpers no)
		(fp_line
			(start -0.508 -0.9398)
			(end -0.508 0.9398)
			(stroke
				(width 0.1524)
				(type default)
			)
			(layer "F.SilkS")
		)
		(fp_line
			(start 0.508 -0.9398)
			(end -0.508 -0.9398)
			(stroke
				(width 0.1524)
				(type default)
			)
			(layer "F.SilkS")
		)
		(fp_rect
			(start -0.508 0.9398)
			(end 0.508 -0.9398)
			(stroke
				(width 0)
				(type default)
			)
			(fill no)
			(layer "F.CrtYd")
		)
		(fp_rect
			(start -0.508 0.9398)
			(end 0.508 -0.9398)
			(stroke
				(width 0)
				(type default)
			)
			(fill no)
			(layer "F.Fab")
		)
		(pad "1" smd custom
			(at 0 -0.4445)
			(size 0.1397 0.1397)
			(layers "F.Cu" "F.Mask" "F.Paste")
			(net "SW_HDD_G12")
			(options
				(clearance outline)
				(anchor circle)
			)
			(primitives
				(gr_poly
					(pts
						(arc
							(start -0.1778 -0.2794)
							(mid -0.249642 -0.249642)
							(end -0.2794 -0.1778)
						)
						(arc
							(start -0.2794 0.1778)
							(mid -0.249642 0.249642)
							(end -0.1778 0.2794)
						)
						(arc
							(start 0.1778 0.2794)
							(mid 0.249642 0.249642)
							(end 0.2794 0.1778)
						)
						(arc
							(start 0.2794 -0.1778)
							(mid 0.249642 -0.249642)
							(end 0.1778 -0.2794)
						)
					)
					(width 0)
					(fill yes)
				)
			)
		)
		(pad "2" smd custom
			(at 0 0.4445)
			(size 0.1397 0.1397)
			(layers "F.Cu" "F.Mask" "F.Paste")
			(net "SW_HDD_R12")
			(options
				(clearance outline)
				(anchor circle)
			)
			(primitives
				(gr_poly
					(pts
						(arc
							(start -0.1778 -0.2794)
							(mid -0.249642 -0.249642)
							(end -0.2794 -0.1778)
						)
						(arc
							(start -0.2794 0.1778)
							(mid -0.249642 0.249642)
							(end -0.1778 0.2794)
						)
						(arc
							(start 0.1778 0.2794)
							(mid 0.249642 0.249642)
							(end 0.2794 0.1778)
						)
						(arc
							(start 0.2794 -0.1778)
							(mid 0.249642 -0.249642)
							(end 0.1778 -0.2794)
						)
					)
					(width 0)
					(fill yes)
				)
			)
		)
	)
	(footprint ""
		(layer "F.Cu")
		(at 331.47 -160.02 180)
		(property "Reference" "C268"
			(at 0 0 180)
			(layer "F.SilkS")
			(hide yes)
			(effects
				(font
					(size 1.27 1.27)
				)
			)
		)
		(property "Value" "SC4D7U25V5KX-1-GP"
			(at -0.0762 -6.1214 180)
			(unlocked yes)
			(layer "F.Fab")
			(hide yes)
			(effects
				(font
					(size 1.016 1.016)
					(thickness 0.1524)
				)
			)
		)
		(property "Device Type" "C805H58"
			(at -0.0762 -8.1534 180)
			(unlocked yes)
			(layer "F.Fab")
			(hide yes)
			(effects
				(font
					(size 1.016 1.016)
					(thickness 0.1524)
				)
			)
		)
		(duplicate_pad_numbers_are_jumpers no)
		(fp_line
			(start 0.635 0)
			(end -0.635 0)
			(stroke
				(width 0.508)
				(type default)
			)
			(layer "F.SilkS")
		)
		(fp_rect
			(start -0.9652 1.778)
			(end 0.9652 -1.778)
			(stroke
				(width 0)
				(type default)
			)
			(fill no)
			(layer "F.CrtYd")
		)
		(fp_poly
			(pts
				(xy -0.9652 -1.778) (xy 0.9652 -1.778) (xy 0.9652 1.778) (xy -0.9652 1.778)
			)
			(stroke
				(width 0)
				(type default)
			)
			(fill no)
			(layer "F.Fab")
		)
		(pad "1" smd rect
			(at 0 -0.9652 180)
			(size 1.397 1.143)
			(layers "F.Cu" "F.Mask" "F.Paste")
			(net "P12V_HDD18")
		)
		(pad "2" smd rect
			(at 0 0.9652 180)
			(size 1.397 1.143)
			(layers "F.Cu" "F.Mask" "F.Paste")
			(net "GND")
		)
	)
	(footprint ""
		(layer "F.Cu")
		(at 243.519452 -362.284772)
		(property "Reference" "C565"
			(at 0 0 0)
			(layer "F.SilkS")
			(hide yes)
			(effects
				(font
					(size 1.27 1.27)
				)
			)
		)
		(property "Value" "SC1U16V3KX-5GP"
			(at 0 -2.8194 0)
			(unlocked yes)
			(layer "F.Fab")
			(hide yes)
			(effects
				(font
					(size 1.016 1.016)
					(thickness 0.1524)
				)
			)
		)
		(property "Device Type" "C603H36"
			(at 0 -4.3434 0)
			(unlocked yes)
			(layer "F.Fab")
			(hide yes)
			(effects
				(font
					(size 1.016 1.016)
					(thickness 0.1524)
				)
			)
		)
		(duplicate_pad_numbers_are_jumpers no)
		(fp_line
			(start 0.508 0)
			(end -0.508 0)
			(stroke
				(width 0.2032)
				(type default)
			)
			(layer "F.SilkS")
		)
		(fp_rect
			(start -0.5842 1.3335)
			(end 0.5842 -1.3335)
			(stroke
				(width 0)
				(type default)
			)
			(fill no)
			(layer "F.CrtYd")
		)
		(fp_rect
			(start -0.5842 1.3335)
			(end 0.5842 -1.3335)
			(stroke
				(width 0)
				(type default)
			)
			(fill no)
			(layer "F.Fab")
		)
		(pad "1" smd custom
			(at 0 -0.762)
			(size 0.2159 0.2159)
			(layers "F.Cu" "F.Mask" "F.Paste")
			(net "MB3_CM_UV_R")
			(options
				(clearance outline)
				(anchor circle)
			)
			(primitives
				(gr_poly
					(pts
						(arc
							(start -0.3302 -0.4318)
							(mid -0.402042 -0.402042)
							(end -0.4318 -0.3302)
						)
						(arc
							(start -0.4318 0.3302)
							(mid -0.402042 0.402042)
							(end -0.3302 0.4318)
						)
						(arc
							(start 0.3302 0.4318)
							(mid 0.402042 0.402042)
							(end 0.4318 0.3302)
						)
						(arc
							(start 0.4318 -0.3302)
							(mid 0.402042 -0.402042)
							(end 0.3302 -0.4318)
						)
					)
					(width 0)
					(fill yes)
				)
			)
		)
		(pad "2" smd custom
			(at 0 0.762)
			(size 0.2159 0.2159)
			(layers "F.Cu" "F.Mask" "F.Paste")
			(net "AGND_CURRENT_DPB")
			(options
				(clearance outline)
				(anchor circle)
			)
			(primitives
				(gr_poly
					(pts
						(arc
							(start -0.3302 -0.4318)
							(mid -0.402042 -0.402042)
							(end -0.4318 -0.3302)
						)
						(arc
							(start -0.4318 0.3302)
							(mid -0.402042 0.402042)
							(end -0.3302 0.4318)
						)
						(arc
							(start 0.3302 0.4318)
							(mid 0.402042 0.402042)
							(end 0.4318 0.3302)
						)
						(arc
							(start 0.4318 -0.3302)
							(mid 0.402042 -0.402042)
							(end 0.3302 -0.4318)
						)
					)
					(width 0)
					(fill yes)
				)
			)
		)
	)
	(footprint ""
		(layer "F.Cu")
		(at 426.085 -274.955 180)
		(property "Reference" "C151"
			(at 0 0 180)
			(layer "F.SilkS")
			(hide yes)
			(effects
				(font
					(size 1.27 1.27)
				)
			)
		)
		(property "Value" "SC4D7U25V5KX-1-GP"
			(at -0.0762 -6.1214 180)
			(unlocked yes)
			(layer "F.Fab")
			(hide yes)
			(effects
				(font
					(size 1.016 1.016)
					(thickness 0.1524)
				)
			)
		)
		(property "Device Type" "C805H58"
			(at -0.0762 -8.1534 180)
			(unlocked yes)
			(layer "F.Fab")
			(hide yes)
			(effects
				(font
					(size 1.016 1.016)
					(thickness 0.1524)
				)
			)
		)
		(duplicate_pad_numbers_are_jumpers no)
		(fp_line
			(start 0.635 0)
			(end -0.635 0)
			(stroke
				(width 0.508)
				(type default)
			)
			(layer "F.SilkS")
		)
		(fp_rect
			(start -0.9652 1.778)
			(end 0.9652 -1.778)
			(stroke
				(width 0)
				(type default)
			)
			(fill no)
			(layer "F.CrtYd")
		)
		(fp_poly
			(pts
				(xy -0.9652 -1.778) (xy 0.9652 -1.778) (xy 0.9652 1.778) (xy -0.9652 1.778)
			)
			(stroke
				(width 0)
				(type default)
			)
			(fill no)
			(layer "F.Fab")
		)
		(pad "1" smd rect
			(at 0 -0.9652 180)
			(size 1.397 1.143)
			(layers "F.Cu" "F.Mask" "F.Paste")
			(net "P12V_HDD9")
		)
		(pad "2" smd rect
			(at 0 0.9652 180)
			(size 1.397 1.143)
			(layers "F.Cu" "F.Mask" "F.Paste")
			(net "GND")
		)
	)
	(footprint ""
		(layer "F.Cu")
		(at 402.843746 -99.860354 90)
		(property "Reference" "Q262"
			(at 0 0 90)
			(layer "F.SilkS")
			(hide yes)
			(effects
				(font
					(size 1.27 1.27)
				)
			)
		)
		(property "Value" "SSM3K324R-GP"
			(at 0.127 -8.9662 90)
			(unlocked yes)
			(layer "F.Fab")
			(hide yes)
			(effects
				(font
					(size 1.016 1.016)
					(thickness 0.1524)
				)
			)
		)
		(property "Device Type" "SOT23DGS2D4H35"
			(at 0.127 -10.4902 90)
			(unlocked yes)
			(layer "F.Fab")
			(hide yes)
			(effects
				(font
					(size 1.016 1.016)
					(thickness 0.1524)
				)
			)
		)
		(duplicate_pad_numbers_are_jumpers no)
		(fp_line
			(start 1.651 -1.778)
			(end -1.651 -1.778)
			(stroke
				(width 0.1524)
				(type default)
			)
			(layer "F.SilkS")
		)
		(fp_line
			(start -1.651 -1.778)
			(end -1.651 1.778)
			(stroke
				(width 0.1524)
				(type default)
			)
			(layer "F.SilkS")
		)
		(fp_line
			(start 1.651 1.778)
			(end 1.651 -1.778)
			(stroke
				(width 0.1524)
				(type default)
			)
			(layer "F.SilkS")
		)
		(fp_line
			(start -1.651 1.778)
			(end 1.651 1.778)
			(stroke
				(width 0.1524)
				(type default)
			)
			(layer "F.SilkS")
		)
		(fp_poly
			(pts
				(xy -1.778 1.8796) (xy -1.778 -1.8796) (xy 1.778 -1.8796) (xy 1.778 1.8796)
			)
			(stroke
				(width 0)
				(type default)
			)
			(fill no)
			(layer "F.CrtYd")
		)
		(fp_poly
			(pts
				(xy -1.778 1.8796) (xy -1.778 -1.8796) (xy 1.778 -1.8796) (xy 1.778 1.8796)
			)
			(stroke
				(width 0)
				(type default)
			)
			(fill no)
			(layer "F.Fab")
		)
		(pad "D" smd custom
			(at 0 -0.9525 90)
			(size 0.1905 0.1905)
			(layers "F.Cu" "F.Mask" "F.Paste")
			(net "DRV_ACT_21_N")
			(options
				(clearance outline)
				(anchor circle)
			)
			(primitives
				(gr_poly
					(pts
						(arc
							(start -0.1778 0.5715)
							(mid -0.321484 0.511984)
							(end -0.381 0.3683)
						)
						(arc
							(start -0.381 -0.3683)
							(mid -0.321484 -0.511984)
							(end -0.1778 -0.5715)
						)
						(arc
							(start 0.1778 -0.5715)
							(mid 0.321484 -0.511984)
							(end 0.381 -0.3683)
						)
						(arc
							(start 0.381 0.3683)
							(mid 0.321484 0.511984)
							(end 0.1778 0.5715)
						)
					)
					(width 0)
					(fill yes)
				)
			)
		)
		(pad "G" smd custom
			(at -0.98425 0.9525 90)
			(size 0.1905 0.1905)
			(layers "F.Cu" "F.Mask" "F.Paste")
			(net "DRIVE_B_21_ACT")
			(options
				(clearance outline)
				(anchor circle)
			)
			(primitives
				(gr_poly
					(pts
						(arc
							(start -0.1778 0.5715)
							(mid -0.321484 0.511984)
							(end -0.381 0.3683)
						)
						(arc
							(start -0.381 -0.3683)
							(mid -0.321484 -0.511984)
							(end -0.1778 -0.5715)
						)
						(arc
							(start 0.1778 -0.5715)
							(mid 0.321484 -0.511984)
							(end 0.381 -0.3683)
						)
						(arc
							(start 0.381 0.3683)
							(mid 0.321484 0.511984)
							(end 0.1778 0.5715)
						)
					)
					(width 0)
					(fill yes)
				)
			)
		)
		(pad "S" smd custom
			(at 0.98425 0.9525 90)
			(size 0.1905 0.1905)
			(layers "F.Cu" "F.Mask" "F.Paste")
			(net "GND")
			(options
				(clearance outline)
				(anchor circle)
			)
			(primitives
				(gr_poly
					(pts
						(arc
							(start -0.1778 0.5715)
							(mid -0.321484 0.511984)
							(end -0.381 0.3683)
						)
						(arc
							(start -0.381 -0.3683)
							(mid -0.321484 -0.511984)
							(end -0.1778 -0.5715)
						)
						(arc
							(start 0.1778 -0.5715)
							(mid 0.321484 -0.511984)
							(end 0.381 -0.3683)
						)
						(arc
							(start 0.381 0.3683)
							(mid 0.321484 0.511984)
							(end 0.1778 0.5715)
						)
					)
					(width 0)
					(fill yes)
				)
			)
		)
	)
	(footprint ""
		(layer "F.Cu")
		(at 363.855 -36.83 180)
		(property "Reference" "C434"
			(at 0 0 180)
			(layer "F.SilkS")
			(hide yes)
			(effects
				(font
					(size 1.27 1.27)
				)
			)
		)
		(property "Value" "SC10U16V6KX-2GP"
			(at -0.0762 -5.1308 180)
			(unlocked yes)
			(layer "F.Fab")
			(hide yes)
			(effects
				(font
					(size 1.016 1.016)
					(thickness 0.1524)
				)
			)
		)
		(property "Device Type" "C1206H71"
			(at -0.127 -6.6548 180)
			(unlocked yes)
			(layer "F.Fab")
			(hide yes)
			(effects
				(font
					(size 1.016 1.016)
					(thickness 0.1524)
				)
			)
		)
		(duplicate_pad_numbers_are_jumpers no)
		(fp_line
			(start 1.016 2.2352)
			(end -1.016 2.2352)
			(stroke
				(width 0.1524)
				(type default)
			)
			(layer "F.SilkS")
		)
		(fp_line
			(start 1.016 0.8382)
			(end 1.016 2.2352)
			(stroke
				(width 0.1524)
				(type default)
			)
			(layer "F.SilkS")
		)
		(fp_line
			(start 1.016 -2.2352)
			(end 1.016 -0.8382)
			(stroke
				(width 0.1524)
				(type default)
			)
			(layer "F.SilkS")
		)
		(fp_line
			(start -1.016 2.2352)
			(end -1.016 0.8382)
			(stroke
				(width 0.1524)
				(type default)
			)
			(layer "F.SilkS")
		)
		(fp_line
			(start -1.016 -0.8382)
			(end -1.016 -2.2352)
			(stroke
				(width 0.1524)
				(type default)
			)
			(layer "F.SilkS")
		)
		(fp_line
			(start -1.016 -2.2352)
			(end 1.016 -2.2352)
			(stroke
				(width 0.1524)
				(type default)
			)
			(layer "F.SilkS")
		)
		(fp_rect
			(start -1.0922 2.3114)
			(end 1.0922 -2.3114)
			(stroke
				(width 0)
				(type default)
			)
			(fill no)
			(layer "F.CrtYd")
		)
		(fp_poly
			(pts
				(xy 1.0922 -2.3114) (xy 1.0922 2.3114) (xy -1.0922 2.3114) (xy -1.0922 -2.3114)
			)
			(stroke
				(width 0)
				(type default)
			)
			(fill no)
			(layer "F.Fab")
		)
		(pad "1" smd rect
			(at 0 -1.397 180)
			(size 1.651 1.27)
			(layers "F.Cu" "F.Mask" "F.Paste")
			(net "P5V_HDD31")
		)
		(pad "2" smd rect
			(at 0 1.397 180)
			(size 1.651 1.27)
			(layers "F.Cu" "F.Mask" "F.Paste")
			(net "GND")
		)
	)
	(footprint ""
		(layer "F.Cu")
		(at 241.995452 -358.855772 90)
		(property "Reference" "R1048"
			(at 0 0 90)
			(layer "F.SilkS")
			(hide yes)
			(effects
				(font
					(size 1.27 1.27)
				)
			)
		)
		(property "Value" "49K9R2F-L-GP"
			(at 0.064008 -3.993896 90)
			(unlocked yes)
			(layer "F.Fab")
			(hide yes)
			(effects
				(font
					(size 1.016 1.016)
					(thickness 0.1524)
				)
			)
		)
		(property "Device Type" "R402H16"
			(at 0.064008 -5.517896 90)
			(unlocked yes)
			(layer "F.Fab")
			(hide yes)
			(effects
				(font
					(size 1.016 1.016)
					(thickness 0.1524)
				)
			)
		)
		(duplicate_pad_numbers_are_jumpers no)
		(fp_line
			(start 0.508 -0.9398)
			(end -0.508 -0.9398)
			(stroke
				(width 0.1524)
				(type default)
			)
			(layer "F.SilkS")
		)
		(fp_line
			(start -0.508 -0.9398)
			(end -0.508 0.9398)
			(stroke
				(width 0.1524)
				(type default)
			)
			(layer "F.SilkS")
		)
		(fp_rect
			(start -0.508 0.9398)
			(end 0.508 -0.9398)
			(stroke
				(width 0)
				(type default)
			)
			(fill no)
			(layer "F.CrtYd")
		)
		(fp_rect
			(start -0.508 0.9398)
			(end 0.508 -0.9398)
			(stroke
				(width 0)
				(type default)
			)
			(fill no)
			(layer "F.Fab")
		)
		(pad "1" smd custom
			(at 0 -0.4445 90)
			(size 0.1397 0.1397)
			(layers "F.Cu" "F.Mask" "F.Paste")
			(net "P12V_IN")
			(options
				(clearance outline)
				(anchor circle)
			)
			(primitives
				(gr_poly
					(pts
						(arc
							(start -0.1778 -0.2794)
							(mid -0.249642 -0.249642)
							(end -0.2794 -0.1778)
						)
						(arc
							(start -0.2794 0.1778)
							(mid -0.249642 0.249642)
							(end -0.1778 0.2794)
						)
						(arc
							(start 0.1778 0.2794)
							(mid 0.249642 0.249642)
							(end 0.2794 0.1778)
						)
						(arc
							(start 0.2794 -0.1778)
							(mid 0.249642 -0.249642)
							(end 0.1778 -0.2794)
						)
					)
					(width 0)
					(fill yes)
				)
			)
		)
		(pad "2" smd custom
			(at 0 0.4445 90)
			(size 0.1397 0.1397)
			(layers "F.Cu" "F.Mask" "F.Paste")
			(net "MB3_CM_OV_R")
			(options
				(clearance outline)
				(anchor circle)
			)
			(primitives
				(gr_poly
					(pts
						(arc
							(start -0.1778 -0.2794)
							(mid -0.249642 -0.249642)
							(end -0.2794 -0.1778)
						)
						(arc
							(start -0.2794 0.1778)
							(mid -0.249642 0.249642)
							(end -0.1778 0.2794)
						)
						(arc
							(start 0.1778 0.2794)
							(mid 0.249642 0.249642)
							(end 0.2794 0.1778)
						)
						(arc
							(start 0.2794 -0.1778)
							(mid 0.249642 -0.249642)
							(end 0.1778 -0.2794)
						)
					)
					(width 0)
					(fill yes)
				)
			)
		)
	)
	(footprint ""
		(layer "F.Cu")
		(at 451.749922 -28.910026 -90)
		(property "Reference" "HDDSAS34"
			(at 0 0 270)
			(layer "F.SilkS")
			(hide yes)
			(effects
				(font
					(size 1.27 1.27)
				)
			)
		)
		(property "Value" "SKT-SAS15P-14P-45-GP"
			(at -20.7645 -8.9789 270)
			(unlocked yes)
			(layer "F.Fab")
			(hide yes)
			(effects
				(font
					(size 1.016 1.016)
					(thickness 0.1524)
				)
			)
		)
		(property "Device Type" "10120818-001C-TRLF"
			(at -20.7645 -10.5029 270)
			(unlocked yes)
			(layer "F.Fab")
			(hide yes)
			(effects
				(font
					(size 1.016 1.016)
					(thickness 0.1524)
				)
			)
		)
		(duplicate_pad_numbers_are_jumpers no)
		(fp_line
			(start 1.651 4.2926)
			(end 1.651 3.0099)
			(stroke
				(width 0.1524)
				(type default)
			)
			(layer "F.SilkS")
		)
		(fp_line
			(start 8.509 4.2926)
			(end 1.651 4.2926)
			(stroke
				(width 0.1524)
				(type default)
			)
			(layer "F.SilkS")
		)
		(fp_line
			(start -23.4188 3.0099)
			(end -23.4188 -3.2512)
			(stroke
				(width 0.1524)
				(type default)
			)
			(layer "F.SilkS")
		)
		(fp_line
			(start 1.651 3.0099)
			(end -23.4188 3.0099)
			(stroke
				(width 0.1524)
				(type default)
			)
			(layer "F.SilkS")
		)
		(fp_line
			(start 8.509 3.0099)
			(end 8.509 4.2926)
			(stroke
				(width 0.1524)
				(type default)
			)
			(layer "F.SilkS")
		)
		(fp_line
			(start 23.4188 3.0099)
			(end 8.509 3.0099)
			(stroke
				(width 0.1524)
				(type default)
			)
			(layer "F.SilkS")
		)
		(fp_line
			(start -23.4188 -3.2512)
			(end 23.4188 -3.2512)
			(stroke
				(width 0.1524)
				(type default)
			)
			(layer "F.SilkS")
		)
		(fp_line
			(start 23.4188 -3.2512)
			(end 23.4188 3.0099)
			(stroke
				(width 0.1524)
				(type default)
			)
			(layer "F.SilkS")
		)
		(fp_line
			(start 15.5067 -3.3401)
			(end 16.2687 -3.3401)
			(stroke
				(width 0.3302)
				(type default)
			)
			(layer "F.SilkS")
		)
		(fp_poly
			(pts
				(xy 15.868904 -3.230372) (xy 16.503904 -3.865372) (xy 15.233904 -3.865372)
			)
			(stroke
				(width 0)
				(type default)
			)
			(fill yes)
			(layer "F.SilkS")
		)
		(fp_poly
			(pts
				(xy -22.8727 -2.7559) (xy 22.8727 -2.7559) (xy 22.8727 2.7559) (xy 8.255 2.7559) (xy 8.255 3.5179)
				(xy 1.905 3.5179) (xy 1.905 2.7559) (xy -22.8727 2.7559)
			)
			(stroke
				(width 0)
				(type default)
			)
			(fill no)
			(layer "F.CrtYd")
		)
		(fp_poly
			(pts
				(xy 1.397 4.5466) (xy 1.397 3.2639) (xy -23.6728 3.2639) (xy -23.6728 -3.5052) (xy 23.6728 -3.5052)
				(xy 23.6728 -0.00635) (xy 22.8727 -0.00635) (xy 22.8727 -2.7559) (xy -22.8727 -2.7559) (xy -22.8727 2.7559)
				(xy 1.905 2.7559) (xy 1.905 3.5179) (xy 8.255 3.5179) (xy 8.255 2.7559) (xy 22.8727 2.7559) (xy 22.8727 0.00635)
				(xy 23.6728 0.00635) (xy 23.6728 3.2639) (xy 8.763 3.2639) (xy 8.763 4.5466)
			)
			(stroke
				(width 0)
				(type default)
			)
			(fill no)
			(layer "F.CrtYd")
		)
		(fp_poly
			(pts
				(xy 1.397 4.5466) (xy 1.397 3.2639) (xy -23.6728 3.2639) (xy -23.6728 -3.5052) (xy 23.6728 -3.5052)
				(xy 23.6728 3.2639) (xy 8.763 3.2639) (xy 8.763 4.5466)
			)
			(stroke
				(width 0)
				(type default)
			)
			(fill no)
			(layer "F.Fab")
		)
		(pad "" np_thru_hole circle
			(at -18.874994 0 270)
			(size 0.254 0.254)
			(drill 1.3462)
			(layers "*.Cu" "*.Mask")
			(clearance 0.9017)
			(thermal_gap 0.9017)
		)
		(pad "" np_thru_hole circle
			(at 18.874994 0 270)
			(size 0.254 0.254)
			(drill 0.9398)
			(layers "*.Cu" "*.Mask")
			(clearance 0.6985)
			(thermal_gap 0.6985)
		)
		(pad "G1" smd rect
			(at 21.874988 0 270)
			(size 2.5908 2.5908)
			(layers "F.Cu" "F.Mask" "F.Paste")
			(net "GND")
		)
		(pad "G2" smd rect
			(at -21.874988 0 270)
			(size 2.5908 2.5908)
			(layers "F.Cu" "F.Mask" "F.Paste")
			(net "GND")
		)
		(pad "P1" smd rect
			(at 1.905 -1.82499 270)
			(size 0.6096 2.3622)
			(layers "F.Cu" "F.Mask" "F.Paste")
			(net "Net_1624")
		)
		(pad "P2" smd rect
			(at 0.635 -1.82499 270)
			(size 0.6096 2.3622)
			(layers "F.Cu" "F.Mask" "F.Paste")
			(net "Net_1625")
		)
		(pad "P3" smd rect
			(at -0.635 -1.82499 270)
			(size 0.6096 2.3622)
			(layers "F.Cu" "F.Mask" "F.Paste")
			(net "Net_1626")
		)
		(pad "P4" smd rect
			(at -1.905 -1.82499 270)
			(size 0.6096 2.3622)
			(layers "F.Cu" "F.Mask" "F.Paste")
			(net "GND")
		)
		(pad "P5" smd rect
			(at -3.175 -1.82499 270)
			(size 0.6096 2.3622)
			(layers "F.Cu" "F.Mask" "F.Paste")
			(net "HDD_PRSNT_34")
		)
		(pad "P6" smd rect
			(at -4.445 -1.82499 270)
			(size 0.6096 2.3622)
			(layers "F.Cu" "F.Mask" "F.Paste")
			(net "GND")
		)
		(pad "P7" smd rect
			(at -5.715 -1.82499 270)
			(size 0.6096 2.3622)
			(layers "F.Cu" "F.Mask" "F.Paste")
			(net "5V_PRE_34")
		)
		(pad "P8" smd rect
			(at -6.985 -1.82499 270)
			(size 0.6096 2.3622)
			(layers "F.Cu" "F.Mask" "F.Paste")
			(net "P5V_HDD34")
		)
		(pad "P9" smd rect
			(at -8.255 -1.82499 270)
			(size 0.6096 2.3622)
			(layers "F.Cu" "F.Mask" "F.Paste")
			(net "P5V_HDD34")
		)
		(pad "P10" smd rect
			(at -9.525 -1.82499 270)
			(size 0.6096 2.3622)
			(layers "F.Cu" "F.Mask" "F.Paste")
			(net "GND")
		)
		(pad "P11" smd rect
			(at -10.795 -1.82499 270)
			(size 0.6096 2.3622)
			(layers "F.Cu" "F.Mask" "F.Paste")
			(net "ACT_HDD_34")
		)
		(pad "P12" smd rect
			(at -12.065 -1.82499 270)
			(size 0.6096 2.3622)
			(layers "F.Cu" "F.Mask" "F.Paste")
			(net "GND")
		)
		(pad "P13" smd rect
			(at -13.335 -1.82499 270)
			(size 0.6096 2.3622)
			(layers "F.Cu" "F.Mask" "F.Paste")
			(net "12V_PRE_34")
		)
		(pad "P14" smd rect
			(at -14.605 -1.82499 270)
			(size 0.6096 2.3622)
			(layers "F.Cu" "F.Mask" "F.Paste")
			(net "P12V_HDD34")
		)
		(pad "P15" smd rect
			(at -15.875 -1.82499 270)
			(size 0.6096 2.3622)
			(layers "F.Cu" "F.Mask" "F.Paste")
			(net "P12V_HDD34")
		)
		(pad "S1" smd rect
			(at 15.875 -1.82499 270)
			(size 0.6096 2.3622)
			(layers "F.Cu" "F.Mask" "F.Paste")
			(net "GND")
		)
		(pad "S2" smd rect
			(at 14.605 -1.82499 270)
			(size 0.6096 2.3622)
			(layers "F.Cu" "F.Mask" "F.Paste")
			(net "SAS_HDD_RX_P34")
		)
		(pad "S3" smd rect
			(at 13.335 -1.82499 270)
			(size 0.6096 2.3622)
			(layers "F.Cu" "F.Mask" "F.Paste")
			(net "SAS_HDD_RX_N34")
		)
		(pad "S4" smd rect
			(at 12.065 -1.82499 270)
			(size 0.6096 2.3622)
			(layers "F.Cu" "F.Mask" "F.Paste")
			(net "GND")
		)
		(pad "S5" smd rect
			(at 10.795 -1.82499 270)
			(size 0.6096 2.3622)
			(layers "F.Cu" "F.Mask" "F.Paste")
			(net "PHY_DRV_B_TO_SCC_B_34_DN")
		)
		(pad "S6" smd rect
			(at 9.525 -1.82499 270)
			(size 0.6096 2.3622)
			(layers "F.Cu" "F.Mask" "F.Paste")
			(net "PHY_DRV_B_TO_SCC_B_34_DP")
		)
		(pad "S7" smd rect
			(at 8.255 -1.82499 270)
			(size 0.6096 2.3622)
			(layers "F.Cu" "F.Mask" "F.Paste")
			(net "GND")
		)
		(pad "S8" smd rect
			(at 7.480046 2.845054 270)
			(size 0.508 2.3622)
			(layers "F.Cu" "F.Mask" "F.Paste")
			(net "GND")
		)
		(pad "S9" smd rect
			(at 6.679946 2.845054 270)
			(size 0.508 2.3622)
			(layers "F.Cu" "F.Mask" "F.Paste")
			(net "Net_459")
		)
		(pad "S10" smd rect
			(at 5.8801 2.845054 270)
			(size 0.508 2.3622)
			(layers "F.Cu" "F.Mask" "F.Paste")
			(net "Net_351")
		)
		(pad "S11" smd rect
			(at 5.08 2.845054 270)
			(size 0.508 2.3622)
			(layers "F.Cu" "F.Mask" "F.Paste")
			(net "GND")
		)
		(pad "S12" smd rect
			(at 4.2799 2.845054 270)
			(size 0.508 2.3622)
			(layers "F.Cu" "F.Mask" "F.Paste")
			(net "Net_387")
		)
		(pad "S13" smd rect
			(at 3.480054 2.845054 270)
			(size 0.508 2.3622)
			(layers "F.Cu" "F.Mask" "F.Paste")
			(net "Net_423")
		)
		(pad "S14" smd rect
			(at 2.679954 2.845054 270)
			(size 0.508 2.3622)
			(layers "F.Cu" "F.Mask" "F.Paste")
			(net "GND")
		)
		(zone
			(layer "F.Cu")
			(hatch none 0.5)
			(connect_pads
				(clearance 0)
			)
			(min_thickness 0.25)
			(keepout
				(tracks not_allowed)
				(vias allowed)
				(pads allowed)
				(copperpour not_allowed)
				(footprints allowed)
			)
			(placement
				(enabled no)
				(sheetname "")
			)
			(fill
				(thermal_gap 0.5)
				(thermal_bridge_width 0.5)
				(island_removal_mode 0)
			)
			(polygon
				(pts
					(xy 455.407522 -45.648626) (xy 448.333622 -45.648626) (xy 448.333622 -52.582826) (xy 449.438522 -52.582826)
					(xy 449.438522 -48.468026) (xy 454.061322 -48.468026) (xy 454.061322 -52.582826) (xy 455.407522 -52.582826)
				)
			)
		)
		(zone
			(layer "F.Cu")
			(hatch none 0.5)
			(connect_pads
				(clearance 0)
			)
			(min_thickness 0.25)
			(keepout
				(tracks allowed)
				(vias not_allowed)
				(pads allowed)
				(copperpour not_allowed)
				(footprints allowed)
			)
			(placement
				(enabled no)
				(sheetname "")
			)
			(fill
				(thermal_gap 0.5)
				(thermal_bridge_width 0.5)
				(island_removal_mode 0)
			)
			(polygon
				(pts
					(xy 455.407522 -45.648626) (xy 448.333622 -45.648626) (xy 448.333622 -52.582826) (xy 449.438522 -52.582826)
					(xy 449.438522 -48.468026) (xy 454.061322 -48.468026) (xy 454.061322 -52.582826) (xy 455.407522 -52.582826)
				)
			)
		)
		(zone
			(layer "F.Cu")
			(hatch none 0.5)
			(connect_pads
				(clearance 0)
			)
			(min_thickness 0.25)
			(keepout
				(tracks allowed)
				(vias not_allowed)
				(pads allowed)
				(copperpour not_allowed)
				(footprints allowed)
			)
			(placement
				(enabled no)
				(sheetname "")
			)
			(fill
				(thermal_gap 0.5)
				(thermal_bridge_width 0.5)
				(island_removal_mode 0)
			)
			(polygon
				(pts
					(xy 455.407522 -12.171426) (xy 448.333622 -12.171426) (xy 448.333622 -5.237226) (xy 449.438522 -5.237226)
					(xy 449.438522 -9.352026) (xy 454.061322 -9.352026) (xy 454.061322 -5.237226) (xy 455.407522 -5.237226)
				)
			)
		)
		(zone
			(layer "F.Cu")
			(hatch none 0.5)
			(connect_pads
				(clearance 0)
			)
			(min_thickness 0.25)
			(keepout
				(tracks not_allowed)
				(vias allowed)
				(pads allowed)
				(copperpour not_allowed)
				(footprints allowed)
			)
			(placement
				(enabled no)
				(sheetname "")
			)
			(fill
				(thermal_gap 0.5)
				(thermal_bridge_width 0.5)
				(island_removal_mode 0)
			)
			(polygon
				(pts
					(xy 455.407522 -12.171426) (xy 448.333622 -12.171426) (xy 448.333622 -5.237226) (xy 449.438522 -5.237226)
					(xy 449.438522 -9.352026) (xy 454.061322 -9.352026) (xy 454.061322 -5.237226) (xy 455.407522 -5.237226)
				)
			)
		)
		(zone
			(layers "F.Cu" "B.Cu" "In1.Cu" "In2.Cu" "In3.Cu" "In4.Cu" "In5.Cu" "In6.Cu")
			(hatch none 0.5)
			(connect_pads
				(clearance 0)
			)
			(min_thickness 0.25)
			(keepout
				(tracks not_allowed)
				(vias allowed)
				(pads allowed)
				(copperpour not_allowed)
				(footprints allowed)
			)
			(placement
				(enabled no)
				(sheetname "")
			)
			(fill
				(thermal_gap 0.5)
				(thermal_bridge_width 0.5)
				(island_removal_mode 0)
			)
			(polygon
				(pts
					(arc
						(start 452.524622 -10.035032)
						(mid 450.975222 -10.035032)
						(end 452.524622 -10.035032)
					)
				)
			)
		)
		(zone
			(layers "F.Cu" "B.Cu" "In1.Cu" "In2.Cu" "In3.Cu" "In4.Cu" "In5.Cu" "In6.Cu")
			(hatch none 0.5)
			(connect_pads
				(clearance 0)
			)
			(min_thickness 0.25)
			(keepout
				(tracks not_allowed)
				(vias allowed)
				(pads allowed)
				(copperpour not_allowed)
				(footprints allowed)
			)
			(placement
				(enabled no)
				(sheetname "")
			)
			(fill
				(thermal_gap 0.5)
				(thermal_bridge_width 0.5)
				(island_removal_mode 0)
			)
			(polygon
				(pts
					(arc
						(start 452.727822 -47.78502)
						(mid 450.772022 -47.78502)
						(end 452.727822 -47.78502)
					)
				)
			)
		)
	)
	(footprint ""
		(layer "F.Cu")
		(at 141.097 -30.861)
		(property "Reference" "Q144"
			(at 0 0 0)
			(layer "F.SilkS")
			(hide yes)
			(effects
				(font
					(size 1.27 1.27)
				)
			)
		)
		(property "Value" "AO4407AL-GP"
			(at -3.707384 -1.5367 0)
			(unlocked yes)
			(layer "F.Fab")
			(hide yes)
			(effects
				(font
					(size 1.016 1.016)
					(thickness 0.1524)
				)
			)
		)
		(property "Device Type" "SOIC8H69"
			(at -3.707384 -3.0607 0)
			(unlocked yes)
			(layer "F.Fab")
			(hide yes)
			(effects
				(font
					(size 1.016 1.016)
					(thickness 0.1524)
				)
			)
		)
		(duplicate_pad_numbers_are_jumpers no)
		(fp_line
			(start -2.7432 -1.4224)
			(end -2.7432 1.4224)
			(stroke
				(width 0.1524)
				(type default)
			)
			(layer "F.SilkS")
		)
		(fp_line
			(start -2.7432 1.4224)
			(end -2.6416 1.4224)
			(stroke
				(width 0.1524)
				(type default)
			)
			(layer "F.SilkS")
		)
		(fp_line
			(start -2.7432 1.4224)
			(end 2.1336 1.4224)
			(stroke
				(width 0.1524)
				(type default)
			)
			(layer "F.SilkS")
		)
		(fp_line
			(start -2.7178 -0.508)
			(end -2.1844 -0.0508)
			(stroke
				(width 0.1524)
				(type default)
			)
			(layer "F.SilkS")
		)
		(fp_line
			(start -2.6289 3.4417)
			(end -2.6289 1.4732)
			(stroke
				(width 0.381)
				(type default)
			)
			(layer "F.SilkS")
		)
		(fp_line
			(start -2.1844 -0.0508)
			(end -2.7178 0.508)
			(stroke
				(width 0.1524)
				(type default)
			)
			(layer "F.SilkS")
		)
		(fp_line
			(start 2.1336 -1.4224)
			(end -2.7432 -1.4224)
			(stroke
				(width 0.1524)
				(type default)
			)
			(layer "F.SilkS")
		)
		(fp_line
			(start 2.1336 1.4224)
			(end 2.1336 -1.4224)
			(stroke
				(width 0.1524)
				(type default)
			)
			(layer "F.SilkS")
		)
		(fp_poly
			(pts
				(xy -2.2098 -1.4224) (xy -2.2098 1.4224) (xy 2.2098 1.4224) (xy 2.2098 -1.4224)
			)
			(stroke
				(width 0)
				(type default)
			)
			(fill yes)
			(layer "F.SilkS")
		)
		(fp_rect
			(start -2.450084 2.999994)
			(end 2.450084 -2.999994)
			(stroke
				(width 0)
				(type default)
			)
			(fill no)
			(layer "F.CrtYd")
		)
		(fp_poly
			(pts
				(xy -2.8194 3.6322) (xy -2.8194 -3.6322) (xy 2.8194 -3.6322) (xy 2.8194 1.18364) (xy 2.450084 1.18364)
				(xy 2.450084 -2.999994) (xy -2.450084 -2.999994) (xy -2.450084 2.999994) (xy 2.450084 2.999994)
				(xy 2.450084 1.18618) (xy 2.8194 1.18618) (xy 2.8194 3.6322)
			)
			(stroke
				(width 0)
				(type default)
			)
			(fill no)
			(layer "F.CrtYd")
		)
		(fp_rect
			(start -2.8194 3.6322)
			(end 2.8194 -3.6322)
			(stroke
				(width 0)
				(type default)
			)
			(fill no)
			(layer "F.Fab")
		)
		(pad "1" smd rect
			(at -1.905 2.54)
			(size 0.635 1.651)
			(layers "F.Cu" "F.Mask" "F.Paste")
			(net "P12V_B")
		)
		(pad "2" smd rect
			(at -0.635 2.54)
			(size 0.635 1.651)
			(layers "F.Cu" "F.Mask" "F.Paste")
			(net "P12V_B")
		)
		(pad "3" smd rect
			(at 0.635 2.54)
			(size 0.635 1.651)
			(layers "F.Cu" "F.Mask" "F.Paste")
			(net "P12V_B")
		)
		(pad "4" smd rect
			(at 1.905 2.54)
			(size 0.635 1.651)
			(layers "F.Cu" "F.Mask" "F.Paste")
			(net "SW_HDD_N28")
		)
		(pad "5" smd rect
			(at 1.905 -2.54)
			(size 0.635 1.651)
			(layers "F.Cu" "F.Mask" "F.Paste")
			(net "P12V_HDD28")
		)
		(pad "6" smd rect
			(at 0.635 -2.54)
			(size 0.635 1.651)
			(layers "F.Cu" "F.Mask" "F.Paste")
			(net "P12V_HDD28")
		)
		(pad "7" smd rect
			(at -0.635 -2.54)
			(size 0.635 1.651)
			(layers "F.Cu" "F.Mask" "F.Paste")
			(net "P12V_HDD28")
		)
		(pad "8" smd rect
			(at -1.905 -2.54)
			(size 0.635 1.651)
			(layers "F.Cu" "F.Mask" "F.Paste")
			(net "P12V_HDD28")
		)
	)
	(footprint ""
		(layer "F.Cu")
		(at 230.378 -193.7004)
		(property "Reference" "Q29"
			(at 0 0 0)
			(layer "F.SilkS")
			(hide yes)
			(effects
				(font
					(size 1.27 1.27)
				)
			)
		)
		(property "Value" "SSM3K324R-GP"
			(at 0.127 -8.9662 0)
			(unlocked yes)
			(layer "F.Fab")
			(hide yes)
			(effects
				(font
					(size 1.016 1.016)
					(thickness 0.1524)
				)
			)
		)
		(property "Device Type" "SOT23DGS2D4H35"
			(at 0.127 -10.4902 0)
			(unlocked yes)
			(layer "F.Fab")
			(hide yes)
			(effects
				(font
					(size 1.016 1.016)
					(thickness 0.1524)
				)
			)
		)
		(duplicate_pad_numbers_are_jumpers no)
		(fp_line
			(start -1.651 -1.778)
			(end -1.651 1.778)
			(stroke
				(width 0.1524)
				(type default)
			)
			(layer "F.SilkS")
		)
		(fp_line
			(start -1.651 1.778)
			(end 1.651 1.778)
			(stroke
				(width 0.1524)
				(type default)
			)
			(layer "F.SilkS")
		)
		(fp_line
			(start 1.651 -1.778)
			(end -1.651 -1.778)
			(stroke
				(width 0.1524)
				(type default)
			)
			(layer "F.SilkS")
		)
		(fp_line
			(start 1.651 1.778)
			(end 1.651 -1.778)
			(stroke
				(width 0.1524)
				(type default)
			)
			(layer "F.SilkS")
		)
		(fp_poly
			(pts
				(xy -1.778 1.8796) (xy -1.778 -1.8796) (xy 1.778 -1.8796) (xy 1.778 1.8796)
			)
			(stroke
				(width 0)
				(type default)
			)
			(fill no)
			(layer "F.CrtYd")
		)
		(fp_poly
			(pts
				(xy -1.778 1.8796) (xy -1.778 -1.8796) (xy 1.778 -1.8796) (xy 1.778 1.8796)
			)
			(stroke
				(width 0)
				(type default)
			)
			(fill no)
			(layer "F.Fab")
		)
		(pad "D" smd custom
			(at 0 -0.9525)
			(size 0.1905 0.1905)
			(layers "F.Cu" "F.Mask" "F.Paste")
			(net "P3V3_STBY_B")
			(options
				(clearance outline)
				(anchor circle)
			)
			(primitives
				(gr_poly
					(pts
						(arc
							(start -0.1778 0.5715)
							(mid -0.321484 0.511984)
							(end -0.381 0.3683)
						)
						(arc
							(start -0.381 -0.3683)
							(mid -0.321484 -0.511984)
							(end -0.1778 -0.5715)
						)
						(arc
							(start 0.1778 -0.5715)
							(mid 0.321484 -0.511984)
							(end 0.381 -0.3683)
						)
						(arc
							(start 0.381 0.3683)
							(mid 0.321484 0.511984)
							(end 0.1778 0.5715)
						)
					)
					(width 0)
					(fill yes)
				)
			)
		)
		(pad "G" smd custom
			(at -0.98425 0.9525)
			(size 0.1905 0.1905)
			(layers "F.Cu" "F.Mask" "F.Paste")
			(net "SCC_FULL_PWR_EN_5V")
			(options
				(clearance outline)
				(anchor circle)
			)
			(primitives
				(gr_poly
					(pts
						(arc
							(start -0.1778 0.5715)
							(mid -0.321484 0.511984)
							(end -0.381 0.3683)
						)
						(arc
							(start -0.381 -0.3683)
							(mid -0.321484 -0.511984)
							(end -0.1778 -0.5715)
						)
						(arc
							(start 0.1778 -0.5715)
							(mid 0.321484 -0.511984)
							(end 0.381 -0.3683)
						)
						(arc
							(start 0.381 0.3683)
							(mid 0.321484 0.511984)
							(end 0.1778 0.5715)
						)
					)
					(width 0)
					(fill yes)
				)
			)
		)
		(pad "S" smd custom
			(at 0.98425 0.9525)
			(size 0.1905 0.1905)
			(layers "F.Cu" "F.Mask" "F.Paste")
			(net "GPIO_VCC_U9")
			(options
				(clearance outline)
				(anchor circle)
			)
			(primitives
				(gr_poly
					(pts
						(arc
							(start -0.1778 0.5715)
							(mid -0.321484 0.511984)
							(end -0.381 0.3683)
						)
						(arc
							(start -0.381 -0.3683)
							(mid -0.321484 -0.511984)
							(end -0.1778 -0.5715)
						)
						(arc
							(start 0.1778 -0.5715)
							(mid 0.321484 -0.511984)
							(end 0.381 -0.3683)
						)
						(arc
							(start 0.381 0.3683)
							(mid 0.321484 0.511984)
							(end 0.1778 0.5715)
						)
					)
					(width 0)
					(fill yes)
				)
			)
		)
	)
	(footprint ""
		(layer "F.Cu")
		(at 20.210018 -99.401884)
		(property "Reference" "R382"
			(at 0 0 0)
			(layer "F.SilkS")
			(hide yes)
			(effects
				(font
					(size 1.27 1.27)
				)
			)
		)
		(property "Value" "130R3F-GP"
			(at -0.0254 -2.5146 0)
			(unlocked yes)
			(layer "F.Fab")
			(hide yes)
			(effects
				(font
					(size 1.016 1.016)
					(thickness 0.1524)
				)
			)
		)
		(property "Device Type" "R603H22"
			(at -0.0254 -4.0386 0)
			(unlocked yes)
			(layer "F.Fab")
			(hide yes)
			(effects
				(font
					(size 1.016 1.016)
					(thickness 0.1524)
				)
			)
		)
		(duplicate_pad_numbers_are_jumpers no)
		(fp_line
			(start -0.4826 0)
			(end -0.2032 0)
			(stroke
				(width 0.2032)
				(type default)
			)
			(layer "F.SilkS")
		)
		(fp_line
			(start 0.2032 0)
			(end 0.4826 0)
			(stroke
				(width 0.2032)
				(type default)
			)
			(layer "F.SilkS")
		)
		(fp_rect
			(start -0.5842 1.3335)
			(end 0.5842 -1.3335)
			(stroke
				(width 0)
				(type default)
			)
			(fill no)
			(layer "F.CrtYd")
		)
		(fp_rect
			(start -0.5842 1.3335)
			(end 0.5842 -1.3335)
			(stroke
				(width 0)
				(type default)
			)
			(fill no)
			(layer "F.Fab")
		)
		(pad "1" smd custom
			(at 0 -0.762)
			(size 0.2159 0.2159)
			(layers "F.Cu" "F.Mask" "F.Paste")
			(net "P5V_B_1")
			(options
				(clearance outline)
				(anchor circle)
			)
			(primitives
				(gr_poly
					(pts
						(arc
							(start -0.3302 -0.4318)
							(mid -0.402042 -0.402042)
							(end -0.4318 -0.3302)
						)
						(arc
							(start -0.4318 0.3302)
							(mid -0.402042 0.402042)
							(end -0.3302 0.4318)
						)
						(arc
							(start 0.3302 0.4318)
							(mid 0.402042 0.402042)
							(end 0.4318 0.3302)
						)
						(arc
							(start 0.4318 -0.3302)
							(mid 0.402042 -0.402042)
							(end 0.3302 -0.4318)
						)
					)
					(width 0)
					(fill yes)
				)
			)
		)
		(pad "2" smd custom
			(at 0 0.762)
			(size 0.2159 0.2159)
			(layers "F.Cu" "F.Mask" "F.Paste")
			(net "FLT_HDD12")
			(options
				(clearance outline)
				(anchor circle)
			)
			(primitives
				(gr_poly
					(pts
						(arc
							(start -0.3302 -0.4318)
							(mid -0.402042 -0.402042)
							(end -0.4318 -0.3302)
						)
						(arc
							(start -0.4318 0.3302)
							(mid -0.402042 0.402042)
							(end -0.3302 0.4318)
						)
						(arc
							(start 0.3302 0.4318)
							(mid 0.402042 0.402042)
							(end 0.4318 0.3302)
						)
						(arc
							(start 0.4318 -0.3302)
							(mid 0.402042 -0.402042)
							(end 0.3302 -0.4318)
						)
					)
					(width 0)
					(fill yes)
				)
			)
		)
	)
	(footprint ""
		(layer "F.Cu")
		(at 24.257 -160.401 180)
		(property "Reference" "C193"
			(at 0 0 180)
			(layer "F.SilkS")
			(hide yes)
			(effects
				(font
					(size 1.27 1.27)
				)
			)
		)
		(property "Value" "SC1U25V3KX-GP"
			(at 0 -2.8194 180)
			(unlocked yes)
			(layer "F.Fab")
			(hide yes)
			(effects
				(font
					(size 1.016 1.016)
					(thickness 0.1524)
				)
			)
		)
		(property "Device Type" "C603H36"
			(at 0 -4.3434 180)
			(unlocked yes)
			(layer "F.Fab")
			(hide yes)
			(effects
				(font
					(size 1.016 1.016)
					(thickness 0.1524)
				)
			)
		)
		(duplicate_pad_numbers_are_jumpers no)
		(fp_line
			(start 0.508 0)
			(end -0.508 0)
			(stroke
				(width 0.2032)
				(type default)
			)
			(layer "F.SilkS")
		)
		(fp_rect
			(start -0.5842 1.3335)
			(end 0.5842 -1.3335)
			(stroke
				(width 0)
				(type default)
			)
			(fill no)
			(layer "F.CrtYd")
		)
		(fp_rect
			(start -0.5842 1.3335)
			(end 0.5842 -1.3335)
			(stroke
				(width 0)
				(type default)
			)
			(fill no)
			(layer "F.Fab")
		)
		(pad "1" smd custom
			(at 0 -0.762 180)
			(size 0.2159 0.2159)
			(layers "F.Cu" "F.Mask" "F.Paste")
			(net "P12V_HDD12")
			(options
				(clearance outline)
				(anchor circle)
			)
			(primitives
				(gr_poly
					(pts
						(arc
							(start -0.3302 -0.4318)
							(mid -0.402042 -0.402042)
							(end -0.4318 -0.3302)
						)
						(arc
							(start -0.4318 0.3302)
							(mid -0.402042 0.402042)
							(end -0.3302 0.4318)
						)
						(arc
							(start 0.3302 0.4318)
							(mid 0.402042 0.402042)
							(end 0.4318 0.3302)
						)
						(arc
							(start 0.4318 -0.3302)
							(mid 0.402042 -0.402042)
							(end 0.3302 -0.4318)
						)
					)
					(width 0)
					(fill yes)
				)
			)
		)
		(pad "2" smd custom
			(at 0 0.762 180)
			(size 0.2159 0.2159)
			(layers "F.Cu" "F.Mask" "F.Paste")
			(net "GND")
			(options
				(clearance outline)
				(anchor circle)
			)
			(primitives
				(gr_poly
					(pts
						(arc
							(start -0.3302 -0.4318)
							(mid -0.402042 -0.402042)
							(end -0.4318 -0.3302)
						)
						(arc
							(start -0.4318 0.3302)
							(mid -0.402042 0.402042)
							(end -0.3302 0.4318)
						)
						(arc
							(start 0.3302 0.4318)
							(mid 0.402042 0.402042)
							(end 0.4318 0.3302)
						)
						(arc
							(start 0.4318 -0.3302)
							(mid 0.402042 -0.402042)
							(end 0.3302 -0.4318)
						)
					)
					(width 0)
					(fill yes)
				)
			)
		)
	)
	(footprint ""
		(layer "F.Cu")
		(at 145.161 -150.622 90)
		(property "Reference" "R439"
			(at 0 0 90)
			(layer "F.SilkS")
			(hide yes)
			(effects
				(font
					(size 1.27 1.27)
				)
			)
		)
		(property "Value" "2R6F-GP"
			(at -0.0508 -4.8514 90)
			(unlocked yes)
			(layer "F.Fab")
			(hide yes)
			(effects
				(font
					(size 1.016 1.016)
					(thickness 0.1524)
				)
			)
		)
		(property "Device Type" "R1206H26"
			(at 0 -6.3754 90)
			(unlocked yes)
			(layer "F.Fab")
			(hide yes)
			(effects
				(font
					(size 1.016 1.016)
					(thickness 0.1524)
				)
			)
		)
		(duplicate_pad_numbers_are_jumpers no)
		(fp_line
			(start 1.016 -2.2352)
			(end 1.016 2.2352)
			(stroke
				(width 0.1524)
				(type default)
			)
			(layer "F.SilkS")
		)
		(fp_line
			(start -1.016 -2.2352)
			(end 1.016 -2.2352)
			(stroke
				(width 0.1524)
				(type default)
			)
			(layer "F.SilkS")
		)
		(fp_line
			(start 1.016 2.2352)
			(end -1.016 2.2352)
			(stroke
				(width 0.1524)
				(type default)
			)
			(layer "F.SilkS")
		)
		(fp_line
			(start -1.016 2.2352)
			(end -1.016 -2.2352)
			(stroke
				(width 0.1524)
				(type default)
			)
			(layer "F.SilkS")
		)
		(fp_rect
			(start -1.0922 2.3114)
			(end 1.0922 -2.3114)
			(stroke
				(width 0)
				(type default)
			)
			(fill no)
			(layer "F.CrtYd")
		)
		(fp_poly
			(pts
				(xy -1.0922 -2.3114) (xy 1.0922 -2.3114) (xy 1.0922 2.3114) (xy -1.0922 2.3114)
			)
			(stroke
				(width 0)
				(type default)
			)
			(fill no)
			(layer "F.Fab")
		)
		(pad "1" smd rect
			(at 0 -1.397 90)
			(size 1.651 1.27)
			(layers "F.Cu" "F.Mask" "F.Paste")
			(net "P12V_HDD16")
		)
		(pad "2" smd rect
			(at 0 1.397 90)
			(size 1.651 1.27)
			(layers "F.Cu" "F.Mask" "F.Paste")
			(net "12V_PRE_16")
		)
	)
	(footprint ""
		(layer "F.Cu")
		(at 256.779522 -360.400346)
		(property "Reference" "R1029"
			(at 0 0 0)
			(layer "F.SilkS")
			(hide yes)
			(effects
				(font
					(size 1.27 1.27)
				)
			)
		)
		(property "Value" "0R2J-2-GP"
			(at 0.064008 -3.993896 0)
			(unlocked yes)
			(layer "F.Fab")
			(hide yes)
			(effects
				(font
					(size 1.016 1.016)
					(thickness 0.1524)
				)
			)
		)
		(property "Device Type" "R402H16"
			(at 0.064008 -5.517896 0)
			(unlocked yes)
			(layer "F.Fab")
			(hide yes)
			(effects
				(font
					(size 1.016 1.016)
					(thickness 0.1524)
				)
			)
		)
		(duplicate_pad_numbers_are_jumpers no)
		(fp_line
			(start -0.508 -0.9398)
			(end -0.508 0.9398)
			(stroke
				(width 0.1524)
				(type default)
			)
			(layer "F.SilkS")
		)
		(fp_line
			(start 0.508 -0.9398)
			(end -0.508 -0.9398)
			(stroke
				(width 0.1524)
				(type default)
			)
			(layer "F.SilkS")
		)
		(fp_rect
			(start -0.508 0.9398)
			(end 0.508 -0.9398)
			(stroke
				(width 0)
				(type default)
			)
			(fill no)
			(layer "F.CrtYd")
		)
		(fp_rect
			(start -0.508 0.9398)
			(end 0.508 -0.9398)
			(stroke
				(width 0)
				(type default)
			)
			(fill no)
			(layer "F.Fab")
		)
		(pad "1" smd custom
			(at 0 -0.4445)
			(size 0.1397 0.1397)
			(layers "F.Cu" "F.Mask" "F.Paste")
			(net "MB3_CM_ADR1_R")
			(options
				(clearance outline)
				(anchor circle)
			)
			(primitives
				(gr_poly
					(pts
						(arc
							(start -0.1778 -0.2794)
							(mid -0.249642 -0.249642)
							(end -0.2794 -0.1778)
						)
						(arc
							(start -0.2794 0.1778)
							(mid -0.249642 0.249642)
							(end -0.1778 0.2794)
						)
						(arc
							(start 0.1778 0.2794)
							(mid 0.249642 0.249642)
							(end 0.2794 0.1778)
						)
						(arc
							(start 0.2794 -0.1778)
							(mid 0.249642 -0.249642)
							(end 0.1778 -0.2794)
						)
					)
					(width 0)
					(fill yes)
				)
			)
		)
		(pad "2" smd custom
			(at 0 0.4445)
			(size 0.1397 0.1397)
			(layers "F.Cu" "F.Mask" "F.Paste")
			(net "AGND_CURRENT_DPB")
			(options
				(clearance outline)
				(anchor circle)
			)
			(primitives
				(gr_poly
					(pts
						(arc
							(start -0.1778 -0.2794)
							(mid -0.249642 -0.249642)
							(end -0.2794 -0.1778)
						)
						(arc
							(start -0.2794 0.1778)
							(mid -0.249642 0.249642)
							(end -0.1778 0.2794)
						)
						(arc
							(start 0.1778 0.2794)
							(mid 0.249642 0.249642)
							(end 0.2794 0.1778)
						)
						(arc
							(start 0.2794 -0.1778)
							(mid 0.249642 -0.249642)
							(end 0.1778 -0.2794)
						)
					)
					(width 0)
					(fill yes)
				)
			)
		)
	)
	(footprint ""
		(layer "F.Cu")
		(at 141.097 -254.508 -90)
		(property "Reference" "R233"
			(at 0 0 270)
			(layer "F.SilkS")
			(hide yes)
			(effects
				(font
					(size 1.27 1.27)
				)
			)
		)
		(property "Value" "300KR2F-GP"
			(at 0.064008 -3.993896 270)
			(unlocked yes)
			(layer "F.Fab")
			(hide yes)
			(effects
				(font
					(size 1.016 1.016)
					(thickness 0.1524)
				)
			)
		)
		(property "Device Type" "R402H16"
			(at 0.064008 -5.517896 270)
			(unlocked yes)
			(layer "F.Fab")
			(hide yes)
			(effects
				(font
					(size 1.016 1.016)
					(thickness 0.1524)
				)
			)
		)
		(duplicate_pad_numbers_are_jumpers no)
		(fp_line
			(start -0.508 -0.9398)
			(end -0.508 0.9398)
			(stroke
				(width 0.1524)
				(type default)
			)
			(layer "F.SilkS")
		)
		(fp_line
			(start 0.508 -0.9398)
			(end -0.508 -0.9398)
			(stroke
				(width 0.1524)
				(type default)
			)
			(layer "F.SilkS")
		)
		(fp_rect
			(start -0.508 0.9398)
			(end 0.508 -0.9398)
			(stroke
				(width 0)
				(type default)
			)
			(fill no)
			(layer "F.CrtYd")
		)
		(fp_rect
			(start -0.508 0.9398)
			(end 0.508 -0.9398)
			(stroke
				(width 0)
				(type default)
			)
			(fill no)
			(layer "F.Fab")
		)
		(pad "1" smd custom
			(at 0 -0.4445 270)
			(size 0.1397 0.1397)
			(layers "F.Cu" "F.Mask" "F.Paste")
			(net "SW_HDD_N4")
			(options
				(clearance outline)
				(anchor circle)
			)
			(primitives
				(gr_poly
					(pts
						(arc
							(start -0.1778 -0.2794)
							(mid -0.249642 -0.249642)
							(end -0.2794 -0.1778)
						)
						(arc
							(start -0.2794 0.1778)
							(mid -0.249642 0.249642)
							(end -0.1778 0.2794)
						)
						(arc
							(start 0.1778 0.2794)
							(mid 0.249642 0.249642)
							(end 0.2794 0.1778)
						)
						(arc
							(start 0.2794 -0.1778)
							(mid 0.249642 -0.249642)
							(end 0.1778 -0.2794)
						)
					)
					(width 0)
					(fill yes)
				)
			)
		)
		(pad "2" smd custom
			(at 0 0.4445 270)
			(size 0.1397 0.1397)
			(layers "F.Cu" "F.Mask" "F.Paste")
			(net "P12V_B")
			(options
				(clearance outline)
				(anchor circle)
			)
			(primitives
				(gr_poly
					(pts
						(arc
							(start -0.1778 -0.2794)
							(mid -0.249642 -0.249642)
							(end -0.2794 -0.1778)
						)
						(arc
							(start -0.2794 0.1778)
							(mid -0.249642 0.249642)
							(end -0.1778 0.2794)
						)
						(arc
							(start 0.1778 0.2794)
							(mid 0.249642 0.249642)
							(end 0.2794 0.1778)
						)
						(arc
							(start 0.2794 -0.1778)
							(mid 0.249642 -0.249642)
							(end 0.1778 -0.2794)
						)
					)
					(width 0)
					(fill yes)
				)
			)
		)
	)
	(footprint ""
		(layer "F.Cu")
		(at 236.601 -223.52 90)
		(property "Reference" "C13"
			(at 0 0 90)
			(layer "F.SilkS")
			(hide yes)
			(effects
				(font
					(size 1.27 1.27)
				)
			)
		)
		(property "Value" "SC1U16V3KX-5GP"
			(at 0 -2.8194 90)
			(unlocked yes)
			(layer "F.Fab")
			(hide yes)
			(effects
				(font
					(size 1.016 1.016)
					(thickness 0.1524)
				)
			)
		)
		(property "Device Type" "C603H36"
			(at 0 -4.3434 90)
			(unlocked yes)
			(layer "F.Fab")
			(hide yes)
			(effects
				(font
					(size 1.016 1.016)
					(thickness 0.1524)
				)
			)
		)
		(duplicate_pad_numbers_are_jumpers no)
		(fp_line
			(start 0.508 0)
			(end -0.508 0)
			(stroke
				(width 0.2032)
				(type default)
			)
			(layer "F.SilkS")
		)
		(fp_rect
			(start -0.5842 1.3335)
			(end 0.5842 -1.3335)
			(stroke
				(width 0)
				(type default)
			)
			(fill no)
			(layer "F.CrtYd")
		)
		(fp_rect
			(start -0.5842 1.3335)
			(end 0.5842 -1.3335)
			(stroke
				(width 0)
				(type default)
			)
			(fill no)
			(layer "F.Fab")
		)
		(pad "1" smd custom
			(at 0 -0.762 90)
			(size 0.2159 0.2159)
			(layers "F.Cu" "F.Mask" "F.Paste")
			(net "GPIO_VCC_U8")
			(options
				(clearance outline)
				(anchor circle)
			)
			(primitives
				(gr_poly
					(pts
						(arc
							(start -0.3302 -0.4318)
							(mid -0.402042 -0.402042)
							(end -0.4318 -0.3302)
						)
						(arc
							(start -0.4318 0.3302)
							(mid -0.402042 0.402042)
							(end -0.3302 0.4318)
						)
						(arc
							(start 0.3302 0.4318)
							(mid 0.402042 0.402042)
							(end 0.4318 0.3302)
						)
						(arc
							(start 0.4318 -0.3302)
							(mid 0.402042 -0.402042)
							(end 0.3302 -0.4318)
						)
					)
					(width 0)
					(fill yes)
				)
			)
		)
		(pad "2" smd custom
			(at 0 0.762 90)
			(size 0.2159 0.2159)
			(layers "F.Cu" "F.Mask" "F.Paste")
			(net "GND")
			(options
				(clearance outline)
				(anchor circle)
			)
			(primitives
				(gr_poly
					(pts
						(arc
							(start -0.3302 -0.4318)
							(mid -0.402042 -0.402042)
							(end -0.4318 -0.3302)
						)
						(arc
							(start -0.4318 0.3302)
							(mid -0.402042 0.402042)
							(end -0.3302 0.4318)
						)
						(arc
							(start 0.3302 0.4318)
							(mid 0.402042 0.402042)
							(end 0.4318 0.3302)
						)
						(arc
							(start 0.4318 -0.3302)
							(mid 0.402042 -0.402042)
							(end 0.3302 -0.4318)
						)
					)
					(width 0)
					(fill yes)
				)
			)
		)
	)
	(footprint ""
		(layer "F.Cu")
		(at 470.281 -133.858 -90)
		(property "Reference" "R616"
			(at 0 0 270)
			(layer "F.SilkS")
			(hide yes)
			(effects
				(font
					(size 1.27 1.27)
				)
			)
		)
		(property "Value" "0R2J-2-GP"
			(at 0.064008 -3.993896 270)
			(unlocked yes)
			(layer "F.Fab")
			(hide yes)
			(effects
				(font
					(size 1.016 1.016)
					(thickness 0.1524)
				)
			)
		)
		(property "Device Type" "R402H16"
			(at 0.064008 -5.517896 270)
			(unlocked yes)
			(layer "F.Fab")
			(hide yes)
			(effects
				(font
					(size 1.016 1.016)
					(thickness 0.1524)
				)
			)
		)
		(duplicate_pad_numbers_are_jumpers no)
		(fp_line
			(start -0.508 -0.9398)
			(end -0.508 0.9398)
			(stroke
				(width 0.1524)
				(type default)
			)
			(layer "F.SilkS")
		)
		(fp_line
			(start 0.508 -0.9398)
			(end -0.508 -0.9398)
			(stroke
				(width 0.1524)
				(type default)
			)
			(layer "F.SilkS")
		)
		(fp_rect
			(start -0.508 0.9398)
			(end 0.508 -0.9398)
			(stroke
				(width 0)
				(type default)
			)
			(fill no)
			(layer "F.CrtYd")
		)
		(fp_rect
			(start -0.508 0.9398)
			(end 0.508 -0.9398)
			(stroke
				(width 0)
				(type default)
			)
			(fill no)
			(layer "F.Fab")
		)
		(pad "1" smd custom
			(at 0 -0.4445 270)
			(size 0.1397 0.1397)
			(layers "F.Cu" "F.Mask" "F.Paste")
			(net "SW_HDD_G23")
			(options
				(clearance outline)
				(anchor circle)
			)
			(primitives
				(gr_poly
					(pts
						(arc
							(start -0.1778 -0.2794)
							(mid -0.249642 -0.249642)
							(end -0.2794 -0.1778)
						)
						(arc
							(start -0.2794 0.1778)
							(mid -0.249642 0.249642)
							(end -0.1778 0.2794)
						)
						(arc
							(start 0.1778 0.2794)
							(mid 0.249642 0.249642)
							(end 0.2794 0.1778)
						)
						(arc
							(start 0.2794 -0.1778)
							(mid 0.249642 -0.249642)
							(end 0.1778 -0.2794)
						)
					)
					(width 0)
					(fill yes)
				)
			)
		)
		(pad "2" smd custom
			(at 0 0.4445 270)
			(size 0.1397 0.1397)
			(layers "F.Cu" "F.Mask" "F.Paste")
			(net "SW_HDD_R23")
			(options
				(clearance outline)
				(anchor circle)
			)
			(primitives
				(gr_poly
					(pts
						(arc
							(start -0.1778 -0.2794)
							(mid -0.249642 -0.249642)
							(end -0.2794 -0.1778)
						)
						(arc
							(start -0.2794 0.1778)
							(mid -0.249642 0.249642)
							(end -0.1778 0.2794)
						)
						(arc
							(start 0.1778 0.2794)
							(mid 0.249642 0.249642)
							(end 0.2794 0.1778)
						)
						(arc
							(start 0.2794 -0.1778)
							(mid 0.249642 -0.249642)
							(end 0.1778 -0.2794)
						)
					)
					(width 0)
					(fill yes)
				)
			)
		)
	)
	(footprint ""
		(layer "F.Cu")
		(at 172.593 -254.508 -90)
		(property "Reference" "R249"
			(at 0 0 270)
			(layer "F.SilkS")
			(hide yes)
			(effects
				(font
					(size 1.27 1.27)
				)
			)
		)
		(property "Value" "300KR2F-GP"
			(at 0.064008 -3.993896 270)
			(unlocked yes)
			(layer "F.Fab")
			(hide yes)
			(effects
				(font
					(size 1.016 1.016)
					(thickness 0.1524)
				)
			)
		)
		(property "Device Type" "R402H16"
			(at 0.064008 -5.517896 270)
			(unlocked yes)
			(layer "F.Fab")
			(hide yes)
			(effects
				(font
					(size 1.016 1.016)
					(thickness 0.1524)
				)
			)
		)
		(duplicate_pad_numbers_are_jumpers no)
		(fp_line
			(start -0.508 -0.9398)
			(end -0.508 0.9398)
			(stroke
				(width 0.1524)
				(type default)
			)
			(layer "F.SilkS")
		)
		(fp_line
			(start 0.508 -0.9398)
			(end -0.508 -0.9398)
			(stroke
				(width 0.1524)
				(type default)
			)
			(layer "F.SilkS")
		)
		(fp_rect
			(start -0.508 0.9398)
			(end 0.508 -0.9398)
			(stroke
				(width 0)
				(type default)
			)
			(fill no)
			(layer "F.CrtYd")
		)
		(fp_rect
			(start -0.508 0.9398)
			(end 0.508 -0.9398)
			(stroke
				(width 0)
				(type default)
			)
			(fill no)
			(layer "F.Fab")
		)
		(pad "1" smd custom
			(at 0 -0.4445 270)
			(size 0.1397 0.1397)
			(layers "F.Cu" "F.Mask" "F.Paste")
			(net "SW_HDD_N5")
			(options
				(clearance outline)
				(anchor circle)
			)
			(primitives
				(gr_poly
					(pts
						(arc
							(start -0.1778 -0.2794)
							(mid -0.249642 -0.249642)
							(end -0.2794 -0.1778)
						)
						(arc
							(start -0.2794 0.1778)
							(mid -0.249642 0.249642)
							(end -0.1778 0.2794)
						)
						(arc
							(start 0.1778 0.2794)
							(mid 0.249642 0.249642)
							(end 0.2794 0.1778)
						)
						(arc
							(start 0.2794 -0.1778)
							(mid 0.249642 -0.249642)
							(end 0.1778 -0.2794)
						)
					)
					(width 0)
					(fill yes)
				)
			)
		)
		(pad "2" smd custom
			(at 0 0.4445 270)
			(size 0.1397 0.1397)
			(layers "F.Cu" "F.Mask" "F.Paste")
			(net "P12V_B")
			(options
				(clearance outline)
				(anchor circle)
			)
			(primitives
				(gr_poly
					(pts
						(arc
							(start -0.1778 -0.2794)
							(mid -0.249642 -0.249642)
							(end -0.2794 -0.1778)
						)
						(arc
							(start -0.2794 0.1778)
							(mid -0.249642 0.249642)
							(end -0.1778 0.2794)
						)
						(arc
							(start 0.1778 0.2794)
							(mid 0.249642 0.249642)
							(end 0.2794 0.1778)
						)
						(arc
							(start 0.2794 -0.1778)
							(mid 0.249642 -0.249642)
							(end 0.1778 -0.2794)
						)
					)
					(width 0)
					(fill yes)
				)
			)
		)
	)
	(footprint ""
		(layer "F.Cu")
		(at 178.816 -19.177 180)
		(property "Reference" "R750"
			(at 0 0 180)
			(layer "F.SilkS")
			(hide yes)
			(effects
				(font
					(size 1.27 1.27)
				)
			)
		)
		(property "Value" "4K7R2F-GP"
			(at 0.064008 -3.993896 180)
			(unlocked yes)
			(layer "F.Fab")
			(hide yes)
			(effects
				(font
					(size 1.016 1.016)
					(thickness 0.1524)
				)
			)
		)
		(property "Device Type" "R402H16"
			(at 0.064008 -5.517896 180)
			(unlocked yes)
			(layer "F.Fab")
			(hide yes)
			(effects
				(font
					(size 1.016 1.016)
					(thickness 0.1524)
				)
			)
		)
		(duplicate_pad_numbers_are_jumpers no)
		(fp_line
			(start 0.508 -0.9398)
			(end -0.508 -0.9398)
			(stroke
				(width 0.1524)
				(type default)
			)
			(layer "F.SilkS")
		)
		(fp_line
			(start -0.508 -0.9398)
			(end -0.508 0.9398)
			(stroke
				(width 0.1524)
				(type default)
			)
			(layer "F.SilkS")
		)
		(fp_rect
			(start -0.508 0.9398)
			(end 0.508 -0.9398)
			(stroke
				(width 0)
				(type default)
			)
			(fill no)
			(layer "F.CrtYd")
		)
		(fp_rect
			(start -0.508 0.9398)
			(end 0.508 -0.9398)
			(stroke
				(width 0)
				(type default)
			)
			(fill no)
			(layer "F.Fab")
		)
		(pad "1" smd custom
			(at 0 -0.4445 180)
			(size 0.1397 0.1397)
			(layers "F.Cu" "F.Mask" "F.Paste")
			(net "SW_PWR_R_HDD29")
			(options
				(clearance outline)
				(anchor circle)
			)
			(primitives
				(gr_poly
					(pts
						(arc
							(start -0.1778 -0.2794)
							(mid -0.249642 -0.249642)
							(end -0.2794 -0.1778)
						)
						(arc
							(start -0.2794 0.1778)
							(mid -0.249642 0.249642)
							(end -0.1778 0.2794)
						)
						(arc
							(start 0.1778 0.2794)
							(mid 0.249642 0.249642)
							(end 0.2794 0.1778)
						)
						(arc
							(start 0.2794 -0.1778)
							(mid 0.249642 -0.249642)
							(end 0.1778 -0.2794)
						)
					)
					(width 0)
					(fill yes)
				)
			)
		)
		(pad "2" smd custom
			(at 0 0.4445 180)
			(size 0.1397 0.1397)
			(layers "F.Cu" "F.Mask" "F.Paste")
			(net "GND")
			(options
				(clearance outline)
				(anchor circle)
			)
			(primitives
				(gr_poly
					(pts
						(arc
							(start -0.1778 -0.2794)
							(mid -0.249642 -0.249642)
							(end -0.2794 -0.1778)
						)
						(arc
							(start -0.2794 0.1778)
							(mid -0.249642 0.249642)
							(end -0.1778 0.2794)
						)
						(arc
							(start 0.1778 0.2794)
							(mid 0.249642 0.249642)
							(end 0.2794 0.1778)
						)
						(arc
							(start 0.2794 -0.1778)
							(mid 0.249642 -0.249642)
							(end 0.1778 -0.2794)
						)
					)
					(width 0)
					(fill yes)
				)
			)
		)
	)
	(footprint ""
		(layer "F.Cu")
		(at 338.709 -142.875 -90)
		(property "Reference" "R499"
			(at 0 0 270)
			(layer "F.SilkS")
			(hide yes)
			(effects
				(font
					(size 1.27 1.27)
				)
			)
		)
		(property "Value" "300KR2F-GP"
			(at 0.064008 -3.993896 270)
			(unlocked yes)
			(layer "F.Fab")
			(hide yes)
			(effects
				(font
					(size 1.016 1.016)
					(thickness 0.1524)
				)
			)
		)
		(property "Device Type" "R402H16"
			(at 0.064008 -5.517896 270)
			(unlocked yes)
			(layer "F.Fab")
			(hide yes)
			(effects
				(font
					(size 1.016 1.016)
					(thickness 0.1524)
				)
			)
		)
		(duplicate_pad_numbers_are_jumpers no)
		(fp_line
			(start -0.508 -0.9398)
			(end -0.508 0.9398)
			(stroke
				(width 0.1524)
				(type default)
			)
			(layer "F.SilkS")
		)
		(fp_line
			(start 0.508 -0.9398)
			(end -0.508 -0.9398)
			(stroke
				(width 0.1524)
				(type default)
			)
			(layer "F.SilkS")
		)
		(fp_rect
			(start -0.508 0.9398)
			(end 0.508 -0.9398)
			(stroke
				(width 0)
				(type default)
			)
			(fill no)
			(layer "F.CrtYd")
		)
		(fp_rect
			(start -0.508 0.9398)
			(end 0.508 -0.9398)
			(stroke
				(width 0)
				(type default)
			)
			(fill no)
			(layer "F.Fab")
		)
		(pad "1" smd custom
			(at 0 -0.4445 270)
			(size 0.1397 0.1397)
			(layers "F.Cu" "F.Mask" "F.Paste")
			(net "SW_HDD_N18")
			(options
				(clearance outline)
				(anchor circle)
			)
			(primitives
				(gr_poly
					(pts
						(arc
							(start -0.1778 -0.2794)
							(mid -0.249642 -0.249642)
							(end -0.2794 -0.1778)
						)
						(arc
							(start -0.2794 0.1778)
							(mid -0.249642 0.249642)
							(end -0.1778 0.2794)
						)
						(arc
							(start 0.1778 0.2794)
							(mid 0.249642 0.249642)
							(end 0.2794 0.1778)
						)
						(arc
							(start 0.2794 -0.1778)
							(mid 0.249642 -0.249642)
							(end 0.1778 -0.2794)
						)
					)
					(width 0)
					(fill yes)
				)
			)
		)
		(pad "2" smd custom
			(at 0 0.4445 270)
			(size 0.1397 0.1397)
			(layers "F.Cu" "F.Mask" "F.Paste")
			(net "P12V_B")
			(options
				(clearance outline)
				(anchor circle)
			)
			(primitives
				(gr_poly
					(pts
						(arc
							(start -0.1778 -0.2794)
							(mid -0.249642 -0.249642)
							(end -0.2794 -0.1778)
						)
						(arc
							(start -0.2794 0.1778)
							(mid -0.249642 0.249642)
							(end -0.1778 0.2794)
						)
						(arc
							(start 0.1778 0.2794)
							(mid 0.249642 0.249642)
							(end 0.2794 0.1778)
						)
						(arc
							(start 0.2794 -0.1778)
							(mid 0.249642 -0.249642)
							(end 0.1778 -0.2794)
						)
					)
					(width 0)
					(fill yes)
				)
			)
		)
	)
	(footprint ""
		(layer "F.Cu")
		(at 399.288 -13.335 180)
		(property "Reference" "R819"
			(at 0 0 180)
			(layer "F.SilkS")
			(hide yes)
			(effects
				(font
					(size 1.27 1.27)
				)
			)
		)
		(property "Value" "4K7R2J-2-GP"
			(at 0.064008 -3.993896 180)
			(unlocked yes)
			(layer "F.Fab")
			(hide yes)
			(effects
				(font
					(size 1.016 1.016)
					(thickness 0.1524)
				)
			)
		)
		(property "Device Type" "R402H16"
			(at 0.064008 -5.517896 180)
			(unlocked yes)
			(layer "F.Fab")
			(hide yes)
			(effects
				(font
					(size 1.016 1.016)
					(thickness 0.1524)
				)
			)
		)
		(duplicate_pad_numbers_are_jumpers no)
		(fp_line
			(start 0.508 -0.9398)
			(end -0.508 -0.9398)
			(stroke
				(width 0.1524)
				(type default)
			)
			(layer "F.SilkS")
		)
		(fp_line
			(start -0.508 -0.9398)
			(end -0.508 0.9398)
			(stroke
				(width 0.1524)
				(type default)
			)
			(layer "F.SilkS")
		)
		(fp_rect
			(start -0.508 0.9398)
			(end 0.508 -0.9398)
			(stroke
				(width 0)
				(type default)
			)
			(fill no)
			(layer "F.CrtYd")
		)
		(fp_rect
			(start -0.508 0.9398)
			(end 0.508 -0.9398)
			(stroke
				(width 0)
				(type default)
			)
			(fill no)
			(layer "F.Fab")
		)
		(pad "1" smd custom
			(at 0 -0.4445 180)
			(size 0.1397 0.1397)
			(layers "F.Cu" "F.Mask" "F.Paste")
			(net "P12V_B")
			(options
				(clearance outline)
				(anchor circle)
			)
			(primitives
				(gr_poly
					(pts
						(arc
							(start -0.1778 -0.2794)
							(mid -0.249642 -0.249642)
							(end -0.2794 -0.1778)
						)
						(arc
							(start -0.2794 0.1778)
							(mid -0.249642 0.249642)
							(end -0.1778 0.2794)
						)
						(arc
							(start 0.1778 0.2794)
							(mid 0.249642 0.249642)
							(end 0.2794 0.1778)
						)
						(arc
							(start 0.2794 -0.1778)
							(mid 0.249642 -0.249642)
							(end 0.1778 -0.2794)
						)
					)
					(width 0)
					(fill yes)
				)
			)
		)
		(pad "2" smd custom
			(at 0 0.4445 180)
			(size 0.1397 0.1397)
			(layers "F.Cu" "F.Mask" "F.Paste")
			(net "SW_HDD_R32")
			(options
				(clearance outline)
				(anchor circle)
			)
			(primitives
				(gr_poly
					(pts
						(arc
							(start -0.1778 -0.2794)
							(mid -0.249642 -0.249642)
							(end -0.2794 -0.1778)
						)
						(arc
							(start -0.2794 0.1778)
							(mid -0.249642 0.249642)
							(end -0.1778 0.2794)
						)
						(arc
							(start 0.1778 0.2794)
							(mid 0.249642 0.249642)
							(end 0.2794 0.1778)
						)
						(arc
							(start 0.2794 -0.1778)
							(mid 0.249642 -0.249642)
							(end 0.1778 -0.2794)
						)
					)
					(width 0)
					(fill yes)
				)
			)
		)
	)
	(footprint ""
		(layer "F.Cu")
		(at 115.316 -20.0406 180)
		(property "Reference" "R703"
			(at 0 0 180)
			(layer "F.SilkS")
			(hide yes)
			(effects
				(font
					(size 1.27 1.27)
				)
			)
		)
		(property "Value" "4K7R2F-GP"
			(at 0.064008 -3.993896 180)
			(unlocked yes)
			(layer "F.Fab")
			(hide yes)
			(effects
				(font
					(size 1.016 1.016)
					(thickness 0.1524)
				)
			)
		)
		(property "Device Type" "R402H16"
			(at 0.064008 -5.517896 180)
			(unlocked yes)
			(layer "F.Fab")
			(hide yes)
			(effects
				(font
					(size 1.016 1.016)
					(thickness 0.1524)
				)
			)
		)
		(duplicate_pad_numbers_are_jumpers no)
		(fp_line
			(start 0.508 -0.9398)
			(end -0.508 -0.9398)
			(stroke
				(width 0.1524)
				(type default)
			)
			(layer "F.SilkS")
		)
		(fp_line
			(start -0.508 -0.9398)
			(end -0.508 0.9398)
			(stroke
				(width 0.1524)
				(type default)
			)
			(layer "F.SilkS")
		)
		(fp_rect
			(start -0.508 0.9398)
			(end 0.508 -0.9398)
			(stroke
				(width 0)
				(type default)
			)
			(fill no)
			(layer "F.CrtYd")
		)
		(fp_rect
			(start -0.508 0.9398)
			(end 0.508 -0.9398)
			(stroke
				(width 0)
				(type default)
			)
			(fill no)
			(layer "F.Fab")
		)
		(pad "1" smd custom
			(at 0 -0.4445 180)
			(size 0.1397 0.1397)
			(layers "F.Cu" "F.Mask" "F.Paste")
			(net "SW_PWR_R_HDD27")
			(options
				(clearance outline)
				(anchor circle)
			)
			(primitives
				(gr_poly
					(pts
						(arc
							(start -0.1778 -0.2794)
							(mid -0.249642 -0.249642)
							(end -0.2794 -0.1778)
						)
						(arc
							(start -0.2794 0.1778)
							(mid -0.249642 0.249642)
							(end -0.1778 0.2794)
						)
						(arc
							(start 0.1778 0.2794)
							(mid 0.249642 0.249642)
							(end 0.2794 0.1778)
						)
						(arc
							(start 0.2794 -0.1778)
							(mid 0.249642 -0.249642)
							(end 0.1778 -0.2794)
						)
					)
					(width 0)
					(fill yes)
				)
			)
		)
		(pad "2" smd custom
			(at 0 0.4445 180)
			(size 0.1397 0.1397)
			(layers "F.Cu" "F.Mask" "F.Paste")
			(net "GND")
			(options
				(clearance outline)
				(anchor circle)
			)
			(primitives
				(gr_poly
					(pts
						(arc
							(start -0.1778 -0.2794)
							(mid -0.249642 -0.249642)
							(end -0.2794 -0.1778)
						)
						(arc
							(start -0.2794 0.1778)
							(mid -0.249642 0.249642)
							(end -0.1778 0.2794)
						)
						(arc
							(start 0.1778 0.2794)
							(mid 0.249642 0.249642)
							(end 0.2794 0.1778)
						)
						(arc
							(start 0.2794 -0.1778)
							(mid 0.249642 -0.249642)
							(end 0.1778 -0.2794)
						)
					)
					(width 0)
					(fill yes)
				)
			)
		)
	)
	(footprint ""
		(layer "F.Cu")
		(at 456.3618 -229.50932 180)
		(property "Reference" "R1153"
			(at 0 0 180)
			(layer "F.SilkS")
			(hide yes)
			(effects
				(font
					(size 1.27 1.27)
				)
			)
		)
		(property "Value" "0R2J-2-GP"
			(at 0.064008 -3.993896 180)
			(unlocked yes)
			(layer "F.Fab")
			(hide yes)
			(effects
				(font
					(size 1.016 1.016)
					(thickness 0.1524)
				)
			)
		)
		(property "Device Type" "R402H16"
			(at 0.064008 -5.517896 180)
			(unlocked yes)
			(layer "F.Fab")
			(hide yes)
			(effects
				(font
					(size 1.016 1.016)
					(thickness 0.1524)
				)
			)
		)
		(duplicate_pad_numbers_are_jumpers no)
		(fp_line
			(start 0.508 -0.9398)
			(end -0.508 -0.9398)
			(stroke
				(width 0.1524)
				(type default)
			)
			(layer "F.SilkS")
		)
		(fp_line
			(start -0.508 -0.9398)
			(end -0.508 0.9398)
			(stroke
				(width 0.1524)
				(type default)
			)
			(layer "F.SilkS")
		)
		(fp_rect
			(start -0.508 0.9398)
			(end 0.508 -0.9398)
			(stroke
				(width 0)
				(type default)
			)
			(fill no)
			(layer "F.CrtYd")
		)
		(fp_rect
			(start -0.508 0.9398)
			(end 0.508 -0.9398)
			(stroke
				(width 0)
				(type default)
			)
			(fill no)
			(layer "F.Fab")
		)
		(pad "1" smd custom
			(at 0 -0.4445 180)
			(size 0.1397 0.1397)
			(layers "F.Cu" "F.Mask" "F.Paste")
			(net "P5V_B_3_ROVP")
			(options
				(clearance outline)
				(anchor circle)
			)
			(primitives
				(gr_poly
					(pts
						(arc
							(start -0.1778 -0.2794)
							(mid -0.249642 -0.249642)
							(end -0.2794 -0.1778)
						)
						(arc
							(start -0.2794 0.1778)
							(mid -0.249642 0.249642)
							(end -0.1778 0.2794)
						)
						(arc
							(start 0.1778 0.2794)
							(mid 0.249642 0.249642)
							(end 0.2794 0.1778)
						)
						(arc
							(start 0.2794 -0.1778)
							(mid 0.249642 -0.249642)
							(end 0.1778 -0.2794)
						)
					)
					(width 0)
					(fill yes)
				)
			)
		)
		(pad "2" smd custom
			(at 0 0.4445 180)
			(size 0.1397 0.1397)
			(layers "F.Cu" "F.Mask" "F.Paste")
			(net "AGND_P5V_B_3")
			(options
				(clearance outline)
				(anchor circle)
			)
			(primitives
				(gr_poly
					(pts
						(arc
							(start -0.1778 -0.2794)
							(mid -0.249642 -0.249642)
							(end -0.2794 -0.1778)
						)
						(arc
							(start -0.2794 0.1778)
							(mid -0.249642 0.249642)
							(end -0.1778 0.2794)
						)
						(arc
							(start 0.1778 0.2794)
							(mid 0.249642 0.249642)
							(end 0.2794 0.1778)
						)
						(arc
							(start 0.2794 -0.1778)
							(mid 0.249642 -0.249642)
							(end 0.1778 -0.2794)
						)
					)
					(width 0)
					(fill yes)
				)
			)
		)
	)
	(footprint ""
		(layer "F.Cu")
		(at 239.780064 -367.607088)
		(property "Reference" "R1025"
			(at 0 0 0)
			(layer "F.SilkS")
			(hide yes)
			(effects
				(font
					(size 1.27 1.27)
				)
			)
		)
		(property "Value" "100R2D-GP"
			(at 0.064008 -3.993896 0)
			(unlocked yes)
			(layer "F.Fab")
			(hide yes)
			(effects
				(font
					(size 1.016 1.016)
					(thickness 0.1524)
				)
			)
		)
		(property "Device Type" "R402H14"
			(at 0.064008 -5.517896 0)
			(unlocked yes)
			(layer "F.Fab")
			(hide yes)
			(effects
				(font
					(size 1.016 1.016)
					(thickness 0.1524)
				)
			)
		)
		(duplicate_pad_numbers_are_jumpers no)
		(fp_line
			(start -0.508 -0.9398)
			(end -0.508 0.9398)
			(stroke
				(width 0.1524)
				(type default)
			)
			(layer "F.SilkS")
		)
		(fp_line
			(start 0.508 -0.9398)
			(end -0.508 -0.9398)
			(stroke
				(width 0.1524)
				(type default)
			)
			(layer "F.SilkS")
		)
		(fp_rect
			(start -0.508 0.9398)
			(end 0.508 -0.9398)
			(stroke
				(width 0)
				(type default)
			)
			(fill no)
			(layer "F.CrtYd")
		)
		(fp_rect
			(start -0.508 0.9398)
			(end 0.508 -0.9398)
			(stroke
				(width 0)
				(type default)
			)
			(fill no)
			(layer "F.Fab")
		)
		(pad "1" smd custom
			(at 0 -0.4445)
			(size 0.1397 0.1397)
			(layers "F.Cu" "F.Mask" "F.Paste")
			(net "GND")
			(options
				(clearance outline)
				(anchor circle)
			)
			(primitives
				(gr_poly
					(pts
						(arc
							(start -0.1778 -0.2794)
							(mid -0.249642 -0.249642)
							(end -0.2794 -0.1778)
						)
						(arc
							(start -0.2794 0.1778)
							(mid -0.249642 0.249642)
							(end -0.1778 0.2794)
						)
						(arc
							(start 0.1778 0.2794)
							(mid 0.249642 0.249642)
							(end 0.2794 0.1778)
						)
						(arc
							(start 0.2794 -0.1778)
							(mid 0.249642 -0.249642)
							(end 0.1778 -0.2794)
						)
					)
					(width 0)
					(fill yes)
				)
			)
		)
		(pad "2" smd custom
			(at 0 0.4445)
			(size 0.1397 0.1397)
			(layers "F.Cu" "F.Mask" "F.Paste")
			(net "MB3_TEMP_E")
			(options
				(clearance outline)
				(anchor circle)
			)
			(primitives
				(gr_poly
					(pts
						(arc
							(start -0.1778 -0.2794)
							(mid -0.249642 -0.249642)
							(end -0.2794 -0.1778)
						)
						(arc
							(start -0.2794 0.1778)
							(mid -0.249642 0.249642)
							(end -0.1778 0.2794)
						)
						(arc
							(start 0.1778 0.2794)
							(mid 0.249642 0.249642)
							(end 0.2794 0.1778)
						)
						(arc
							(start 0.2794 -0.1778)
							(mid 0.249642 -0.249642)
							(end 0.1778 -0.2794)
						)
					)
					(width 0)
					(fill yes)
				)
			)
		)
	)
	(footprint ""
		(layer "F.Cu")
		(at 111.76 -99.314)
		(property "Reference" "R410"
			(at 0 0 0)
			(layer "F.SilkS")
			(hide yes)
			(effects
				(font
					(size 1.27 1.27)
				)
			)
		)
		(property "Value" "130R3F-GP"
			(at -0.0254 -2.5146 0)
			(unlocked yes)
			(layer "F.Fab")
			(hide yes)
			(effects
				(font
					(size 1.016 1.016)
					(thickness 0.1524)
				)
			)
		)
		(property "Device Type" "R603H22"
			(at -0.0254 -4.0386 0)
			(unlocked yes)
			(layer "F.Fab")
			(hide yes)
			(effects
				(font
					(size 1.016 1.016)
					(thickness 0.1524)
				)
			)
		)
		(duplicate_pad_numbers_are_jumpers no)
		(fp_line
			(start -0.4826 0)
			(end -0.2032 0)
			(stroke
				(width 0.2032)
				(type default)
			)
			(layer "F.SilkS")
		)
		(fp_line
			(start 0.2032 0)
			(end 0.4826 0)
			(stroke
				(width 0.2032)
				(type default)
			)
			(layer "F.SilkS")
		)
		(fp_rect
			(start -0.5842 1.3335)
			(end 0.5842 -1.3335)
			(stroke
				(width 0)
				(type default)
			)
			(fill no)
			(layer "F.CrtYd")
		)
		(fp_rect
			(start -0.5842 1.3335)
			(end 0.5842 -1.3335)
			(stroke
				(width 0)
				(type default)
			)
			(fill no)
			(layer "F.Fab")
		)
		(pad "1" smd custom
			(at 0 -0.762)
			(size 0.2159 0.2159)
			(layers "F.Cu" "F.Mask" "F.Paste")
			(net "P5V_B_2")
			(options
				(clearance outline)
				(anchor circle)
			)
			(primitives
				(gr_poly
					(pts
						(arc
							(start -0.3302 -0.4318)
							(mid -0.402042 -0.402042)
							(end -0.4318 -0.3302)
						)
						(arc
							(start -0.4318 0.3302)
							(mid -0.402042 0.402042)
							(end -0.3302 0.4318)
						)
						(arc
							(start 0.3302 0.4318)
							(mid 0.402042 0.402042)
							(end 0.4318 0.3302)
						)
						(arc
							(start 0.4318 -0.3302)
							(mid 0.402042 -0.402042)
							(end 0.3302 -0.4318)
						)
					)
					(width 0)
					(fill yes)
				)
			)
		)
		(pad "2" smd custom
			(at 0 0.762)
			(size 0.2159 0.2159)
			(layers "F.Cu" "F.Mask" "F.Paste")
			(net "FLT_HDD15")
			(options
				(clearance outline)
				(anchor circle)
			)
			(primitives
				(gr_poly
					(pts
						(arc
							(start -0.3302 -0.4318)
							(mid -0.402042 -0.402042)
							(end -0.4318 -0.3302)
						)
						(arc
							(start -0.4318 0.3302)
							(mid -0.402042 0.402042)
							(end -0.3302 0.4318)
						)
						(arc
							(start 0.3302 0.4318)
							(mid 0.402042 0.402042)
							(end 0.4318 0.3302)
						)
						(arc
							(start 0.4318 -0.3302)
							(mid 0.402042 -0.402042)
							(end 0.3302 -0.4318)
						)
					)
					(width 0)
					(fill yes)
				)
			)
		)
	)
	(footprint ""
		(layer "F.Cu")
		(at 260.462522 -368.655346 90)
		(property "Reference" "R1028"
			(at 0 0 90)
			(layer "F.SilkS")
			(hide yes)
			(effects
				(font
					(size 1.27 1.27)
				)
			)
		)
		(property "Value" "0R2J-2-GP"
			(at 0.064008 -3.993896 90)
			(unlocked yes)
			(layer "F.Fab")
			(hide yes)
			(effects
				(font
					(size 1.016 1.016)
					(thickness 0.1524)
				)
			)
		)
		(property "Device Type" "R402H16"
			(at 0.064008 -5.517896 90)
			(unlocked yes)
			(layer "F.Fab")
			(hide yes)
			(effects
				(font
					(size 1.016 1.016)
					(thickness 0.1524)
				)
			)
		)
		(duplicate_pad_numbers_are_jumpers no)
		(fp_line
			(start 0.508 -0.9398)
			(end -0.508 -0.9398)
			(stroke
				(width 0.1524)
				(type default)
			)
			(layer "F.SilkS")
		)
		(fp_line
			(start -0.508 -0.9398)
			(end -0.508 0.9398)
			(stroke
				(width 0.1524)
				(type default)
			)
			(layer "F.SilkS")
		)
		(fp_rect
			(start -0.508 0.9398)
			(end 0.508 -0.9398)
			(stroke
				(width 0)
				(type default)
			)
			(fill no)
			(layer "F.CrtYd")
		)
		(fp_rect
			(start -0.508 0.9398)
			(end 0.508 -0.9398)
			(stroke
				(width 0)
				(type default)
			)
			(fill no)
			(layer "F.Fab")
		)
		(pad "1" smd custom
			(at 0 -0.4445 90)
			(size 0.1397 0.1397)
			(layers "F.Cu" "F.Mask" "F.Paste")
			(net "MB3_SDA_R")
			(options
				(clearance outline)
				(anchor circle)
			)
			(primitives
				(gr_poly
					(pts
						(arc
							(start -0.1778 -0.2794)
							(mid -0.249642 -0.249642)
							(end -0.2794 -0.1778)
						)
						(arc
							(start -0.2794 0.1778)
							(mid -0.249642 0.249642)
							(end -0.1778 0.2794)
						)
						(arc
							(start 0.1778 0.2794)
							(mid 0.249642 0.249642)
							(end 0.2794 0.1778)
						)
						(arc
							(start 0.2794 -0.1778)
							(mid 0.249642 -0.249642)
							(end 0.1778 -0.2794)
						)
					)
					(width 0)
					(fill yes)
				)
			)
		)
		(pad "2" smd custom
			(at 0 0.4445 90)
			(size 0.1397 0.1397)
			(layers "F.Cu" "F.Mask" "F.Paste")
			(net "I2C_DPB_B_SDA_BUF")
			(options
				(clearance outline)
				(anchor circle)
			)
			(primitives
				(gr_poly
					(pts
						(arc
							(start -0.1778 -0.2794)
							(mid -0.249642 -0.249642)
							(end -0.2794 -0.1778)
						)
						(arc
							(start -0.2794 0.1778)
							(mid -0.249642 0.249642)
							(end -0.1778 0.2794)
						)
						(arc
							(start 0.1778 0.2794)
							(mid 0.249642 0.249642)
							(end 0.2794 0.1778)
						)
						(arc
							(start 0.2794 -0.1778)
							(mid 0.249642 -0.249642)
							(end 0.1778 -0.2794)
						)
					)
					(width 0)
					(fill yes)
				)
			)
		)
	)
	(footprint ""
		(layer "F.Cu")
		(at 78.359 -133.096 180)
		(property "Reference" "R408"
			(at 0 0 180)
			(layer "F.SilkS")
			(hide yes)
			(effects
				(font
					(size 1.27 1.27)
				)
			)
		)
		(property "Value" "200KR2F-L-GP"
			(at 0.064008 -3.993896 180)
			(unlocked yes)
			(layer "F.Fab")
			(hide yes)
			(effects
				(font
					(size 1.016 1.016)
					(thickness 0.1524)
				)
			)
		)
		(property "Device Type" "R402H16"
			(at 0.064008 -5.517896 180)
			(unlocked yes)
			(layer "F.Fab")
			(hide yes)
			(effects
				(font
					(size 1.016 1.016)
					(thickness 0.1524)
				)
			)
		)
		(duplicate_pad_numbers_are_jumpers no)
		(fp_line
			(start 0.508 -0.9398)
			(end -0.508 -0.9398)
			(stroke
				(width 0.1524)
				(type default)
			)
			(layer "F.SilkS")
		)
		(fp_line
			(start -0.508 -0.9398)
			(end -0.508 0.9398)
			(stroke
				(width 0.1524)
				(type default)
			)
			(layer "F.SilkS")
		)
		(fp_rect
			(start -0.508 0.9398)
			(end 0.508 -0.9398)
			(stroke
				(width 0)
				(type default)
			)
			(fill no)
			(layer "F.CrtYd")
		)
		(fp_rect
			(start -0.508 0.9398)
			(end 0.508 -0.9398)
			(stroke
				(width 0)
				(type default)
			)
			(fill no)
			(layer "F.Fab")
		)
		(pad "1" smd custom
			(at 0 -0.4445 180)
			(size 0.1397 0.1397)
			(layers "F.Cu" "F.Mask" "F.Paste")
			(net "SW_HDD_R14")
			(options
				(clearance outline)
				(anchor circle)
			)
			(primitives
				(gr_poly
					(pts
						(arc
							(start -0.1778 -0.2794)
							(mid -0.249642 -0.249642)
							(end -0.2794 -0.1778)
						)
						(arc
							(start -0.2794 0.1778)
							(mid -0.249642 0.249642)
							(end -0.1778 0.2794)
						)
						(arc
							(start 0.1778 0.2794)
							(mid 0.249642 0.249642)
							(end 0.2794 0.1778)
						)
						(arc
							(start 0.2794 -0.1778)
							(mid 0.249642 -0.249642)
							(end 0.1778 -0.2794)
						)
					)
					(width 0)
					(fill yes)
				)
			)
		)
		(pad "2" smd custom
			(at 0 0.4445 180)
			(size 0.1397 0.1397)
			(layers "F.Cu" "F.Mask" "F.Paste")
			(net "SW_HDD_N14")
			(options
				(clearance outline)
				(anchor circle)
			)
			(primitives
				(gr_poly
					(pts
						(arc
							(start -0.1778 -0.2794)
							(mid -0.249642 -0.249642)
							(end -0.2794 -0.1778)
						)
						(arc
							(start -0.2794 0.1778)
							(mid -0.249642 0.249642)
							(end -0.1778 0.2794)
						)
						(arc
							(start 0.1778 0.2794)
							(mid 0.249642 0.249642)
							(end 0.2794 0.1778)
						)
						(arc
							(start 0.2794 -0.1778)
							(mid 0.249642 -0.249642)
							(end 0.1778 -0.2794)
						)
					)
					(width 0)
					(fill yes)
				)
			)
		)
	)
	(footprint ""
		(layer "F.Cu")
		(at 46.355 -139.446 -90)
		(property "Reference" "R384"
			(at 0 0 270)
			(layer "F.SilkS")
			(hide yes)
			(effects
				(font
					(size 1.27 1.27)
				)
			)
		)
		(property "Value" "300KR2F-GP"
			(at 0.064008 -3.993896 270)
			(unlocked yes)
			(layer "F.Fab")
			(hide yes)
			(effects
				(font
					(size 1.016 1.016)
					(thickness 0.1524)
				)
			)
		)
		(property "Device Type" "R402H16"
			(at 0.064008 -5.517896 270)
			(unlocked yes)
			(layer "F.Fab")
			(hide yes)
			(effects
				(font
					(size 1.016 1.016)
					(thickness 0.1524)
				)
			)
		)
		(duplicate_pad_numbers_are_jumpers no)
		(fp_line
			(start -0.508 -0.9398)
			(end -0.508 0.9398)
			(stroke
				(width 0.1524)
				(type default)
			)
			(layer "F.SilkS")
		)
		(fp_line
			(start 0.508 -0.9398)
			(end -0.508 -0.9398)
			(stroke
				(width 0.1524)
				(type default)
			)
			(layer "F.SilkS")
		)
		(fp_rect
			(start -0.508 0.9398)
			(end 0.508 -0.9398)
			(stroke
				(width 0)
				(type default)
			)
			(fill no)
			(layer "F.CrtYd")
		)
		(fp_rect
			(start -0.508 0.9398)
			(end 0.508 -0.9398)
			(stroke
				(width 0)
				(type default)
			)
			(fill no)
			(layer "F.Fab")
		)
		(pad "1" smd custom
			(at 0 -0.4445 270)
			(size 0.1397 0.1397)
			(layers "F.Cu" "F.Mask" "F.Paste")
			(net "SW_HDD_N13")
			(options
				(clearance outline)
				(anchor circle)
			)
			(primitives
				(gr_poly
					(pts
						(arc
							(start -0.1778 -0.2794)
							(mid -0.249642 -0.249642)
							(end -0.2794 -0.1778)
						)
						(arc
							(start -0.2794 0.1778)
							(mid -0.249642 0.249642)
							(end -0.1778 0.2794)
						)
						(arc
							(start 0.1778 0.2794)
							(mid 0.249642 0.249642)
							(end 0.2794 0.1778)
						)
						(arc
							(start 0.2794 -0.1778)
							(mid 0.249642 -0.249642)
							(end 0.1778 -0.2794)
						)
					)
					(width 0)
					(fill yes)
				)
			)
		)
		(pad "2" smd custom
			(at 0 0.4445 270)
			(size 0.1397 0.1397)
			(layers "F.Cu" "F.Mask" "F.Paste")
			(net "P12V_B")
			(options
				(clearance outline)
				(anchor circle)
			)
			(primitives
				(gr_poly
					(pts
						(arc
							(start -0.1778 -0.2794)
							(mid -0.249642 -0.249642)
							(end -0.2794 -0.1778)
						)
						(arc
							(start -0.2794 0.1778)
							(mid -0.249642 0.249642)
							(end -0.1778 0.2794)
						)
						(arc
							(start 0.1778 0.2794)
							(mid 0.249642 0.249642)
							(end 0.2794 0.1778)
						)
						(arc
							(start 0.2794 -0.1778)
							(mid 0.249642 -0.249642)
							(end 0.1778 -0.2794)
						)
					)
					(width 0)
					(fill yes)
				)
			)
		)
	)
	(footprint ""
		(layer "F.Cu")
		(at 320.7004 -146.6342 180)
		(property "Reference" "R484"
			(at 0 0 180)
			(layer "F.SilkS")
			(hide yes)
			(effects
				(font
					(size 1.27 1.27)
				)
			)
		)
		(property "Value" "10KR2F-2-GP"
			(at 0.064008 -3.993896 180)
			(unlocked yes)
			(layer "F.Fab")
			(hide yes)
			(effects
				(font
					(size 1.016 1.016)
					(thickness 0.1524)
				)
			)
		)
		(property "Device Type" "R402H16"
			(at 0.064008 -5.517896 180)
			(unlocked yes)
			(layer "F.Fab")
			(hide yes)
			(effects
				(font
					(size 1.016 1.016)
					(thickness 0.1524)
				)
			)
		)
		(duplicate_pad_numbers_are_jumpers no)
		(fp_line
			(start 0.508 -0.9398)
			(end -0.508 -0.9398)
			(stroke
				(width 0.1524)
				(type default)
			)
			(layer "F.SilkS")
		)
		(fp_line
			(start -0.508 -0.9398)
			(end -0.508 0.9398)
			(stroke
				(width 0.1524)
				(type default)
			)
			(layer "F.SilkS")
		)
		(fp_rect
			(start -0.508 0.9398)
			(end 0.508 -0.9398)
			(stroke
				(width 0)
				(type default)
			)
			(fill no)
			(layer "F.CrtYd")
		)
		(fp_rect
			(start -0.508 0.9398)
			(end 0.508 -0.9398)
			(stroke
				(width 0)
				(type default)
			)
			(fill no)
			(layer "F.Fab")
		)
		(pad "1" smd custom
			(at 0 -0.4445 180)
			(size 0.1397 0.1397)
			(layers "F.Cu" "F.Mask" "F.Paste")
			(net "P3V3_STBY_B")
			(options
				(clearance outline)
				(anchor circle)
			)
			(primitives
				(gr_poly
					(pts
						(arc
							(start -0.1778 -0.2794)
							(mid -0.249642 -0.249642)
							(end -0.2794 -0.1778)
						)
						(arc
							(start -0.2794 0.1778)
							(mid -0.249642 0.249642)
							(end -0.1778 0.2794)
						)
						(arc
							(start 0.1778 0.2794)
							(mid 0.249642 0.249642)
							(end 0.2794 0.1778)
						)
						(arc
							(start 0.2794 -0.1778)
							(mid 0.249642 -0.249642)
							(end 0.1778 -0.2794)
						)
					)
					(width 0)
					(fill yes)
				)
			)
		)
		(pad "2" smd custom
			(at 0 0.4445 180)
			(size 0.1397 0.1397)
			(layers "F.Cu" "F.Mask" "F.Paste")
			(net "HDD_PRSNT_18")
			(options
				(clearance outline)
				(anchor circle)
			)
			(primitives
				(gr_poly
					(pts
						(arc
							(start -0.1778 -0.2794)
							(mid -0.249642 -0.249642)
							(end -0.2794 -0.1778)
						)
						(arc
							(start -0.2794 0.1778)
							(mid -0.249642 0.249642)
							(end -0.1778 0.2794)
						)
						(arc
							(start 0.1778 0.2794)
							(mid 0.249642 0.249642)
							(end 0.2794 0.1778)
						)
						(arc
							(start 0.2794 -0.1778)
							(mid 0.249642 -0.249642)
							(end 0.1778 -0.2794)
						)
					)
					(width 0)
					(fill yes)
				)
			)
		)
	)
	(footprint ""
		(layer "F.Cu")
		(at 333.248 -128.651 180)
		(property "Reference" "R492"
			(at 0 0 180)
			(layer "F.SilkS")
			(hide yes)
			(effects
				(font
					(size 1.27 1.27)
				)
			)
		)
		(property "Value" "1KR2F-3-GP"
			(at 0.064008 -3.993896 180)
			(unlocked yes)
			(layer "F.Fab")
			(hide yes)
			(effects
				(font
					(size 1.016 1.016)
					(thickness 0.1524)
				)
			)
		)
		(property "Device Type" "R402H16"
			(at 0.064008 -5.517896 180)
			(unlocked yes)
			(layer "F.Fab")
			(hide yes)
			(effects
				(font
					(size 1.016 1.016)
					(thickness 0.1524)
				)
			)
		)
		(duplicate_pad_numbers_are_jumpers no)
		(fp_line
			(start 0.508 -0.9398)
			(end -0.508 -0.9398)
			(stroke
				(width 0.1524)
				(type default)
			)
			(layer "F.SilkS")
		)
		(fp_line
			(start -0.508 -0.9398)
			(end -0.508 0.9398)
			(stroke
				(width 0.1524)
				(type default)
			)
			(layer "F.SilkS")
		)
		(fp_rect
			(start -0.508 0.9398)
			(end 0.508 -0.9398)
			(stroke
				(width 0)
				(type default)
			)
			(fill no)
			(layer "F.CrtYd")
		)
		(fp_rect
			(start -0.508 0.9398)
			(end 0.508 -0.9398)
			(stroke
				(width 0)
				(type default)
			)
			(fill no)
			(layer "F.Fab")
		)
		(pad "1" smd custom
			(at 0 -0.4445 180)
			(size 0.1397 0.1397)
			(layers "F.Cu" "F.Mask" "F.Paste")
			(net "P3V3_STBY_B")
			(options
				(clearance outline)
				(anchor circle)
			)
			(primitives
				(gr_poly
					(pts
						(arc
							(start -0.1778 -0.2794)
							(mid -0.249642 -0.249642)
							(end -0.2794 -0.1778)
						)
						(arc
							(start -0.2794 0.1778)
							(mid -0.249642 0.249642)
							(end -0.1778 0.2794)
						)
						(arc
							(start 0.1778 0.2794)
							(mid 0.249642 0.249642)
							(end 0.2794 0.1778)
						)
						(arc
							(start 0.2794 -0.1778)
							(mid 0.249642 -0.249642)
							(end 0.1778 -0.2794)
						)
					)
					(width 0)
					(fill yes)
				)
			)
		)
		(pad "2" smd custom
			(at 0 0.4445 180)
			(size 0.1397 0.1397)
			(layers "F.Cu" "F.Mask" "F.Paste")
			(net "SW_PWR_R_HDD18")
			(options
				(clearance outline)
				(anchor circle)
			)
			(primitives
				(gr_poly
					(pts
						(arc
							(start -0.1778 -0.2794)
							(mid -0.249642 -0.249642)
							(end -0.2794 -0.1778)
						)
						(arc
							(start -0.2794 0.1778)
							(mid -0.249642 0.249642)
							(end -0.1778 0.2794)
						)
						(arc
							(start 0.1778 0.2794)
							(mid 0.249642 0.249642)
							(end 0.2794 0.1778)
						)
						(arc
							(start 0.2794 -0.1778)
							(mid 0.249642 -0.249642)
							(end 0.1778 -0.2794)
						)
					)
					(width 0)
					(fill yes)
				)
			)
		)
	)
	(footprint ""
		(layer "F.Cu")
		(at 239.798352 -134.393178 90)
		(property "Reference" "R371"
			(at 0 0 90)
			(layer "F.SilkS")
			(hide yes)
			(effects
				(font
					(size 1.27 1.27)
				)
			)
		)
		(property "Value" "10KR2F-2-GP"
			(at 0.064008 -3.993896 90)
			(unlocked yes)
			(layer "F.Fab")
			(hide yes)
			(effects
				(font
					(size 1.016 1.016)
					(thickness 0.1524)
				)
			)
		)
		(property "Device Type" "R402H16"
			(at 0.064008 -5.517896 90)
			(unlocked yes)
			(layer "F.Fab")
			(hide yes)
			(effects
				(font
					(size 1.016 1.016)
					(thickness 0.1524)
				)
			)
		)
		(duplicate_pad_numbers_are_jumpers no)
		(fp_line
			(start 0.508 -0.9398)
			(end -0.508 -0.9398)
			(stroke
				(width 0.1524)
				(type default)
			)
			(layer "F.SilkS")
		)
		(fp_line
			(start -0.508 -0.9398)
			(end -0.508 0.9398)
			(stroke
				(width 0.1524)
				(type default)
			)
			(layer "F.SilkS")
		)
		(fp_rect
			(start -0.508 0.9398)
			(end 0.508 -0.9398)
			(stroke
				(width 0)
				(type default)
			)
			(fill no)
			(layer "F.CrtYd")
		)
		(fp_rect
			(start -0.508 0.9398)
			(end 0.508 -0.9398)
			(stroke
				(width 0)
				(type default)
			)
			(fill no)
			(layer "F.Fab")
		)
		(pad "1" smd custom
			(at 0 -0.4445 90)
			(size 0.1397 0.1397)
			(layers "F.Cu" "F.Mask" "F.Paste")
			(net "P3V3_STBY_B")
			(options
				(clearance outline)
				(anchor circle)
			)
			(primitives
				(gr_poly
					(pts
						(arc
							(start -0.1778 -0.2794)
							(mid -0.249642 -0.249642)
							(end -0.2794 -0.1778)
						)
						(arc
							(start -0.2794 0.1778)
							(mid -0.249642 0.249642)
							(end -0.1778 0.2794)
						)
						(arc
							(start 0.1778 0.2794)
							(mid 0.249642 0.249642)
							(end 0.2794 0.1778)
						)
						(arc
							(start 0.2794 -0.1778)
							(mid 0.249642 -0.249642)
							(end 0.1778 -0.2794)
						)
					)
					(width 0)
					(fill yes)
				)
			)
		)
		(pad "2" smd custom
			(at 0 0.4445 90)
			(size 0.1397 0.1397)
			(layers "F.Cu" "F.Mask" "F.Paste")
			(net "I2C_DPB_BUFF_EN")
			(options
				(clearance outline)
				(anchor circle)
			)
			(primitives
				(gr_poly
					(pts
						(arc
							(start -0.1778 -0.2794)
							(mid -0.249642 -0.249642)
							(end -0.2794 -0.1778)
						)
						(arc
							(start -0.2794 0.1778)
							(mid -0.249642 0.249642)
							(end -0.1778 0.2794)
						)
						(arc
							(start 0.1778 0.2794)
							(mid 0.249642 0.249642)
							(end 0.2794 0.1778)
						)
						(arc
							(start 0.2794 -0.1778)
							(mid 0.249642 -0.249642)
							(end 0.1778 -0.2794)
						)
					)
					(width 0)
					(fill yes)
				)
			)
		)
	)
	(footprint ""
		(layer "F.Cu")
		(at 471.805 -254.127 -90)
		(property "Reference" "C181"
			(at 0 0 270)
			(layer "F.SilkS")
			(hide yes)
			(effects
				(font
					(size 1.27 1.27)
				)
			)
		)
		(property "Value" "SCD033U25V2KX-GP"
			(at 1.1811 -2.7051 270)
			(unlocked yes)
			(layer "F.Fab")
			(hide yes)
			(effects
				(font
					(size 1.016 1.016)
					(thickness 0.1524)
				)
			)
		)
		(property "Device Type" "C402H22"
			(at 1.1811 -4.2291 270)
			(unlocked yes)
			(layer "F.Fab")
			(hide yes)
			(effects
				(font
					(size 1.016 1.016)
					(thickness 0.1524)
				)
			)
		)
		(duplicate_pad_numbers_are_jumpers no)
		(fp_rect
			(start -0.4318 0.9525)
			(end 0.4318 -0.9525)
			(stroke
				(width 0)
				(type default)
			)
			(fill no)
			(layer "F.CrtYd")
		)
		(fp_rect
			(start -0.4318 0.9525)
			(end 0.4318 -0.9525)
			(stroke
				(width 0)
				(type default)
			)
			(fill no)
			(layer "F.Fab")
		)
		(pad "1" smd custom
			(at 0 -0.4445 270)
			(size 0.1524 0.1524)
			(layers "F.Cu" "F.Mask" "F.Paste")
			(net "SW_HDD_P11")
			(options
				(clearance outline)
				(anchor circle)
			)
			(primitives
				(gr_poly
					(pts
						(arc
							(start 0.3048 -0.2032)
							(mid 0.275042 -0.275042)
							(end 0.2032 -0.3048)
						)
						(arc
							(start -0.2032 -0.3048)
							(mid -0.275042 -0.275042)
							(end -0.3048 -0.2032)
						)
						(arc
							(start -0.3048 0.2032)
							(mid -0.275042 0.275042)
							(end -0.2032 0.3048)
						)
						(arc
							(start 0.2032 0.3048)
							(mid 0.275042 0.275042)
							(end 0.3048 0.2032)
						)
					)
					(width 0)
					(fill yes)
				)
			)
		)
		(pad "2" smd custom
			(at 0 0.4445 270)
			(size 0.1524 0.1524)
			(layers "F.Cu" "F.Mask" "F.Paste")
			(net "GND")
			(options
				(clearance outline)
				(anchor circle)
			)
			(primitives
				(gr_poly
					(pts
						(arc
							(start 0.3048 -0.2032)
							(mid 0.275042 -0.275042)
							(end 0.2032 -0.3048)
						)
						(arc
							(start -0.2032 -0.3048)
							(mid -0.275042 -0.275042)
							(end -0.3048 -0.2032)
						)
						(arc
							(start -0.3048 0.2032)
							(mid -0.275042 0.275042)
							(end -0.2032 0.3048)
						)
						(arc
							(start 0.2032 0.3048)
							(mid 0.275042 0.275042)
							(end 0.3048 0.2032)
						)
					)
					(width 0)
					(fill yes)
				)
			)
		)
	)
	(footprint ""
		(layer "F.Cu")
		(at 426.72 -13.589)
		(property "Reference" "R841"
			(at 0 0 0)
			(layer "F.SilkS")
			(hide yes)
			(effects
				(font
					(size 1.27 1.27)
				)
			)
		)
		(property "Value" "4K7R2F-GP"
			(at 0.064008 -3.993896 0)
			(unlocked yes)
			(layer "F.Fab")
			(hide yes)
			(effects
				(font
					(size 1.016 1.016)
					(thickness 0.1524)
				)
			)
		)
		(property "Device Type" "R402H16"
			(at 0.064008 -5.517896 0)
			(unlocked yes)
			(layer "F.Fab")
			(hide yes)
			(effects
				(font
					(size 1.016 1.016)
					(thickness 0.1524)
				)
			)
		)
		(duplicate_pad_numbers_are_jumpers no)
		(fp_line
			(start -0.508 -0.9398)
			(end -0.508 0.9398)
			(stroke
				(width 0.1524)
				(type default)
			)
			(layer "F.SilkS")
		)
		(fp_line
			(start 0.508 -0.9398)
			(end -0.508 -0.9398)
			(stroke
				(width 0.1524)
				(type default)
			)
			(layer "F.SilkS")
		)
		(fp_rect
			(start -0.508 0.9398)
			(end 0.508 -0.9398)
			(stroke
				(width 0)
				(type default)
			)
			(fill no)
			(layer "F.CrtYd")
		)
		(fp_rect
			(start -0.508 0.9398)
			(end 0.508 -0.9398)
			(stroke
				(width 0)
				(type default)
			)
			(fill no)
			(layer "F.Fab")
		)
		(pad "1" smd custom
			(at 0 -0.4445)
			(size 0.1397 0.1397)
			(layers "F.Cu" "F.Mask" "F.Paste")
			(net "SW_PWR_R_HDD33")
			(options
				(clearance outline)
				(anchor circle)
			)
			(primitives
				(gr_poly
					(pts
						(arc
							(start -0.1778 -0.2794)
							(mid -0.249642 -0.249642)
							(end -0.2794 -0.1778)
						)
						(arc
							(start -0.2794 0.1778)
							(mid -0.249642 0.249642)
							(end -0.1778 0.2794)
						)
						(arc
							(start 0.1778 0.2794)
							(mid 0.249642 0.249642)
							(end 0.2794 0.1778)
						)
						(arc
							(start 0.2794 -0.1778)
							(mid 0.249642 -0.249642)
							(end 0.1778 -0.2794)
						)
					)
					(width 0)
					(fill yes)
				)
			)
		)
		(pad "2" smd custom
			(at 0 0.4445)
			(size 0.1397 0.1397)
			(layers "F.Cu" "F.Mask" "F.Paste")
			(net "GND")
			(options
				(clearance outline)
				(anchor circle)
			)
			(primitives
				(gr_poly
					(pts
						(arc
							(start -0.1778 -0.2794)
							(mid -0.249642 -0.249642)
							(end -0.2794 -0.1778)
						)
						(arc
							(start -0.2794 0.1778)
							(mid -0.249642 0.249642)
							(end -0.1778 0.2794)
						)
						(arc
							(start 0.1778 0.2794)
							(mid 0.249642 0.249642)
							(end 0.2794 0.1778)
						)
						(arc
							(start 0.2794 -0.1778)
							(mid 0.249642 -0.249642)
							(end 0.1778 -0.2794)
						)
					)
					(width 0)
					(fill yes)
				)
			)
		)
	)
	(footprint ""
		(layer "F.Cu")
		(at 141.097 -139.446 -90)
		(property "Reference" "R453"
			(at 0 0 270)
			(layer "F.SilkS")
			(hide yes)
			(effects
				(font
					(size 1.27 1.27)
				)
			)
		)
		(property "Value" "300KR2F-GP"
			(at 0.064008 -3.993896 270)
			(unlocked yes)
			(layer "F.Fab")
			(hide yes)
			(effects
				(font
					(size 1.016 1.016)
					(thickness 0.1524)
				)
			)
		)
		(property "Device Type" "R402H16"
			(at 0.064008 -5.517896 270)
			(unlocked yes)
			(layer "F.Fab")
			(hide yes)
			(effects
				(font
					(size 1.016 1.016)
					(thickness 0.1524)
				)
			)
		)
		(duplicate_pad_numbers_are_jumpers no)
		(fp_line
			(start -0.508 -0.9398)
			(end -0.508 0.9398)
			(stroke
				(width 0.1524)
				(type default)
			)
			(layer "F.SilkS")
		)
		(fp_line
			(start 0.508 -0.9398)
			(end -0.508 -0.9398)
			(stroke
				(width 0.1524)
				(type default)
			)
			(layer "F.SilkS")
		)
		(fp_rect
			(start -0.508 0.9398)
			(end 0.508 -0.9398)
			(stroke
				(width 0)
				(type default)
			)
			(fill no)
			(layer "F.CrtYd")
		)
		(fp_rect
			(start -0.508 0.9398)
			(end 0.508 -0.9398)
			(stroke
				(width 0)
				(type default)
			)
			(fill no)
			(layer "F.Fab")
		)
		(pad "1" smd custom
			(at 0 -0.4445 270)
			(size 0.1397 0.1397)
			(layers "F.Cu" "F.Mask" "F.Paste")
			(net "SW_HDD_N16")
			(options
				(clearance outline)
				(anchor circle)
			)
			(primitives
				(gr_poly
					(pts
						(arc
							(start -0.1778 -0.2794)
							(mid -0.249642 -0.249642)
							(end -0.2794 -0.1778)
						)
						(arc
							(start -0.2794 0.1778)
							(mid -0.249642 0.249642)
							(end -0.1778 0.2794)
						)
						(arc
							(start 0.1778 0.2794)
							(mid 0.249642 0.249642)
							(end 0.2794 0.1778)
						)
						(arc
							(start 0.2794 -0.1778)
							(mid 0.249642 -0.249642)
							(end 0.1778 -0.2794)
						)
					)
					(width 0)
					(fill yes)
				)
			)
		)
		(pad "2" smd custom
			(at 0 0.4445 270)
			(size 0.1397 0.1397)
			(layers "F.Cu" "F.Mask" "F.Paste")
			(net "P12V_B")
			(options
				(clearance outline)
				(anchor circle)
			)
			(primitives
				(gr_poly
					(pts
						(arc
							(start -0.1778 -0.2794)
							(mid -0.249642 -0.249642)
							(end -0.2794 -0.1778)
						)
						(arc
							(start -0.2794 0.1778)
							(mid -0.249642 0.249642)
							(end -0.1778 0.2794)
						)
						(arc
							(start 0.1778 0.2794)
							(mid 0.249642 0.249642)
							(end 0.2794 0.1778)
						)
						(arc
							(start 0.2794 -0.1778)
							(mid 0.249642 -0.249642)
							(end 0.1778 -0.2794)
						)
					)
					(width 0)
					(fill yes)
				)
			)
		)
	)
	(footprint ""
		(layer "F.Cu")
		(at 105.992168 -97.328228 -90)
		(property "Reference" "R388"
			(at 0 0 270)
			(layer "F.SilkS")
			(hide yes)
			(effects
				(font
					(size 1.27 1.27)
				)
			)
		)
		(property "Value" "4K7R2F-GP"
			(at 0.064008 -3.993896 270)
			(unlocked yes)
			(layer "F.Fab")
			(hide yes)
			(effects
				(font
					(size 1.016 1.016)
					(thickness 0.1524)
				)
			)
		)
		(property "Device Type" "R402H16"
			(at 0.064008 -5.517896 270)
			(unlocked yes)
			(layer "F.Fab")
			(hide yes)
			(effects
				(font
					(size 1.016 1.016)
					(thickness 0.1524)
				)
			)
		)
		(duplicate_pad_numbers_are_jumpers no)
		(fp_line
			(start -0.508 -0.9398)
			(end -0.508 0.9398)
			(stroke
				(width 0.1524)
				(type default)
			)
			(layer "F.SilkS")
		)
		(fp_line
			(start 0.508 -0.9398)
			(end -0.508 -0.9398)
			(stroke
				(width 0.1524)
				(type default)
			)
			(layer "F.SilkS")
		)
		(fp_rect
			(start -0.508 0.9398)
			(end 0.508 -0.9398)
			(stroke
				(width 0)
				(type default)
			)
			(fill no)
			(layer "F.CrtYd")
		)
		(fp_rect
			(start -0.508 0.9398)
			(end 0.508 -0.9398)
			(stroke
				(width 0)
				(type default)
			)
			(fill no)
			(layer "F.Fab")
		)
		(pad "1" smd custom
			(at 0 -0.4445 270)
			(size 0.1397 0.1397)
			(layers "F.Cu" "F.Mask" "F.Paste")
			(net "DRIVE_B_15_ACT")
			(options
				(clearance outline)
				(anchor circle)
			)
			(primitives
				(gr_poly
					(pts
						(arc
							(start -0.1778 -0.2794)
							(mid -0.249642 -0.249642)
							(end -0.2794 -0.1778)
						)
						(arc
							(start -0.2794 0.1778)
							(mid -0.249642 0.249642)
							(end -0.1778 0.2794)
						)
						(arc
							(start 0.1778 0.2794)
							(mid 0.249642 0.249642)
							(end 0.2794 0.1778)
						)
						(arc
							(start 0.2794 -0.1778)
							(mid 0.249642 -0.249642)
							(end 0.1778 -0.2794)
						)
					)
					(width 0)
					(fill yes)
				)
			)
		)
		(pad "2" smd custom
			(at 0 0.4445 270)
			(size 0.1397 0.1397)
			(layers "F.Cu" "F.Mask" "F.Paste")
			(net "GND")
			(options
				(clearance outline)
				(anchor circle)
			)
			(primitives
				(gr_poly
					(pts
						(arc
							(start -0.1778 -0.2794)
							(mid -0.249642 -0.249642)
							(end -0.2794 -0.1778)
						)
						(arc
							(start -0.2794 0.1778)
							(mid -0.249642 0.249642)
							(end -0.1778 0.2794)
						)
						(arc
							(start 0.1778 0.2794)
							(mid 0.249642 0.249642)
							(end 0.2794 0.1778)
						)
						(arc
							(start 0.2794 -0.1778)
							(mid 0.249642 -0.249642)
							(end 0.1778 -0.2794)
						)
					)
					(width 0)
					(fill yes)
				)
			)
		)
	)
	(footprint ""
		(layer "F.Cu")
		(at 472.6432 -5.6642 90)
		(property "Reference" "R889"
			(at 0 0 90)
			(layer "F.SilkS")
			(hide yes)
			(effects
				(font
					(size 1.27 1.27)
				)
			)
		)
		(property "Value" "4K7R2J-2-GP"
			(at 0.064008 -3.993896 90)
			(unlocked yes)
			(layer "F.Fab")
			(hide yes)
			(effects
				(font
					(size 1.016 1.016)
					(thickness 0.1524)
				)
			)
		)
		(property "Device Type" "R402H16"
			(at 0.064008 -5.517896 90)
			(unlocked yes)
			(layer "F.Fab")
			(hide yes)
			(effects
				(font
					(size 1.016 1.016)
					(thickness 0.1524)
				)
			)
		)
		(duplicate_pad_numbers_are_jumpers no)
		(fp_line
			(start 0.508 -0.9398)
			(end -0.508 -0.9398)
			(stroke
				(width 0.1524)
				(type default)
			)
			(layer "F.SilkS")
		)
		(fp_line
			(start -0.508 -0.9398)
			(end -0.508 0.9398)
			(stroke
				(width 0.1524)
				(type default)
			)
			(layer "F.SilkS")
		)
		(fp_rect
			(start -0.508 0.9398)
			(end 0.508 -0.9398)
			(stroke
				(width 0)
				(type default)
			)
			(fill no)
			(layer "F.CrtYd")
		)
		(fp_rect
			(start -0.508 0.9398)
			(end 0.508 -0.9398)
			(stroke
				(width 0)
				(type default)
			)
			(fill no)
			(layer "F.Fab")
		)
		(pad "1" smd custom
			(at 0 -0.4445 90)
			(size 0.1397 0.1397)
			(layers "F.Cu" "F.Mask" "F.Paste")
			(net "P12V_B")
			(options
				(clearance outline)
				(anchor circle)
			)
			(primitives
				(gr_poly
					(pts
						(arc
							(start -0.1778 -0.2794)
							(mid -0.249642 -0.249642)
							(end -0.2794 -0.1778)
						)
						(arc
							(start -0.2794 0.1778)
							(mid -0.249642 0.249642)
							(end -0.1778 0.2794)
						)
						(arc
							(start 0.1778 0.2794)
							(mid 0.249642 0.249642)
							(end 0.2794 0.1778)
						)
						(arc
							(start 0.2794 -0.1778)
							(mid 0.249642 -0.249642)
							(end 0.1778 -0.2794)
						)
					)
					(width 0)
					(fill yes)
				)
			)
		)
		(pad "2" smd custom
			(at 0 0.4445 90)
			(size 0.1397 0.1397)
			(layers "F.Cu" "F.Mask" "F.Paste")
			(net "SW_HDD_R35")
			(options
				(clearance outline)
				(anchor circle)
			)
			(primitives
				(gr_poly
					(pts
						(arc
							(start -0.1778 -0.2794)
							(mid -0.249642 -0.249642)
							(end -0.2794 -0.1778)
						)
						(arc
							(start -0.2794 0.1778)
							(mid -0.249642 0.249642)
							(end -0.1778 0.2794)
						)
						(arc
							(start 0.1778 0.2794)
							(mid 0.249642 0.249642)
							(end 0.2794 0.1778)
						)
						(arc
							(start 0.2794 -0.1778)
							(mid 0.249642 -0.249642)
							(end 0.1778 -0.2794)
						)
					)
					(width 0)
					(fill yes)
				)
			)
		)
	)
	(footprint ""
		(layer "F.Cu")
		(at 24.704802 -229.49535 -90)
		(property "Reference" "C623"
			(at 0 0 270)
			(layer "F.SilkS")
			(hide yes)
			(effects
				(font
					(size 1.27 1.27)
				)
			)
		)
		(property "Value" "SC1U16V3KX-5GP"
			(at 0 -2.8194 270)
			(unlocked yes)
			(layer "F.Fab")
			(hide yes)
			(effects
				(font
					(size 1.016 1.016)
					(thickness 0.1524)
				)
			)
		)
		(property "Device Type" "C603H36"
			(at 0 -4.3434 270)
			(unlocked yes)
			(layer "F.Fab")
			(hide yes)
			(effects
				(font
					(size 1.016 1.016)
					(thickness 0.1524)
				)
			)
		)
		(duplicate_pad_numbers_are_jumpers no)
		(fp_line
			(start 0.508 0)
			(end -0.508 0)
			(stroke
				(width 0.2032)
				(type default)
			)
			(layer "F.SilkS")
		)
		(fp_rect
			(start -0.5842 1.3335)
			(end 0.5842 -1.3335)
			(stroke
				(width 0)
				(type default)
			)
			(fill no)
			(layer "F.CrtYd")
		)
		(fp_rect
			(start -0.5842 1.3335)
			(end 0.5842 -1.3335)
			(stroke
				(width 0)
				(type default)
			)
			(fill no)
			(layer "F.Fab")
		)
		(pad "1" smd custom
			(at 0 -0.762 270)
			(size 0.2159 0.2159)
			(layers "F.Cu" "F.Mask" "F.Paste")
			(net "P5V_B_1_EN_R")
			(options
				(clearance outline)
				(anchor circle)
			)
			(primitives
				(gr_poly
					(pts
						(arc
							(start -0.3302 -0.4318)
							(mid -0.402042 -0.402042)
							(end -0.4318 -0.3302)
						)
						(arc
							(start -0.4318 0.3302)
							(mid -0.402042 0.402042)
							(end -0.3302 0.4318)
						)
						(arc
							(start 0.3302 0.4318)
							(mid 0.402042 0.402042)
							(end 0.4318 0.3302)
						)
						(arc
							(start 0.4318 -0.3302)
							(mid 0.402042 -0.402042)
							(end 0.3302 -0.4318)
						)
					)
					(width 0)
					(fill yes)
				)
			)
		)
		(pad "2" smd custom
			(at 0 0.762 270)
			(size 0.2159 0.2159)
			(layers "F.Cu" "F.Mask" "F.Paste")
			(net "GND")
			(options
				(clearance outline)
				(anchor circle)
			)
			(primitives
				(gr_poly
					(pts
						(arc
							(start -0.3302 -0.4318)
							(mid -0.402042 -0.402042)
							(end -0.4318 -0.3302)
						)
						(arc
							(start -0.4318 0.3302)
							(mid -0.402042 0.402042)
							(end -0.3302 0.4318)
						)
						(arc
							(start 0.3302 0.4318)
							(mid 0.402042 0.402042)
							(end 0.4318 0.3302)
						)
						(arc
							(start 0.4318 -0.3302)
							(mid 0.402042 -0.402042)
							(end 0.3302 -0.4318)
						)
					)
					(width 0)
					(fill yes)
				)
			)
		)
	)
	(footprint ""
		(layer "F.Cu")
		(at 335.788 -128.651 180)
		(property "Reference" "R495"
			(at 0 0 180)
			(layer "F.SilkS")
			(hide yes)
			(effects
				(font
					(size 1.27 1.27)
				)
			)
		)
		(property "Value" "0R2J-2-GP"
			(at 0.064008 -3.993896 180)
			(unlocked yes)
			(layer "F.Fab")
			(hide yes)
			(effects
				(font
					(size 1.016 1.016)
					(thickness 0.1524)
				)
			)
		)
		(property "Device Type" "R402H16"
			(at 0.064008 -5.517896 180)
			(unlocked yes)
			(layer "F.Fab")
			(hide yes)
			(effects
				(font
					(size 1.016 1.016)
					(thickness 0.1524)
				)
			)
		)
		(duplicate_pad_numbers_are_jumpers no)
		(fp_line
			(start 0.508 -0.9398)
			(end -0.508 -0.9398)
			(stroke
				(width 0.1524)
				(type default)
			)
			(layer "F.SilkS")
		)
		(fp_line
			(start -0.508 -0.9398)
			(end -0.508 0.9398)
			(stroke
				(width 0.1524)
				(type default)
			)
			(layer "F.SilkS")
		)
		(fp_rect
			(start -0.508 0.9398)
			(end 0.508 -0.9398)
			(stroke
				(width 0)
				(type default)
			)
			(fill no)
			(layer "F.CrtYd")
		)
		(fp_rect
			(start -0.508 0.9398)
			(end 0.508 -0.9398)
			(stroke
				(width 0)
				(type default)
			)
			(fill no)
			(layer "F.Fab")
		)
		(pad "1" smd custom
			(at 0 -0.4445 180)
			(size 0.1397 0.1397)
			(layers "F.Cu" "F.Mask" "F.Paste")
			(net "DRIVE_B_18_PWR")
			(options
				(clearance outline)
				(anchor circle)
			)
			(primitives
				(gr_poly
					(pts
						(arc
							(start -0.1778 -0.2794)
							(mid -0.249642 -0.249642)
							(end -0.2794 -0.1778)
						)
						(arc
							(start -0.2794 0.1778)
							(mid -0.249642 0.249642)
							(end -0.1778 0.2794)
						)
						(arc
							(start 0.1778 0.2794)
							(mid 0.249642 0.249642)
							(end 0.2794 0.1778)
						)
						(arc
							(start 0.2794 -0.1778)
							(mid 0.249642 -0.249642)
							(end 0.1778 -0.2794)
						)
					)
					(width 0)
					(fill yes)
				)
			)
		)
		(pad "2" smd custom
			(at 0 0.4445 180)
			(size 0.1397 0.1397)
			(layers "F.Cu" "F.Mask" "F.Paste")
			(net "SW_PWR_R_HDD18")
			(options
				(clearance outline)
				(anchor circle)
			)
			(primitives
				(gr_poly
					(pts
						(arc
							(start -0.1778 -0.2794)
							(mid -0.249642 -0.249642)
							(end -0.2794 -0.1778)
						)
						(arc
							(start -0.2794 0.1778)
							(mid -0.249642 0.249642)
							(end -0.1778 0.2794)
						)
						(arc
							(start 0.1778 0.2794)
							(mid 0.249642 0.249642)
							(end 0.2794 0.1778)
						)
						(arc
							(start 0.2794 -0.1778)
							(mid 0.249642 -0.249642)
							(end 0.1778 -0.2794)
						)
					)
					(width 0)
					(fill yes)
				)
			)
		)
	)
	(footprint ""
		(layer "F.Cu")
		(at 33.3248 -293.799768)
		(property "Reference" ""
			(at 0 0 0)
			(layer "F.SilkS")
			(hide yes)
			(effects
				(font
					(size 1.27 1.27)
				)
			)
		)
		(property "Value" "*"
			(at -8.398764 -8.057642 0)
			(unlocked yes)
			(layer "F.Fab")
			(hide yes)
			(effects
				(font
					(size 1.016 1.016)
					(thickness 0.1524)
				)
			)
		)
		(duplicate_pad_numbers_are_jumpers no)
		(fp_poly
			(pts
				(arc
					(start 7.3152 0)
					(mid 0 7.3152)
					(end -7.3152 0)
				)
				(arc
					(start -7.3152 -5.9944)
					(mid 0 -13.3096)
					(end 7.3152 -5.9944)
				)
			)
			(stroke
				(width 0)
				(type default)
			)
			(fill no)
			(layer "B.CrtYd")
		)
		(fp_poly
			(pts
				(arc
					(start 7.3152 0)
					(mid 0 7.3152)
					(end -7.3152 0)
				)
				(arc
					(start -7.3152 -5.9944)
					(mid 0 -13.3096)
					(end 7.3152 -5.9944)
				)
			)
			(stroke
				(width 0)
				(type default)
			)
			(fill no)
			(layer "F.CrtYd")
		)
		(fp_poly
			(pts
				(arc
					(start 7.3152 0)
					(mid 0 7.3152)
					(end -7.3152 0)
				)
				(arc
					(start -7.3152 -5.9944)
					(mid 0 -13.3096)
					(end 7.3152 -5.9944)
				)
			)
			(stroke
				(width 0)
				(type default)
			)
			(fill no)
			(layer "B.Fab")
		)
		(fp_poly
			(pts
				(arc
					(start 7.3152 0)
					(mid 0 7.3152)
					(end -7.3152 0)
				)
				(arc
					(start -7.3152 -5.9944)
					(mid 0 -13.3096)
					(end 7.3152 -5.9944)
				)
			)
			(stroke
				(width 0)
				(type default)
			)
			(fill no)
			(layer "F.Fab")
		)
		(pad "1" thru_hole oval
			(at 0 0)
			(size 14.0208 20.0152)
			(drill 0.0254
				(offset 0 -2.9972)
			)
			(layers "*.Cu" "*.Mask")
			(remove_unused_layers no)
			(net "Net_12")
			(clearance -1.002284)
			(thermal_gap 0.1524)
			(padstack
				(mode front_inner_back)
				(layer "Inner"
					(shape custom)
					(size 2.928012 2.928012)
					(options
						(anchor circle)
					)
					(primitives
						(gr_poly
							(pts
								(arc
									(start 4.571746 -2.084324)
									(mid 0.000333 7.430372)
									(end -4.571492 -2.084324)
								)
								(arc
									(start -4.571492 -2.084324)
									(mid -3.570296 -3.611977)
									(end -2.875026 -5.30098)
								)
								(arc
									(start -2.875026 -5.30098)
									(mid 0.000217 -7.43089)
									(end 2.87528 -5.30098)
								)
								(arc
									(start 2.87528 -5.30098)
									(mid 3.570511 -3.611956)
									(end 4.571746 -2.084324)
								)
							)
							(width 0)
							(fill yes)
						)
					)
					(clearance 0.1524)
				)
				(layer "B.Cu"
					(shape oval)
					(size 14.0208 20.0152)
					(offset 0 -2.9972)
					(clearance -1.002284)
				)
			)
		)
		(zone
			(layers "F.Cu" "B.Cu" "In1.Cu" "In2.Cu" "In3.Cu" "In4.Cu" "In5.Cu" "In6.Cu")
			(hatch none 0.5)
			(connect_pads
				(clearance 0)
			)
			(min_thickness 0.25)
			(keepout
				(tracks not_allowed)
				(vias allowed)
				(pads allowed)
				(copperpour not_allowed)
				(footprints allowed)
			)
			(placement
				(enabled no)
				(sheetname "")
			)
			(fill
				(thermal_gap 0.5)
				(thermal_bridge_width 0.5)
				(island_removal_mode 0)
			)
			(polygon
				(pts
					(arc
						(start 26.3144 -299.794168)
						(mid 33.3248 -306.804568)
						(end 40.3352 -299.794168)
					)
					(arc
						(start 40.3352 -293.799768)
						(mid 33.3248 -286.789368)
						(end 26.3144 -293.799768)
					)
				)
			)
		)
	)
	(footprint ""
		(layer "F.Cu")
		(at 206.970122 -105.154984)
		(property "Reference" "TC4"
			(at 0 0 0)
			(layer "F.SilkS")
			(hide yes)
			(effects
				(font
					(size 1.27 1.27)
				)
			)
		)
		(property "Value" "SE270U16VM-8-GP"
			(at -4.5974 -2.54 0)
			(unlocked yes)
			(layer "F.Fab")
			(hide yes)
			(effects
				(font
					(size 1.016 1.016)
					(thickness 0.1524)
				)
			)
		)
		(property "Device Type" "SE361416H394"
			(at -4.5974 -4.064 0)
			(unlocked yes)
			(layer "F.Fab")
			(hide yes)
			(effects
				(font
					(size 1.016 1.016)
					(thickness 0.1524)
				)
			)
		)
		(duplicate_pad_numbers_are_jumpers no)
		(fp_line
			(start -3.556 -3.4163)
			(end -2.3622 -4.6101)
			(stroke
				(width 0.1524)
				(type default)
			)
			(layer "F.SilkS")
		)
		(fp_line
			(start -3.556 4.6101)
			(end -3.556 -3.4163)
			(stroke
				(width 0.1524)
				(type default)
			)
			(layer "F.SilkS")
		)
		(fp_line
			(start -2.3622 -4.6101)
			(end 2.3622 -4.6101)
			(stroke
				(width 0.1524)
				(type default)
			)
			(layer "F.SilkS")
		)
		(fp_line
			(start 2.3622 -4.6101)
			(end 3.556 -3.4163)
			(stroke
				(width 0.1524)
				(type default)
			)
			(layer "F.SilkS")
		)
		(fp_line
			(start 3.556 -3.4163)
			(end 3.556 4.6101)
			(stroke
				(width 0.1524)
				(type default)
			)
			(layer "F.SilkS")
		)
		(fp_line
			(start 3.556 4.6101)
			(end -3.556 4.6101)
			(stroke
				(width 0.1524)
				(type default)
			)
			(layer "F.SilkS")
		)
		(fp_rect
			(start -3.302 3.6449)
			(end 3.302 -3.6449)
			(stroke
				(width 0)
				(type default)
			)
			(fill no)
			(layer "F.CrtYd")
		)
		(fp_poly
			(pts
				(xy 3.81 4.6863) (xy 3.81 -3.4925) (xy 3.302 -3.4925) (xy 3.302 3.6449) (xy -3.302 3.6449) (xy -3.302 -3.6449)
				(xy 3.302 -3.6449) (xy 3.302 -3.5052) (xy 3.81 -3.5052) (xy 3.81 -4.6863) (xy -3.81 -4.6863) (xy -3.81 4.6863)
			)
			(stroke
				(width 0)
				(type default)
			)
			(fill no)
			(layer "F.CrtYd")
		)
		(fp_rect
			(start -3.81 4.6863)
			(end 3.81 -4.6863)
			(stroke
				(width 0)
				(type default)
			)
			(fill no)
			(layer "F.Fab")
		)
		(pad "1" smd rect
			(at 0 -2.574036)
			(size 1.4224 3.556)
			(layers "F.Cu" "F.Mask" "F.Paste")
			(net "P12V_B")
		)
		(pad "2" smd rect
			(at 0 2.574036)
			(size 1.4224 3.556)
			(layers "F.Cu" "F.Mask" "F.Paste")
			(net "GND")
		)
	)
	(footprint ""
		(layer "F.Cu")
		(at 134.196836 -363.405166 180)
		(property "Reference" "C527"
			(at 0 0 180)
			(layer "F.SilkS")
			(hide yes)
			(effects
				(font
					(size 1.27 1.27)
				)
			)
		)
		(property "Value" "SC1U25V3KX-GP"
			(at 0 -2.8194 180)
			(unlocked yes)
			(layer "F.Fab")
			(hide yes)
			(effects
				(font
					(size 1.016 1.016)
					(thickness 0.1524)
				)
			)
		)
		(property "Device Type" "C603H36"
			(at 0 -4.3434 180)
			(unlocked yes)
			(layer "F.Fab")
			(hide yes)
			(effects
				(font
					(size 1.016 1.016)
					(thickness 0.1524)
				)
			)
		)
		(duplicate_pad_numbers_are_jumpers no)
		(fp_line
			(start 0.508 0)
			(end -0.508 0)
			(stroke
				(width 0.2032)
				(type default)
			)
			(layer "F.SilkS")
		)
		(fp_rect
			(start -0.5842 1.3335)
			(end 0.5842 -1.3335)
			(stroke
				(width 0)
				(type default)
			)
			(fill no)
			(layer "F.CrtYd")
		)
		(fp_rect
			(start -0.5842 1.3335)
			(end 0.5842 -1.3335)
			(stroke
				(width 0)
				(type default)
			)
			(fill no)
			(layer "F.Fab")
		)
		(pad "1" smd custom
			(at 0 -0.762 180)
			(size 0.2159 0.2159)
			(layers "F.Cu" "F.Mask" "F.Paste")
			(net "P12V_FAN1")
			(options
				(clearance outline)
				(anchor circle)
			)
			(primitives
				(gr_poly
					(pts
						(arc
							(start -0.3302 -0.4318)
							(mid -0.402042 -0.402042)
							(end -0.4318 -0.3302)
						)
						(arc
							(start -0.4318 0.3302)
							(mid -0.402042 0.402042)
							(end -0.3302 0.4318)
						)
						(arc
							(start 0.3302 0.4318)
							(mid 0.402042 0.402042)
							(end 0.4318 0.3302)
						)
						(arc
							(start 0.4318 -0.3302)
							(mid 0.402042 -0.402042)
							(end 0.3302 -0.4318)
						)
					)
					(width 0)
					(fill yes)
				)
			)
		)
		(pad "2" smd custom
			(at 0 0.762 180)
			(size 0.2159 0.2159)
			(layers "F.Cu" "F.Mask" "F.Paste")
			(net "GND")
			(options
				(clearance outline)
				(anchor circle)
			)
			(primitives
				(gr_poly
					(pts
						(arc
							(start -0.3302 -0.4318)
							(mid -0.402042 -0.402042)
							(end -0.4318 -0.3302)
						)
						(arc
							(start -0.4318 0.3302)
							(mid -0.402042 0.402042)
							(end -0.3302 0.4318)
						)
						(arc
							(start 0.3302 0.4318)
							(mid 0.402042 0.402042)
							(end 0.4318 0.3302)
						)
						(arc
							(start 0.4318 -0.3302)
							(mid 0.402042 -0.402042)
							(end 0.3302 -0.4318)
						)
					)
					(width 0)
					(fill yes)
				)
			)
		)
	)
	(footprint ""
		(layer "F.Cu")
		(at 289.080448 -347.541342 180)
		(property "Reference" "R1083"
			(at 0 0 180)
			(layer "F.SilkS")
			(hide yes)
			(effects
				(font
					(size 1.27 1.27)
				)
			)
		)
		(property "Value" "0R2J-2-GP"
			(at 0.064008 -3.993896 180)
			(unlocked yes)
			(layer "F.Fab")
			(hide yes)
			(effects
				(font
					(size 1.016 1.016)
					(thickness 0.1524)
				)
			)
		)
		(property "Device Type" "R402H16"
			(at 0.064008 -5.517896 180)
			(unlocked yes)
			(layer "F.Fab")
			(hide yes)
			(effects
				(font
					(size 1.016 1.016)
					(thickness 0.1524)
				)
			)
		)
		(duplicate_pad_numbers_are_jumpers no)
		(fp_line
			(start 0.508 -0.9398)
			(end -0.508 -0.9398)
			(stroke
				(width 0.1524)
				(type default)
			)
			(layer "F.SilkS")
		)
		(fp_line
			(start -0.508 -0.9398)
			(end -0.508 0.9398)
			(stroke
				(width 0.1524)
				(type default)
			)
			(layer "F.SilkS")
		)
		(fp_rect
			(start -0.508 0.9398)
			(end 0.508 -0.9398)
			(stroke
				(width 0)
				(type default)
			)
			(fill no)
			(layer "F.CrtYd")
		)
		(fp_rect
			(start -0.508 0.9398)
			(end 0.508 -0.9398)
			(stroke
				(width 0)
				(type default)
			)
			(fill no)
			(layer "F.Fab")
		)
		(pad "1" smd custom
			(at 0 -0.4445 180)
			(size 0.1397 0.1397)
			(layers "F.Cu" "F.Mask" "F.Paste")
			(net "GND")
			(options
				(clearance outline)
				(anchor circle)
			)
			(primitives
				(gr_poly
					(pts
						(arc
							(start -0.1778 -0.2794)
							(mid -0.249642 -0.249642)
							(end -0.2794 -0.1778)
						)
						(arc
							(start -0.2794 0.1778)
							(mid -0.249642 0.249642)
							(end -0.1778 0.2794)
						)
						(arc
							(start 0.1778 0.2794)
							(mid 0.249642 0.249642)
							(end 0.2794 0.1778)
						)
						(arc
							(start 0.2794 -0.1778)
							(mid 0.249642 -0.249642)
							(end 0.1778 -0.2794)
						)
					)
					(width 0)
					(fill yes)
				)
			)
		)
		(pad "2" smd custom
			(at 0 0.4445 180)
			(size 0.1397 0.1397)
			(layers "F.Cu" "F.Mask" "F.Paste")
			(net "MAX31790_B_WD_ST")
			(options
				(clearance outline)
				(anchor circle)
			)
			(primitives
				(gr_poly
					(pts
						(arc
							(start -0.1778 -0.2794)
							(mid -0.249642 -0.249642)
							(end -0.2794 -0.1778)
						)
						(arc
							(start -0.2794 0.1778)
							(mid -0.249642 0.249642)
							(end -0.1778 0.2794)
						)
						(arc
							(start 0.1778 0.2794)
							(mid 0.249642 0.249642)
							(end 0.2794 0.1778)
						)
						(arc
							(start 0.2794 -0.1778)
							(mid 0.249642 -0.249642)
							(end 0.1778 -0.2794)
						)
					)
					(width 0)
					(fill yes)
				)
			)
		)
	)
	(footprint ""
		(layer "F.Cu")
		(at 457.581 -32.004 -90)
		(property "Reference" "R851"
			(at 0 0 270)
			(layer "F.SilkS")
			(hide yes)
			(effects
				(font
					(size 1.27 1.27)
				)
			)
		)
		(property "Value" "2R6F-GP"
			(at -0.0508 -4.8514 270)
			(unlocked yes)
			(layer "F.Fab")
			(hide yes)
			(effects
				(font
					(size 1.016 1.016)
					(thickness 0.1524)
				)
			)
		)
		(property "Device Type" "R1206H26"
			(at 0 -6.3754 270)
			(unlocked yes)
			(layer "F.Fab")
			(hide yes)
			(effects
				(font
					(size 1.016 1.016)
					(thickness 0.1524)
				)
			)
		)
		(duplicate_pad_numbers_are_jumpers no)
		(fp_line
			(start -1.016 2.2352)
			(end -1.016 -2.2352)
			(stroke
				(width 0.1524)
				(type default)
			)
			(layer "F.SilkS")
		)
		(fp_line
			(start 1.016 2.2352)
			(end -1.016 2.2352)
			(stroke
				(width 0.1524)
				(type default)
			)
			(layer "F.SilkS")
		)
		(fp_line
			(start -1.016 -2.2352)
			(end 1.016 -2.2352)
			(stroke
				(width 0.1524)
				(type default)
			)
			(layer "F.SilkS")
		)
		(fp_line
			(start 1.016 -2.2352)
			(end 1.016 2.2352)
			(stroke
				(width 0.1524)
				(type default)
			)
			(layer "F.SilkS")
		)
		(fp_rect
			(start -1.0922 2.3114)
			(end 1.0922 -2.3114)
			(stroke
				(width 0)
				(type default)
			)
			(fill no)
			(layer "F.CrtYd")
		)
		(fp_poly
			(pts
				(xy -1.0922 -2.3114) (xy 1.0922 -2.3114) (xy 1.0922 2.3114) (xy -1.0922 2.3114)
			)
			(stroke
				(width 0)
				(type default)
			)
			(fill no)
			(layer "F.Fab")
		)
		(pad "1" smd rect
			(at 0 -1.397 270)
			(size 1.651 1.27)
			(layers "F.Cu" "F.Mask" "F.Paste")
			(net "P5V_HDD34")
		)
		(pad "2" smd rect
			(at 0 1.397 270)
			(size 1.651 1.27)
			(layers "F.Cu" "F.Mask" "F.Paste")
			(net "5V_PRE_34")
		)
	)
	(footprint ""
		(layer "F.Cu")
		(at 280.444448 -351.351342 90)
		(property "Reference" "R1129"
			(at 0 0 90)
			(layer "F.SilkS")
			(hide yes)
			(effects
				(font
					(size 1.27 1.27)
				)
			)
		)
		(property "Value" "0R2J-2-GP"
			(at 0.064008 -3.993896 90)
			(unlocked yes)
			(layer "F.Fab")
			(hide yes)
			(effects
				(font
					(size 1.016 1.016)
					(thickness 0.1524)
				)
			)
		)
		(property "Device Type" "R402H16"
			(at 0.064008 -5.517896 90)
			(unlocked yes)
			(layer "F.Fab")
			(hide yes)
			(effects
				(font
					(size 1.016 1.016)
					(thickness 0.1524)
				)
			)
		)
		(duplicate_pad_numbers_are_jumpers no)
		(fp_line
			(start 0.508 -0.9398)
			(end -0.508 -0.9398)
			(stroke
				(width 0.1524)
				(type default)
			)
			(layer "F.SilkS")
		)
		(fp_line
			(start -0.508 -0.9398)
			(end -0.508 0.9398)
			(stroke
				(width 0.1524)
				(type default)
			)
			(layer "F.SilkS")
		)
		(fp_rect
			(start -0.508 0.9398)
			(end 0.508 -0.9398)
			(stroke
				(width 0)
				(type default)
			)
			(fill no)
			(layer "F.CrtYd")
		)
		(fp_rect
			(start -0.508 0.9398)
			(end 0.508 -0.9398)
			(stroke
				(width 0)
				(type default)
			)
			(fill no)
			(layer "F.Fab")
		)
		(pad "1" smd custom
			(at 0 -0.4445 90)
			(size 0.1397 0.1397)
			(layers "F.Cu" "F.Mask" "F.Paste")
			(net "P3V3_STBY_B")
			(options
				(clearance outline)
				(anchor circle)
			)
			(primitives
				(gr_poly
					(pts
						(arc
							(start -0.1778 -0.2794)
							(mid -0.249642 -0.249642)
							(end -0.2794 -0.1778)
						)
						(arc
							(start -0.2794 0.1778)
							(mid -0.249642 0.249642)
							(end -0.1778 0.2794)
						)
						(arc
							(start 0.1778 0.2794)
							(mid 0.249642 0.249642)
							(end 0.2794 0.1778)
						)
						(arc
							(start 0.2794 -0.1778)
							(mid 0.249642 -0.249642)
							(end 0.1778 -0.2794)
						)
					)
					(width 0)
					(fill yes)
				)
			)
		)
		(pad "2" smd custom
			(at 0 0.4445 90)
			(size 0.1397 0.1397)
			(layers "F.Cu" "F.Mask" "F.Paste")
			(net "MAX31790_B_PWM_ST0")
			(options
				(clearance outline)
				(anchor circle)
			)
			(primitives
				(gr_poly
					(pts
						(arc
							(start -0.1778 -0.2794)
							(mid -0.249642 -0.249642)
							(end -0.2794 -0.1778)
						)
						(arc
							(start -0.2794 0.1778)
							(mid -0.249642 0.249642)
							(end -0.1778 0.2794)
						)
						(arc
							(start 0.1778 0.2794)
							(mid 0.249642 0.249642)
							(end 0.2794 0.1778)
						)
						(arc
							(start 0.2794 -0.1778)
							(mid 0.249642 -0.249642)
							(end 0.1778 -0.2794)
						)
					)
					(width 0)
					(fill yes)
				)
			)
		)
	)
	(footprint ""
		(layer "F.Cu")
		(at 143.002 -254.127 -90)
		(property "Reference" "C90"
			(at 0 0 270)
			(layer "F.SilkS")
			(hide yes)
			(effects
				(font
					(size 1.27 1.27)
				)
			)
		)
		(property "Value" "SCD033U25V2KX-GP"
			(at 1.1811 -2.7051 270)
			(unlocked yes)
			(layer "F.Fab")
			(hide yes)
			(effects
				(font
					(size 1.016 1.016)
					(thickness 0.1524)
				)
			)
		)
		(property "Device Type" "C402H22"
			(at 1.1811 -4.2291 270)
			(unlocked yes)
			(layer "F.Fab")
			(hide yes)
			(effects
				(font
					(size 1.016 1.016)
					(thickness 0.1524)
				)
			)
		)
		(duplicate_pad_numbers_are_jumpers no)
		(fp_rect
			(start -0.4318 0.9525)
			(end 0.4318 -0.9525)
			(stroke
				(width 0)
				(type default)
			)
			(fill no)
			(layer "F.CrtYd")
		)
		(fp_rect
			(start -0.4318 0.9525)
			(end 0.4318 -0.9525)
			(stroke
				(width 0)
				(type default)
			)
			(fill no)
			(layer "F.Fab")
		)
		(pad "1" smd custom
			(at 0 -0.4445 270)
			(size 0.1524 0.1524)
			(layers "F.Cu" "F.Mask" "F.Paste")
			(net "SW_HDD_P4")
			(options
				(clearance outline)
				(anchor circle)
			)
			(primitives
				(gr_poly
					(pts
						(arc
							(start 0.3048 -0.2032)
							(mid 0.275042 -0.275042)
							(end 0.2032 -0.3048)
						)
						(arc
							(start -0.2032 -0.3048)
							(mid -0.275042 -0.275042)
							(end -0.3048 -0.2032)
						)
						(arc
							(start -0.3048 0.2032)
							(mid -0.275042 0.275042)
							(end -0.2032 0.3048)
						)
						(arc
							(start 0.2032 0.3048)
							(mid 0.275042 0.275042)
							(end 0.3048 0.2032)
						)
					)
					(width 0)
					(fill yes)
				)
			)
		)
		(pad "2" smd custom
			(at 0 0.4445 270)
			(size 0.1524 0.1524)
			(layers "F.Cu" "F.Mask" "F.Paste")
			(net "GND")
			(options
				(clearance outline)
				(anchor circle)
			)
			(primitives
				(gr_poly
					(pts
						(arc
							(start 0.3048 -0.2032)
							(mid 0.275042 -0.275042)
							(end 0.2032 -0.3048)
						)
						(arc
							(start -0.2032 -0.3048)
							(mid -0.275042 -0.275042)
							(end -0.3048 -0.2032)
						)
						(arc
							(start -0.3048 0.2032)
							(mid -0.275042 0.275042)
							(end -0.2032 0.3048)
						)
						(arc
							(start 0.2032 0.3048)
							(mid 0.275042 0.275042)
							(end 0.3048 0.2032)
						)
					)
					(width 0)
					(fill yes)
				)
			)
		)
	)
	(footprint ""
		(layer "F.Cu")
		(at 55.118 -11.049 180)
		(property "Reference" "R659"
			(at 0 0 180)
			(layer "F.SilkS")
			(hide yes)
			(effects
				(font
					(size 1.27 1.27)
				)
			)
		)
		(property "Value" "4K7R2J-2-GP"
			(at 0.064008 -3.993896 180)
			(unlocked yes)
			(layer "F.Fab")
			(hide yes)
			(effects
				(font
					(size 1.016 1.016)
					(thickness 0.1524)
				)
			)
		)
		(property "Device Type" "R402H16"
			(at 0.064008 -5.517896 180)
			(unlocked yes)
			(layer "F.Fab")
			(hide yes)
			(effects
				(font
					(size 1.016 1.016)
					(thickness 0.1524)
				)
			)
		)
		(duplicate_pad_numbers_are_jumpers no)
		(fp_line
			(start 0.508 -0.9398)
			(end -0.508 -0.9398)
			(stroke
				(width 0.1524)
				(type default)
			)
			(layer "F.SilkS")
		)
		(fp_line
			(start -0.508 -0.9398)
			(end -0.508 0.9398)
			(stroke
				(width 0.1524)
				(type default)
			)
			(layer "F.SilkS")
		)
		(fp_rect
			(start -0.508 0.9398)
			(end 0.508 -0.9398)
			(stroke
				(width 0)
				(type default)
			)
			(fill no)
			(layer "F.CrtYd")
		)
		(fp_rect
			(start -0.508 0.9398)
			(end 0.508 -0.9398)
			(stroke
				(width 0)
				(type default)
			)
			(fill no)
			(layer "F.Fab")
		)
		(pad "1" smd custom
			(at 0 -0.4445 180)
			(size 0.1397 0.1397)
			(layers "F.Cu" "F.Mask" "F.Paste")
			(net "P12V_B")
			(options
				(clearance outline)
				(anchor circle)
			)
			(primitives
				(gr_poly
					(pts
						(arc
							(start -0.1778 -0.2794)
							(mid -0.249642 -0.249642)
							(end -0.2794 -0.1778)
						)
						(arc
							(start -0.2794 0.1778)
							(mid -0.249642 0.249642)
							(end -0.1778 0.2794)
						)
						(arc
							(start 0.1778 0.2794)
							(mid 0.249642 0.249642)
							(end 0.2794 0.1778)
						)
						(arc
							(start 0.2794 -0.1778)
							(mid 0.249642 -0.249642)
							(end 0.1778 -0.2794)
						)
					)
					(width 0)
					(fill yes)
				)
			)
		)
		(pad "2" smd custom
			(at 0 0.4445 180)
			(size 0.1397 0.1397)
			(layers "F.Cu" "F.Mask" "F.Paste")
			(net "SW_HDD_R25")
			(options
				(clearance outline)
				(anchor circle)
			)
			(primitives
				(gr_poly
					(pts
						(arc
							(start -0.1778 -0.2794)
							(mid -0.249642 -0.249642)
							(end -0.2794 -0.1778)
						)
						(arc
							(start -0.2794 0.1778)
							(mid -0.249642 0.249642)
							(end -0.1778 0.2794)
						)
						(arc
							(start 0.1778 0.2794)
							(mid 0.249642 0.249642)
							(end 0.2794 0.1778)
						)
						(arc
							(start 0.2794 -0.1778)
							(mid 0.249642 -0.249642)
							(end 0.1778 -0.2794)
						)
					)
					(width 0)
					(fill yes)
				)
			)
		)
	)
	(footprint ""
		(layer "F.Cu")
		(at 253.096522 -358.622346)
		(property "Reference" "R1046"
			(at 0 0 0)
			(layer "F.SilkS")
			(hide yes)
			(effects
				(font
					(size 1.27 1.27)
				)
			)
		)
		(property "Value" "12K4R2F-GP"
			(at 0.064008 -3.993896 0)
			(unlocked yes)
			(layer "F.Fab")
			(hide yes)
			(effects
				(font
					(size 1.016 1.016)
					(thickness 0.1524)
				)
			)
		)
		(property "Device Type" "R402H16"
			(at 0.064008 -5.517896 0)
			(unlocked yes)
			(layer "F.Fab")
			(hide yes)
			(effects
				(font
					(size 1.016 1.016)
					(thickness 0.1524)
				)
			)
		)
		(duplicate_pad_numbers_are_jumpers no)
		(fp_line
			(start -0.508 -0.9398)
			(end -0.508 0.9398)
			(stroke
				(width 0.1524)
				(type default)
			)
			(layer "F.SilkS")
		)
		(fp_line
			(start 0.508 -0.9398)
			(end -0.508 -0.9398)
			(stroke
				(width 0.1524)
				(type default)
			)
			(layer "F.SilkS")
		)
		(fp_rect
			(start -0.508 0.9398)
			(end 0.508 -0.9398)
			(stroke
				(width 0)
				(type default)
			)
			(fill no)
			(layer "F.CrtYd")
		)
		(fp_rect
			(start -0.508 0.9398)
			(end 0.508 -0.9398)
			(stroke
				(width 0)
				(type default)
			)
			(fill no)
			(layer "F.Fab")
		)
		(pad "1" smd custom
			(at 0 -0.4445)
			(size 0.1397 0.1397)
			(layers "F.Cu" "F.Mask" "F.Paste")
			(net "MB3_ISTART_R")
			(options
				(clearance outline)
				(anchor circle)
			)
			(primitives
				(gr_poly
					(pts
						(arc
							(start -0.1778 -0.2794)
							(mid -0.249642 -0.249642)
							(end -0.2794 -0.1778)
						)
						(arc
							(start -0.2794 0.1778)
							(mid -0.249642 0.249642)
							(end -0.1778 0.2794)
						)
						(arc
							(start 0.1778 0.2794)
							(mid 0.249642 0.249642)
							(end 0.2794 0.1778)
						)
						(arc
							(start 0.2794 -0.1778)
							(mid 0.249642 -0.249642)
							(end 0.1778 -0.2794)
						)
					)
					(width 0)
					(fill yes)
				)
			)
		)
		(pad "2" smd custom
			(at 0 0.4445)
			(size 0.1397 0.1397)
			(layers "F.Cu" "F.Mask" "F.Paste")
			(net "AGND_CURRENT_DPB")
			(options
				(clearance outline)
				(anchor circle)
			)
			(primitives
				(gr_poly
					(pts
						(arc
							(start -0.1778 -0.2794)
							(mid -0.249642 -0.249642)
							(end -0.2794 -0.1778)
						)
						(arc
							(start -0.2794 0.1778)
							(mid -0.249642 0.249642)
							(end -0.1778 0.2794)
						)
						(arc
							(start 0.1778 0.2794)
							(mid 0.249642 0.249642)
							(end 0.2794 0.1778)
						)
						(arc
							(start 0.2794 -0.1778)
							(mid 0.249642 -0.249642)
							(end 0.1778 -0.2794)
						)
					)
					(width 0)
					(fill yes)
				)
			)
		)
	)
	(footprint ""
		(layer "F.Cu")
		(at 232.13949 -353.280726 180)
		(property "Reference" "C518"
			(at 0 0 180)
			(layer "F.SilkS")
			(hide yes)
			(effects
				(font
					(size 1.27 1.27)
				)
			)
		)
		(property "Value" "SC22U25V6KX-2-GP-U"
			(at -2.860802 -5.279644 180)
			(unlocked yes)
			(layer "F.Fab")
			(hide yes)
			(effects
				(font
					(size 1.016 1.016)
					(thickness 0.1524)
				)
			)
		)
		(property "Device Type" "C1206-TO0D3H75"
			(at -2.860802 -6.803644 180)
			(unlocked yes)
			(layer "F.Fab")
			(hide yes)
			(effects
				(font
					(size 1.016 1.016)
					(thickness 0.1524)
				)
			)
		)
		(duplicate_pad_numbers_are_jumpers no)
		(fp_line
			(start 1.3081 2.3749)
			(end -1.3081 2.3749)
			(stroke
				(width 0.1524)
				(type default)
			)
			(layer "F.SilkS")
		)
		(fp_line
			(start 1.3081 -2.3749)
			(end 1.3081 2.3749)
			(stroke
				(width 0.1524)
				(type default)
			)
			(layer "F.SilkS")
		)
		(fp_line
			(start -1.3081 2.3749)
			(end -1.3081 -2.3749)
			(stroke
				(width 0.1524)
				(type default)
			)
			(layer "F.SilkS")
		)
		(fp_line
			(start -1.3081 -2.3749)
			(end 1.3081 -2.3749)
			(stroke
				(width 0.1524)
				(type default)
			)
			(layer "F.SilkS")
		)
		(fp_rect
			(start -0.8001 1.6002)
			(end 0.8001 -1.6002)
			(stroke
				(width 0)
				(type default)
			)
			(fill no)
			(layer "F.CrtYd")
		)
		(fp_poly
			(pts
				(xy -1.5621 2.4511) (xy -1.5621 1.6002) (xy 0.8001 1.6002) (xy 0.8001 -1.6002) (xy -0.8001 -1.6002)
				(xy -0.8001 1.5875) (xy -1.5621 1.5875) (xy -1.5621 -2.4511) (xy 1.5621 -2.4511) (xy 1.5621 2.4511)
			)
			(stroke
				(width 0)
				(type default)
			)
			(fill no)
			(layer "F.CrtYd")
		)
		(fp_rect
			(start -1.5621 2.4511)
			(end 1.5621 -2.4511)
			(stroke
				(width 0)
				(type default)
			)
			(fill no)
			(layer "F.Fab")
		)
		(pad "1" smd rect
			(at 0 -1.392936 180)
			(size 2.1082 1.4478)
			(layers "F.Cu" "F.Mask" "F.Paste")
			(net "P12V_IN")
		)
		(pad "2" smd rect
			(at 0 1.392936 180)
			(size 2.1082 1.4478)
			(layers "F.Cu" "F.Mask" "F.Paste")
			(net "GND")
		)
	)
	(footprint ""
		(layer "F.Cu")
		(at 319.216024 -154.70505)
		(property "Reference" "TP111"
			(at 0 0 0)
			(layer "F.SilkS")
			(hide yes)
			(effects
				(font
					(size 1.27 1.27)
				)
			)
		)
		(property "Value" "*"
			(at -0.0508 -1.6764 0)
			(unlocked yes)
			(layer "F.Fab")
			(hide yes)
			(effects
				(font
					(size 1.016 1.016)
					(thickness 0.1524)
				)
			)
		)
		(property "Device Type" "TPAD32"
			(at -0.0508 -3.2004 0)
			(unlocked yes)
			(layer "F.Fab")
			(hide yes)
			(effects
				(font
					(size 1.016 1.016)
					(thickness 0.1524)
				)
			)
		)
		(duplicate_pad_numbers_are_jumpers no)
		(fp_poly
			(pts
				(arc
					(start 0.4064 0)
					(mid -0.4064 0)
					(end 0.4064 0)
				)
			)
			(stroke
				(width 0)
				(type default)
			)
			(fill no)
			(layer "F.CrtYd")
		)
		(fp_poly
			(pts
				(arc
					(start 0.7112 0)
					(mid -0.7112 0)
					(end 0.7112 0)
				)
			)
			(stroke
				(width 0)
				(type default)
			)
			(fill no)
			(layer "F.Fab")
		)
		(pad "1" smd circle
			(at 0 0)
			(size 0.8128 0.8128)
			(layers "F.Cu" "F.Mask" "F.Paste")
			(net "ACT_HDD_18")
		)
	)
	(footprint ""
		(layer "F.Cu")
		(at 462.788 -33.02)
		(property "Reference" "Q180"
			(at 0 0 0)
			(layer "F.SilkS")
			(hide yes)
			(effects
				(font
					(size 1.27 1.27)
				)
			)
		)
		(property "Value" "AO4407AL-GP"
			(at -3.707384 -1.5367 0)
			(unlocked yes)
			(layer "F.Fab")
			(hide yes)
			(effects
				(font
					(size 1.016 1.016)
					(thickness 0.1524)
				)
			)
		)
		(property "Device Type" "SOIC8H69"
			(at -3.707384 -3.0607 0)
			(unlocked yes)
			(layer "F.Fab")
			(hide yes)
			(effects
				(font
					(size 1.016 1.016)
					(thickness 0.1524)
				)
			)
		)
		(duplicate_pad_numbers_are_jumpers no)
		(fp_line
			(start -2.7432 -1.4224)
			(end -2.7432 1.4224)
			(stroke
				(width 0.1524)
				(type default)
			)
			(layer "F.SilkS")
		)
		(fp_line
			(start -2.7432 1.4224)
			(end -2.6416 1.4224)
			(stroke
				(width 0.1524)
				(type default)
			)
			(layer "F.SilkS")
		)
		(fp_line
			(start -2.7432 1.4224)
			(end 2.1336 1.4224)
			(stroke
				(width 0.1524)
				(type default)
			)
			(layer "F.SilkS")
		)
		(fp_line
			(start -2.7178 -0.508)
			(end -2.1844 -0.0508)
			(stroke
				(width 0.1524)
				(type default)
			)
			(layer "F.SilkS")
		)
		(fp_line
			(start -2.6289 3.4417)
			(end -2.6289 1.4732)
			(stroke
				(width 0.381)
				(type default)
			)
			(layer "F.SilkS")
		)
		(fp_line
			(start -2.1844 -0.0508)
			(end -2.7178 0.508)
			(stroke
				(width 0.1524)
				(type default)
			)
			(layer "F.SilkS")
		)
		(fp_line
			(start 2.1336 -1.4224)
			(end -2.7432 -1.4224)
			(stroke
				(width 0.1524)
				(type default)
			)
			(layer "F.SilkS")
		)
		(fp_line
			(start 2.1336 1.4224)
			(end 2.1336 -1.4224)
			(stroke
				(width 0.1524)
				(type default)
			)
			(layer "F.SilkS")
		)
		(fp_poly
			(pts
				(xy -2.2098 -1.4224) (xy -2.2098 1.4224) (xy 2.2098 1.4224) (xy 2.2098 -1.4224)
			)
			(stroke
				(width 0)
				(type default)
			)
			(fill yes)
			(layer "F.SilkS")
		)
		(fp_rect
			(start -2.450084 2.999994)
			(end 2.450084 -2.999994)
			(stroke
				(width 0)
				(type default)
			)
			(fill no)
			(layer "F.CrtYd")
		)
		(fp_poly
			(pts
				(xy -2.8194 3.6322) (xy -2.8194 -3.6322) (xy 2.8194 -3.6322) (xy 2.8194 1.18364) (xy 2.450084 1.18364)
				(xy 2.450084 -2.999994) (xy -2.450084 -2.999994) (xy -2.450084 2.999994) (xy 2.450084 2.999994)
				(xy 2.450084 1.18618) (xy 2.8194 1.18618) (xy 2.8194 3.6322)
			)
			(stroke
				(width 0)
				(type default)
			)
			(fill no)
			(layer "F.CrtYd")
		)
		(fp_rect
			(start -2.8194 3.6322)
			(end 2.8194 -3.6322)
			(stroke
				(width 0)
				(type default)
			)
			(fill no)
			(layer "F.Fab")
		)
		(pad "1" smd rect
			(at -1.905 2.54)
			(size 0.635 1.651)
			(layers "F.Cu" "F.Mask" "F.Paste")
			(net "P12V_B")
		)
		(pad "2" smd rect
			(at -0.635 2.54)
			(size 0.635 1.651)
			(layers "F.Cu" "F.Mask" "F.Paste")
			(net "P12V_B")
		)
		(pad "3" smd rect
			(at 0.635 2.54)
			(size 0.635 1.651)
			(layers "F.Cu" "F.Mask" "F.Paste")
			(net "P12V_B")
		)
		(pad "4" smd rect
			(at 1.905 2.54)
			(size 0.635 1.651)
			(layers "F.Cu" "F.Mask" "F.Paste")
			(net "SW_HDD_N34")
		)
		(pad "5" smd rect
			(at 1.905 -2.54)
			(size 0.635 1.651)
			(layers "F.Cu" "F.Mask" "F.Paste")
			(net "P12V_HDD34")
		)
		(pad "6" smd rect
			(at 0.635 -2.54)
			(size 0.635 1.651)
			(layers "F.Cu" "F.Mask" "F.Paste")
			(net "P12V_HDD34")
		)
		(pad "7" smd rect
			(at -0.635 -2.54)
			(size 0.635 1.651)
			(layers "F.Cu" "F.Mask" "F.Paste")
			(net "P12V_HDD34")
		)
		(pad "8" smd rect
			(at -1.905 -2.54)
			(size 0.635 1.651)
			(layers "F.Cu" "F.Mask" "F.Paste")
			(net "P12V_HDD34")
		)
	)
	(footprint ""
		(layer "F.Cu")
		(at 338.074 -135.509 90)
		(property "Reference" "R500"
			(at 0 0 90)
			(layer "F.SilkS")
			(hide yes)
			(effects
				(font
					(size 1.27 1.27)
				)
			)
		)
		(property "Value" "200KR2F-L-GP"
			(at 0.064008 -3.993896 90)
			(unlocked yes)
			(layer "F.Fab")
			(hide yes)
			(effects
				(font
					(size 1.016 1.016)
					(thickness 0.1524)
				)
			)
		)
		(property "Device Type" "R402H16"
			(at 0.064008 -5.517896 90)
			(unlocked yes)
			(layer "F.Fab")
			(hide yes)
			(effects
				(font
					(size 1.016 1.016)
					(thickness 0.1524)
				)
			)
		)
		(duplicate_pad_numbers_are_jumpers no)
		(fp_line
			(start 0.508 -0.9398)
			(end -0.508 -0.9398)
			(stroke
				(width 0.1524)
				(type default)
			)
			(layer "F.SilkS")
		)
		(fp_line
			(start -0.508 -0.9398)
			(end -0.508 0.9398)
			(stroke
				(width 0.1524)
				(type default)
			)
			(layer "F.SilkS")
		)
		(fp_rect
			(start -0.508 0.9398)
			(end 0.508 -0.9398)
			(stroke
				(width 0)
				(type default)
			)
			(fill no)
			(layer "F.CrtYd")
		)
		(fp_rect
			(start -0.508 0.9398)
			(end 0.508 -0.9398)
			(stroke
				(width 0)
				(type default)
			)
			(fill no)
			(layer "F.Fab")
		)
		(pad "1" smd custom
			(at 0 -0.4445 90)
			(size 0.1397 0.1397)
			(layers "F.Cu" "F.Mask" "F.Paste")
			(net "SW_HDD_R18")
			(options
				(clearance outline)
				(anchor circle)
			)
			(primitives
				(gr_poly
					(pts
						(arc
							(start -0.1778 -0.2794)
							(mid -0.249642 -0.249642)
							(end -0.2794 -0.1778)
						)
						(arc
							(start -0.2794 0.1778)
							(mid -0.249642 0.249642)
							(end -0.1778 0.2794)
						)
						(arc
							(start 0.1778 0.2794)
							(mid 0.249642 0.249642)
							(end 0.2794 0.1778)
						)
						(arc
							(start 0.2794 -0.1778)
							(mid 0.249642 -0.249642)
							(end 0.1778 -0.2794)
						)
					)
					(width 0)
					(fill yes)
				)
			)
		)
		(pad "2" smd custom
			(at 0 0.4445 90)
			(size 0.1397 0.1397)
			(layers "F.Cu" "F.Mask" "F.Paste")
			(net "SW_HDD_N18")
			(options
				(clearance outline)
				(anchor circle)
			)
			(primitives
				(gr_poly
					(pts
						(arc
							(start -0.1778 -0.2794)
							(mid -0.249642 -0.249642)
							(end -0.2794 -0.1778)
						)
						(arc
							(start -0.2794 0.1778)
							(mid -0.249642 0.249642)
							(end -0.1778 0.2794)
						)
						(arc
							(start 0.1778 0.2794)
							(mid 0.249642 0.249642)
							(end 0.2794 0.1778)
						)
						(arc
							(start 0.2794 -0.1778)
							(mid 0.249642 -0.249642)
							(end 0.1778 -0.2794)
						)
					)
					(width 0)
					(fill yes)
				)
			)
		)
	)
	(footprint ""
		(layer "F.Cu")
		(at 364.998 -274.955 180)
		(property "Reference" "C127"
			(at 0 0 180)
			(layer "F.SilkS")
			(hide yes)
			(effects
				(font
					(size 1.27 1.27)
				)
			)
		)
		(property "Value" "SC4D7U25V5KX-1-GP"
			(at -0.0762 -6.1214 180)
			(unlocked yes)
			(layer "F.Fab")
			(hide yes)
			(effects
				(font
					(size 1.016 1.016)
					(thickness 0.1524)
				)
			)
		)
		(property "Device Type" "C805H58"
			(at -0.0762 -8.1534 180)
			(unlocked yes)
			(layer "F.Fab")
			(hide yes)
			(effects
				(font
					(size 1.016 1.016)
					(thickness 0.1524)
				)
			)
		)
		(duplicate_pad_numbers_are_jumpers no)
		(fp_line
			(start 0.635 0)
			(end -0.635 0)
			(stroke
				(width 0.508)
				(type default)
			)
			(layer "F.SilkS")
		)
		(fp_rect
			(start -0.9652 1.778)
			(end 0.9652 -1.778)
			(stroke
				(width 0)
				(type default)
			)
			(fill no)
			(layer "F.CrtYd")
		)
		(fp_poly
			(pts
				(xy -0.9652 -1.778) (xy 0.9652 -1.778) (xy 0.9652 1.778) (xy -0.9652 1.778)
			)
			(stroke
				(width 0)
				(type default)
			)
			(fill no)
			(layer "F.Fab")
		)
		(pad "1" smd rect
			(at 0 -0.9652 180)
			(size 1.397 1.143)
			(layers "F.Cu" "F.Mask" "F.Paste")
			(net "P12V_HDD7")
		)
		(pad "2" smd rect
			(at 0 0.9652 180)
			(size 1.397 1.143)
			(layers "F.Cu" "F.Mask" "F.Paste")
			(net "GND")
		)
	)
	(footprint ""
		(layer "F.Cu")
		(at 48.029368 -99.798378 90)
		(property "Reference" "Q256"
			(at 0 0 90)
			(layer "F.SilkS")
			(hide yes)
			(effects
				(font
					(size 1.27 1.27)
				)
			)
		)
		(property "Value" "SSM3K324R-GP"
			(at 0.127 -8.9662 90)
			(unlocked yes)
			(layer "F.Fab")
			(hide yes)
			(effects
				(font
					(size 1.016 1.016)
					(thickness 0.1524)
				)
			)
		)
		(property "Device Type" "SOT23DGS2D4H35"
			(at 0.127 -10.4902 90)
			(unlocked yes)
			(layer "F.Fab")
			(hide yes)
			(effects
				(font
					(size 1.016 1.016)
					(thickness 0.1524)
				)
			)
		)
		(duplicate_pad_numbers_are_jumpers no)
		(fp_line
			(start 1.651 -1.778)
			(end -1.651 -1.778)
			(stroke
				(width 0.1524)
				(type default)
			)
			(layer "F.SilkS")
		)
		(fp_line
			(start -1.651 -1.778)
			(end -1.651 1.778)
			(stroke
				(width 0.1524)
				(type default)
			)
			(layer "F.SilkS")
		)
		(fp_line
			(start 1.651 1.778)
			(end 1.651 -1.778)
			(stroke
				(width 0.1524)
				(type default)
			)
			(layer "F.SilkS")
		)
		(fp_line
			(start -1.651 1.778)
			(end 1.651 1.778)
			(stroke
				(width 0.1524)
				(type default)
			)
			(layer "F.SilkS")
		)
		(fp_poly
			(pts
				(xy -1.778 1.8796) (xy -1.778 -1.8796) (xy 1.778 -1.8796) (xy 1.778 1.8796)
			)
			(stroke
				(width 0)
				(type default)
			)
			(fill no)
			(layer "F.CrtYd")
		)
		(fp_poly
			(pts
				(xy -1.778 1.8796) (xy -1.778 -1.8796) (xy 1.778 -1.8796) (xy 1.778 1.8796)
			)
			(stroke
				(width 0)
				(type default)
			)
			(fill no)
			(layer "F.Fab")
		)
		(pad "D" smd custom
			(at 0 -0.9525 90)
			(size 0.1905 0.1905)
			(layers "F.Cu" "F.Mask" "F.Paste")
			(net "DRV_ACT_13_N")
			(options
				(clearance outline)
				(anchor circle)
			)
			(primitives
				(gr_poly
					(pts
						(arc
							(start -0.1778 0.5715)
							(mid -0.321484 0.511984)
							(end -0.381 0.3683)
						)
						(arc
							(start -0.381 -0.3683)
							(mid -0.321484 -0.511984)
							(end -0.1778 -0.5715)
						)
						(arc
							(start 0.1778 -0.5715)
							(mid 0.321484 -0.511984)
							(end 0.381 -0.3683)
						)
						(arc
							(start 0.381 0.3683)
							(mid 0.321484 0.511984)
							(end 0.1778 0.5715)
						)
					)
					(width 0)
					(fill yes)
				)
			)
		)
		(pad "G" smd custom
			(at -0.98425 0.9525 90)
			(size 0.1905 0.1905)
			(layers "F.Cu" "F.Mask" "F.Paste")
			(net "DRIVE_B_13_ACT")
			(options
				(clearance outline)
				(anchor circle)
			)
			(primitives
				(gr_poly
					(pts
						(arc
							(start -0.1778 0.5715)
							(mid -0.321484 0.511984)
							(end -0.381 0.3683)
						)
						(arc
							(start -0.381 -0.3683)
							(mid -0.321484 -0.511984)
							(end -0.1778 -0.5715)
						)
						(arc
							(start 0.1778 -0.5715)
							(mid 0.321484 -0.511984)
							(end 0.381 -0.3683)
						)
						(arc
							(start 0.381 0.3683)
							(mid 0.321484 0.511984)
							(end 0.1778 0.5715)
						)
					)
					(width 0)
					(fill yes)
				)
			)
		)
		(pad "S" smd custom
			(at 0.98425 0.9525 90)
			(size 0.1905 0.1905)
			(layers "F.Cu" "F.Mask" "F.Paste")
			(net "GND")
			(options
				(clearance outline)
				(anchor circle)
			)
			(primitives
				(gr_poly
					(pts
						(arc
							(start -0.1778 0.5715)
							(mid -0.321484 0.511984)
							(end -0.381 0.3683)
						)
						(arc
							(start -0.381 -0.3683)
							(mid -0.321484 -0.511984)
							(end -0.1778 -0.5715)
						)
						(arc
							(start 0.1778 -0.5715)
							(mid 0.321484 -0.511984)
							(end 0.381 -0.3683)
						)
						(arc
							(start 0.381 0.3683)
							(mid 0.321484 0.511984)
							(end 0.1778 0.5715)
						)
					)
					(width 0)
					(fill yes)
				)
			)
		)
	)
	(footprint ""
		(layer "F.Cu")
		(at 349.7326 -261.3152)
		(property "Reference" "R273"
			(at 0 0 0)
			(layer "F.SilkS")
			(hide yes)
			(effects
				(font
					(size 1.27 1.27)
				)
			)
		)
		(property "Value" "220R3F-1-GP"
			(at -0.0254 -2.5146 0)
			(unlocked yes)
			(layer "F.Fab")
			(hide yes)
			(effects
				(font
					(size 1.016 1.016)
					(thickness 0.1524)
				)
			)
		)
		(property "Device Type" "R603H22"
			(at -0.0254 -4.0386 0)
			(unlocked yes)
			(layer "F.Fab")
			(hide yes)
			(effects
				(font
					(size 1.016 1.016)
					(thickness 0.1524)
				)
			)
		)
		(duplicate_pad_numbers_are_jumpers no)
		(fp_line
			(start -0.4826 0)
			(end -0.2032 0)
			(stroke
				(width 0.2032)
				(type default)
			)
			(layer "F.SilkS")
		)
		(fp_line
			(start 0.2032 0)
			(end 0.4826 0)
			(stroke
				(width 0.2032)
				(type default)
			)
			(layer "F.SilkS")
		)
		(fp_rect
			(start -0.5842 1.3335)
			(end 0.5842 -1.3335)
			(stroke
				(width 0)
				(type default)
			)
			(fill no)
			(layer "F.CrtYd")
		)
		(fp_rect
			(start -0.5842 1.3335)
			(end 0.5842 -1.3335)
			(stroke
				(width 0)
				(type default)
			)
			(fill no)
			(layer "F.Fab")
		)
		(pad "1" smd custom
			(at 0 -0.762)
			(size 0.2159 0.2159)
			(layers "F.Cu" "F.Mask" "F.Paste")
			(net "HDD_PRSNT_7")
			(options
				(clearance outline)
				(anchor circle)
			)
			(primitives
				(gr_poly
					(pts
						(arc
							(start -0.3302 -0.4318)
							(mid -0.402042 -0.402042)
							(end -0.4318 -0.3302)
						)
						(arc
							(start -0.4318 0.3302)
							(mid -0.402042 0.402042)
							(end -0.3302 0.4318)
						)
						(arc
							(start 0.3302 0.4318)
							(mid 0.402042 0.402042)
							(end 0.4318 0.3302)
						)
						(arc
							(start 0.4318 -0.3302)
							(mid 0.402042 -0.402042)
							(end 0.3302 -0.4318)
						)
					)
					(width 0)
					(fill yes)
				)
			)
		)
		(pad "2" smd custom
			(at 0 0.762)
			(size 0.2159 0.2159)
			(layers "F.Cu" "F.Mask" "F.Paste")
			(net "DRIVE_B_7_INS")
			(options
				(clearance outline)
				(anchor circle)
			)
			(primitives
				(gr_poly
					(pts
						(arc
							(start -0.3302 -0.4318)
							(mid -0.402042 -0.402042)
							(end -0.4318 -0.3302)
						)
						(arc
							(start -0.4318 0.3302)
							(mid -0.402042 0.402042)
							(end -0.3302 0.4318)
						)
						(arc
							(start 0.3302 0.4318)
							(mid 0.402042 0.402042)
							(end 0.4318 0.3302)
						)
						(arc
							(start 0.4318 -0.3302)
							(mid 0.402042 -0.402042)
							(end 0.3302 -0.4318)
						)
					)
					(width 0)
					(fill yes)
				)
			)
		)
	)
	(footprint ""
		(layer "F.Cu")
		(at 464.185 -135.509 90)
		(property "Reference" "R592"
			(at 0 0 90)
			(layer "F.SilkS")
			(hide yes)
			(effects
				(font
					(size 1.27 1.27)
				)
			)
		)
		(property "Value" "200KR2F-L-GP"
			(at 0.064008 -3.993896 90)
			(unlocked yes)
			(layer "F.Fab")
			(hide yes)
			(effects
				(font
					(size 1.016 1.016)
					(thickness 0.1524)
				)
			)
		)
		(property "Device Type" "R402H16"
			(at 0.064008 -5.517896 90)
			(unlocked yes)
			(layer "F.Fab")
			(hide yes)
			(effects
				(font
					(size 1.016 1.016)
					(thickness 0.1524)
				)
			)
		)
		(duplicate_pad_numbers_are_jumpers no)
		(fp_line
			(start 0.508 -0.9398)
			(end -0.508 -0.9398)
			(stroke
				(width 0.1524)
				(type default)
			)
			(layer "F.SilkS")
		)
		(fp_line
			(start -0.508 -0.9398)
			(end -0.508 0.9398)
			(stroke
				(width 0.1524)
				(type default)
			)
			(layer "F.SilkS")
		)
		(fp_rect
			(start -0.508 0.9398)
			(end 0.508 -0.9398)
			(stroke
				(width 0)
				(type default)
			)
			(fill no)
			(layer "F.CrtYd")
		)
		(fp_rect
			(start -0.508 0.9398)
			(end 0.508 -0.9398)
			(stroke
				(width 0)
				(type default)
			)
			(fill no)
			(layer "F.Fab")
		)
		(pad "1" smd custom
			(at 0 -0.4445 90)
			(size 0.1397 0.1397)
			(layers "F.Cu" "F.Mask" "F.Paste")
			(net "SW_HDD_R22")
			(options
				(clearance outline)
				(anchor circle)
			)
			(primitives
				(gr_poly
					(pts
						(arc
							(start -0.1778 -0.2794)
							(mid -0.249642 -0.249642)
							(end -0.2794 -0.1778)
						)
						(arc
							(start -0.2794 0.1778)
							(mid -0.249642 0.249642)
							(end -0.1778 0.2794)
						)
						(arc
							(start 0.1778 0.2794)
							(mid 0.249642 0.249642)
							(end 0.2794 0.1778)
						)
						(arc
							(start 0.2794 -0.1778)
							(mid 0.249642 -0.249642)
							(end 0.1778 -0.2794)
						)
					)
					(width 0)
					(fill yes)
				)
			)
		)
		(pad "2" smd custom
			(at 0 0.4445 90)
			(size 0.1397 0.1397)
			(layers "F.Cu" "F.Mask" "F.Paste")
			(net "SW_HDD_N22")
			(options
				(clearance outline)
				(anchor circle)
			)
			(primitives
				(gr_poly
					(pts
						(arc
							(start -0.1778 -0.2794)
							(mid -0.249642 -0.249642)
							(end -0.2794 -0.1778)
						)
						(arc
							(start -0.2794 0.1778)
							(mid -0.249642 0.249642)
							(end -0.1778 0.2794)
						)
						(arc
							(start 0.1778 0.2794)
							(mid 0.249642 0.249642)
							(end 0.2794 0.1778)
						)
						(arc
							(start 0.2794 -0.1778)
							(mid 0.249642 -0.249642)
							(end 0.1778 -0.2794)
						)
					)
					(width 0)
					(fill yes)
				)
			)
		)
	)
	(footprint ""
		(layer "F.Cu")
		(at 98.425 -262.128 90)
		(property "Reference" "C63"
			(at 0 0 90)
			(layer "F.SilkS")
			(hide yes)
			(effects
				(font
					(size 1.27 1.27)
				)
			)
		)
		(property "Value" "SCD01U50V2KX-1GP"
			(at 1.1811 -2.7051 90)
			(unlocked yes)
			(layer "F.Fab")
			(hide yes)
			(effects
				(font
					(size 1.016 1.016)
					(thickness 0.1524)
				)
			)
		)
		(property "Device Type" "C402H22"
			(at 1.1811 -4.2291 90)
			(unlocked yes)
			(layer "F.Fab")
			(hide yes)
			(effects
				(font
					(size 1.016 1.016)
					(thickness 0.1524)
				)
			)
		)
		(duplicate_pad_numbers_are_jumpers no)
		(fp_rect
			(start -0.4318 0.9525)
			(end 0.4318 -0.9525)
			(stroke
				(width 0)
				(type default)
			)
			(fill no)
			(layer "F.CrtYd")
		)
		(fp_rect
			(start -0.4318 0.9525)
			(end 0.4318 -0.9525)
			(stroke
				(width 0)
				(type default)
			)
			(fill no)
			(layer "F.Fab")
		)
		(pad "1" smd custom
			(at 0 -0.4445 90)
			(size 0.1524 0.1524)
			(layers "F.Cu" "F.Mask" "F.Paste")
			(net "HDD_PRSNT_2")
			(options
				(clearance outline)
				(anchor circle)
			)
			(primitives
				(gr_poly
					(pts
						(arc
							(start 0.3048 -0.2032)
							(mid 0.275042 -0.275042)
							(end 0.2032 -0.3048)
						)
						(arc
							(start -0.2032 -0.3048)
							(mid -0.275042 -0.275042)
							(end -0.3048 -0.2032)
						)
						(arc
							(start -0.3048 0.2032)
							(mid -0.275042 0.275042)
							(end -0.2032 0.3048)
						)
						(arc
							(start 0.2032 0.3048)
							(mid 0.275042 0.275042)
							(end 0.3048 0.2032)
						)
					)
					(width 0)
					(fill yes)
				)
			)
		)
		(pad "2" smd custom
			(at 0 0.4445 90)
			(size 0.1524 0.1524)
			(layers "F.Cu" "F.Mask" "F.Paste")
			(net "GND")
			(options
				(clearance outline)
				(anchor circle)
			)
			(primitives
				(gr_poly
					(pts
						(arc
							(start 0.3048 -0.2032)
							(mid 0.275042 -0.275042)
							(end 0.2032 -0.3048)
						)
						(arc
							(start -0.2032 -0.3048)
							(mid -0.275042 -0.275042)
							(end -0.3048 -0.2032)
						)
						(arc
							(start -0.3048 0.2032)
							(mid -0.275042 0.275042)
							(end -0.2032 0.3048)
						)
						(arc
							(start 0.2032 0.3048)
							(mid 0.275042 0.275042)
							(end 0.3048 0.2032)
						)
					)
					(width 0)
					(fill yes)
				)
			)
		)
	)
	(footprint ""
		(layer "F.Cu")
		(at 55.753 -160.401 180)
		(property "Reference" "C206"
			(at 0 0 180)
			(layer "F.SilkS")
			(hide yes)
			(effects
				(font
					(size 1.27 1.27)
				)
			)
		)
		(property "Value" "SC1U25V3KX-GP"
			(at 0 -2.8194 180)
			(unlocked yes)
			(layer "F.Fab")
			(hide yes)
			(effects
				(font
					(size 1.016 1.016)
					(thickness 0.1524)
				)
			)
		)
		(property "Device Type" "C603H36"
			(at 0 -4.3434 180)
			(unlocked yes)
			(layer "F.Fab")
			(hide yes)
			(effects
				(font
					(size 1.016 1.016)
					(thickness 0.1524)
				)
			)
		)
		(duplicate_pad_numbers_are_jumpers no)
		(fp_line
			(start 0.508 0)
			(end -0.508 0)
			(stroke
				(width 0.2032)
				(type default)
			)
			(layer "F.SilkS")
		)
		(fp_rect
			(start -0.5842 1.3335)
			(end 0.5842 -1.3335)
			(stroke
				(width 0)
				(type default)
			)
			(fill no)
			(layer "F.CrtYd")
		)
		(fp_rect
			(start -0.5842 1.3335)
			(end 0.5842 -1.3335)
			(stroke
				(width 0)
				(type default)
			)
			(fill no)
			(layer "F.Fab")
		)
		(pad "1" smd custom
			(at 0 -0.762 180)
			(size 0.2159 0.2159)
			(layers "F.Cu" "F.Mask" "F.Paste")
			(net "P12V_HDD13")
			(options
				(clearance outline)
				(anchor circle)
			)
			(primitives
				(gr_poly
					(pts
						(arc
							(start -0.3302 -0.4318)
							(mid -0.402042 -0.402042)
							(end -0.4318 -0.3302)
						)
						(arc
							(start -0.4318 0.3302)
							(mid -0.402042 0.402042)
							(end -0.3302 0.4318)
						)
						(arc
							(start 0.3302 0.4318)
							(mid 0.402042 0.402042)
							(end 0.4318 0.3302)
						)
						(arc
							(start 0.4318 -0.3302)
							(mid 0.402042 -0.402042)
							(end 0.3302 -0.4318)
						)
					)
					(width 0)
					(fill yes)
				)
			)
		)
		(pad "2" smd custom
			(at 0 0.762 180)
			(size 0.2159 0.2159)
			(layers "F.Cu" "F.Mask" "F.Paste")
			(net "GND")
			(options
				(clearance outline)
				(anchor circle)
			)
			(primitives
				(gr_poly
					(pts
						(arc
							(start -0.3302 -0.4318)
							(mid -0.402042 -0.402042)
							(end -0.4318 -0.3302)
						)
						(arc
							(start -0.4318 0.3302)
							(mid -0.402042 0.402042)
							(end -0.3302 0.4318)
						)
						(arc
							(start 0.3302 0.4318)
							(mid 0.402042 0.402042)
							(end 0.4318 0.3302)
						)
						(arc
							(start 0.4318 -0.3302)
							(mid 0.402042 -0.402042)
							(end 0.3302 -0.4318)
						)
					)
					(width 0)
					(fill yes)
				)
			)
		)
	)
	(footprint ""
		(layer "F.Cu")
		(at 83.82 -26.289 180)
		(property "Reference" "Q129"
			(at 0 0 180)
			(layer "F.SilkS")
			(hide yes)
			(effects
				(font
					(size 1.27 1.27)
				)
			)
		)
		(property "Value" "AO4406AL-GP"
			(at -3.707384 -1.5367 180)
			(unlocked yes)
			(layer "F.Fab")
			(hide yes)
			(effects
				(font
					(size 1.016 1.016)
					(thickness 0.1524)
				)
			)
		)
		(property "Device Type" "SOIC8H69"
			(at -3.707384 -3.0607 180)
			(unlocked yes)
			(layer "F.Fab")
			(hide yes)
			(effects
				(font
					(size 1.016 1.016)
					(thickness 0.1524)
				)
			)
		)
		(duplicate_pad_numbers_are_jumpers no)
		(fp_line
			(start 2.1336 1.4224)
			(end 2.1336 -1.4224)
			(stroke
				(width 0.1524)
				(type default)
			)
			(layer "F.SilkS")
		)
		(fp_line
			(start 2.1336 -1.4224)
			(end -2.7432 -1.4224)
			(stroke
				(width 0.1524)
				(type default)
			)
			(layer "F.SilkS")
		)
		(fp_line
			(start -2.1844 -0.0508)
			(end -2.7178 0.508)
			(stroke
				(width 0.1524)
				(type default)
			)
			(layer "F.SilkS")
		)
		(fp_line
			(start -2.6289 3.4417)
			(end -2.6289 1.4732)
			(stroke
				(width 0.381)
				(type default)
			)
			(layer "F.SilkS")
		)
		(fp_line
			(start -2.7178 -0.508)
			(end -2.1844 -0.0508)
			(stroke
				(width 0.1524)
				(type default)
			)
			(layer "F.SilkS")
		)
		(fp_line
			(start -2.7432 1.4224)
			(end 2.1336 1.4224)
			(stroke
				(width 0.1524)
				(type default)
			)
			(layer "F.SilkS")
		)
		(fp_line
			(start -2.7432 1.4224)
			(end -2.6416 1.4224)
			(stroke
				(width 0.1524)
				(type default)
			)
			(layer "F.SilkS")
		)
		(fp_line
			(start -2.7432 -1.4224)
			(end -2.7432 1.4224)
			(stroke
				(width 0.1524)
				(type default)
			)
			(layer "F.SilkS")
		)
		(fp_poly
			(pts
				(xy -2.2098 -1.4224) (xy -2.2098 1.4224) (xy 2.2098 1.4224) (xy 2.2098 -1.4224)
			)
			(stroke
				(width 0)
				(type default)
			)
			(fill yes)
			(layer "F.SilkS")
		)
		(fp_rect
			(start -2.450084 2.999994)
			(end 2.450084 -2.999994)
			(stroke
				(width 0)
				(type default)
			)
			(fill no)
			(layer "F.CrtYd")
		)
		(fp_poly
			(pts
				(xy -2.8194 3.6322) (xy -2.8194 -3.6322) (xy 2.8194 -3.6322) (xy 2.8194 1.18364) (xy 2.450084 1.18364)
				(xy 2.450084 -2.999994) (xy -2.450084 -2.999994) (xy -2.450084 2.999994) (xy 2.450084 2.999994)
				(xy 2.450084 1.18618) (xy 2.8194 1.18618) (xy 2.8194 3.6322)
			)
			(stroke
				(width 0)
				(type default)
			)
			(fill no)
			(layer "F.CrtYd")
		)
		(fp_rect
			(start -2.8194 3.6322)
			(end 2.8194 -3.6322)
			(stroke
				(width 0)
				(type default)
			)
			(fill no)
			(layer "F.Fab")
		)
		(pad "1" smd rect
			(at -1.905 2.54 180)
			(size 0.635 1.651)
			(layers "F.Cu" "F.Mask" "F.Paste")
			(net "P5V_HDD26")
		)
		(pad "2" smd rect
			(at -0.635 2.54 180)
			(size 0.635 1.651)
			(layers "F.Cu" "F.Mask" "F.Paste")
			(net "P5V_HDD26")
		)
		(pad "3" smd rect
			(at 0.635 2.54 180)
			(size 0.635 1.651)
			(layers "F.Cu" "F.Mask" "F.Paste")
			(net "P5V_HDD26")
		)
		(pad "4" smd rect
			(at 1.905 2.54 180)
			(size 0.635 1.651)
			(layers "F.Cu" "F.Mask" "F.Paste")
			(net "SW_HDD_P26")
		)
		(pad "5" smd rect
			(at 1.905 -2.54 180)
			(size 0.635 1.651)
			(layers "F.Cu" "F.Mask" "F.Paste")
			(net "P5V_B_2")
		)
		(pad "6" smd rect
			(at 0.635 -2.54 180)
			(size 0.635 1.651)
			(layers "F.Cu" "F.Mask" "F.Paste")
			(net "P5V_B_2")
		)
		(pad "7" smd rect
			(at -0.635 -2.54 180)
			(size 0.635 1.651)
			(layers "F.Cu" "F.Mask" "F.Paste")
			(net "P5V_B_2")
		)
		(pad "8" smd rect
			(at -1.905 -2.54 180)
			(size 0.635 1.651)
			(layers "F.Cu" "F.Mask" "F.Paste")
			(net "P5V_B_2")
		)
	)
	(footprint ""
		(layer "F.Cu")
		(at 249.7582 -132.1562 180)
		(property "Reference" "R601"
			(at 0 0 180)
			(layer "F.SilkS")
			(hide yes)
			(effects
				(font
					(size 1.27 1.27)
				)
			)
		)
		(property "Value" "2K2R2F-GP"
			(at 0.064008 -3.993896 180)
			(unlocked yes)
			(layer "F.Fab")
			(hide yes)
			(effects
				(font
					(size 1.016 1.016)
					(thickness 0.1524)
				)
			)
		)
		(property "Device Type" "R402H16"
			(at 0.064008 -5.517896 180)
			(unlocked yes)
			(layer "F.Fab")
			(hide yes)
			(effects
				(font
					(size 1.016 1.016)
					(thickness 0.1524)
				)
			)
		)
		(duplicate_pad_numbers_are_jumpers no)
		(fp_line
			(start 0.508 -0.9398)
			(end -0.508 -0.9398)
			(stroke
				(width 0.1524)
				(type default)
			)
			(layer "F.SilkS")
		)
		(fp_line
			(start -0.508 -0.9398)
			(end -0.508 0.9398)
			(stroke
				(width 0.1524)
				(type default)
			)
			(layer "F.SilkS")
		)
		(fp_rect
			(start -0.508 0.9398)
			(end 0.508 -0.9398)
			(stroke
				(width 0)
				(type default)
			)
			(fill no)
			(layer "F.CrtYd")
		)
		(fp_rect
			(start -0.508 0.9398)
			(end 0.508 -0.9398)
			(stroke
				(width 0)
				(type default)
			)
			(fill no)
			(layer "F.Fab")
		)
		(pad "1" smd custom
			(at 0 -0.4445 180)
			(size 0.1397 0.1397)
			(layers "F.Cu" "F.Mask" "F.Paste")
			(net "P3V3_STBY_B")
			(options
				(clearance outline)
				(anchor circle)
			)
			(primitives
				(gr_poly
					(pts
						(arc
							(start -0.1778 -0.2794)
							(mid -0.249642 -0.249642)
							(end -0.2794 -0.1778)
						)
						(arc
							(start -0.2794 0.1778)
							(mid -0.249642 0.249642)
							(end -0.1778 0.2794)
						)
						(arc
							(start 0.1778 0.2794)
							(mid 0.249642 0.249642)
							(end 0.2794 0.1778)
						)
						(arc
							(start 0.2794 -0.1778)
							(mid 0.249642 -0.249642)
							(end 0.1778 -0.2794)
						)
					)
					(width 0)
					(fill yes)
				)
			)
		)
		(pad "2" smd custom
			(at 0 0.4445 180)
			(size 0.1397 0.1397)
			(layers "F.Cu" "F.Mask" "F.Paste")
			(net "I2C_DPB_B_SDA")
			(options
				(clearance outline)
				(anchor circle)
			)
			(primitives
				(gr_poly
					(pts
						(arc
							(start -0.1778 -0.2794)
							(mid -0.249642 -0.249642)
							(end -0.2794 -0.1778)
						)
						(arc
							(start -0.2794 0.1778)
							(mid -0.249642 0.249642)
							(end -0.1778 0.2794)
						)
						(arc
							(start 0.1778 0.2794)
							(mid 0.249642 0.249642)
							(end 0.2794 0.1778)
						)
						(arc
							(start 0.2794 -0.1778)
							(mid 0.249642 -0.249642)
							(end 0.1778 -0.2794)
						)
					)
					(width 0)
					(fill yes)
				)
			)
		)
	)
	(footprint ""
		(layer "F.Cu")
		(at 273.5834 -330.04125 90)
		(property "Reference" "R91"
			(at 0 0 90)
			(layer "F.SilkS")
			(hide yes)
			(effects
				(font
					(size 1.27 1.27)
				)
			)
		)
		(property "Value" "4K7R2F-GP"
			(at 0.064008 -3.993896 90)
			(unlocked yes)
			(layer "F.Fab")
			(hide yes)
			(effects
				(font
					(size 1.016 1.016)
					(thickness 0.1524)
				)
			)
		)
		(property "Device Type" "R402H16"
			(at 0.064008 -5.517896 90)
			(unlocked yes)
			(layer "F.Fab")
			(hide yes)
			(effects
				(font
					(size 1.016 1.016)
					(thickness 0.1524)
				)
			)
		)
		(duplicate_pad_numbers_are_jumpers no)
		(fp_line
			(start 0.508 -0.9398)
			(end -0.508 -0.9398)
			(stroke
				(width 0.1524)
				(type default)
			)
			(layer "F.SilkS")
		)
		(fp_line
			(start -0.508 -0.9398)
			(end -0.508 0.9398)
			(stroke
				(width 0.1524)
				(type default)
			)
			(layer "F.SilkS")
		)
		(fp_rect
			(start -0.508 0.9398)
			(end 0.508 -0.9398)
			(stroke
				(width 0)
				(type default)
			)
			(fill no)
			(layer "F.CrtYd")
		)
		(fp_rect
			(start -0.508 0.9398)
			(end 0.508 -0.9398)
			(stroke
				(width 0)
				(type default)
			)
			(fill no)
			(layer "F.Fab")
		)
		(pad "1" smd custom
			(at 0 -0.4445 90)
			(size 0.1397 0.1397)
			(layers "F.Cu" "F.Mask" "F.Paste")
			(net "P3V3_IN")
			(options
				(clearance outline)
				(anchor circle)
			)
			(primitives
				(gr_poly
					(pts
						(arc
							(start -0.1778 -0.2794)
							(mid -0.249642 -0.249642)
							(end -0.2794 -0.1778)
						)
						(arc
							(start -0.2794 0.1778)
							(mid -0.249642 0.249642)
							(end -0.1778 0.2794)
						)
						(arc
							(start 0.1778 0.2794)
							(mid 0.249642 0.249642)
							(end 0.2794 0.1778)
						)
						(arc
							(start 0.2794 -0.1778)
							(mid 0.249642 -0.249642)
							(end 0.1778 -0.2794)
						)
					)
					(width 0)
					(fill yes)
				)
			)
		)
		(pad "2" smd custom
			(at 0 0.4445 90)
			(size 0.1397 0.1397)
			(layers "F.Cu" "F.Mask" "F.Paste")
			(net "PWM_OUT_FAN2")
			(options
				(clearance outline)
				(anchor circle)
			)
			(primitives
				(gr_poly
					(pts
						(arc
							(start -0.1778 -0.2794)
							(mid -0.249642 -0.249642)
							(end -0.2794 -0.1778)
						)
						(arc
							(start -0.2794 0.1778)
							(mid -0.249642 0.249642)
							(end -0.1778 0.2794)
						)
						(arc
							(start 0.1778 0.2794)
							(mid 0.249642 0.249642)
							(end 0.2794 0.1778)
						)
						(arc
							(start 0.2794 -0.1778)
							(mid 0.249642 -0.249642)
							(end 0.1778 -0.2794)
						)
					)
					(width 0)
					(fill yes)
				)
			)
		)
	)
	(footprint ""
		(layer "F.Cu")
		(at 469.773 -136.525 180)
		(property "Reference" "D23"
			(at 0 0 180)
			(layer "F.SilkS")
			(hide yes)
			(effects
				(font
					(size 1.27 1.27)
				)
			)
		)
		(property "Value" "RB551V30-GP"
			(at 0 -6.7818 180)
			(unlocked yes)
			(layer "F.Fab")
			(hide yes)
			(effects
				(font
					(size 1.016 1.016)
					(thickness 0.1524)
				)
			)
		)
		(property "Device Type" "SOD323AKH38"
			(at 0 -8.6868 180)
			(unlocked yes)
			(layer "F.Fab")
			(hide yes)
			(effects
				(font
					(size 1.016 1.016)
					(thickness 0.1524)
				)
			)
		)
		(duplicate_pad_numbers_are_jumpers no)
		(fp_line
			(start 0.889 2.159)
			(end -0.889 2.159)
			(stroke
				(width 0.1524)
				(type default)
			)
			(layer "F.SilkS")
		)
		(fp_line
			(start 0.889 -1.9304)
			(end 0.889 2.159)
			(stroke
				(width 0.1524)
				(type default)
			)
			(layer "F.SilkS")
		)
		(fp_line
			(start 0.762 2.0574)
			(end -0.762 2.0574)
			(stroke
				(width 0.508)
				(type default)
			)
			(layer "F.SilkS")
		)
		(fp_line
			(start -0.889 2.159)
			(end -0.889 -1.9304)
			(stroke
				(width 0.1524)
				(type default)
			)
			(layer "F.SilkS")
		)
		(fp_line
			(start -0.889 -1.9304)
			(end 0.889 -1.9304)
			(stroke
				(width 0.1524)
				(type default)
			)
			(layer "F.SilkS")
		)
		(fp_rect
			(start -1.016 2.3114)
			(end 1.016 -2.0066)
			(stroke
				(width 0)
				(type default)
			)
			(fill no)
			(layer "F.CrtYd")
		)
		(fp_poly
			(pts
				(xy -1.016 -2.0066) (xy 1.016 -2.0066) (xy 1.016 2.3114) (xy -1.016 2.3114)
			)
			(stroke
				(width 0)
				(type default)
			)
			(fill no)
			(layer "F.Fab")
		)
		(pad "A" smd rect
			(at 0 -1.143 180)
			(size 0.5588 1.016)
			(layers "F.Cu" "F.Mask" "F.Paste")
			(net "SW_HDD_R23")
		)
		(pad "K" smd rect
			(at 0 1.143 180)
			(size 0.5588 1.016)
			(layers "F.Cu" "F.Mask" "F.Paste")
			(net "SW_HDD_N23")
		)
	)
	(footprint ""
		(layer "F.Cu")
		(at 18.558002 -230.96855 -90)
		(property "Reference" "R1110"
			(at 0 0 270)
			(layer "F.SilkS")
			(hide yes)
			(effects
				(font
					(size 1.27 1.27)
				)
			)
		)
		(property "Value" "143KR2F-L-1-GP"
			(at 0.064008 -3.993896 270)
			(unlocked yes)
			(layer "F.Fab")
			(hide yes)
			(effects
				(font
					(size 1.016 1.016)
					(thickness 0.1524)
				)
			)
		)
		(property "Device Type" "R402H16"
			(at 0.064008 -5.517896 270)
			(unlocked yes)
			(layer "F.Fab")
			(hide yes)
			(effects
				(font
					(size 1.016 1.016)
					(thickness 0.1524)
				)
			)
		)
		(duplicate_pad_numbers_are_jumpers no)
		(fp_line
			(start -0.508 -0.9398)
			(end -0.508 0.9398)
			(stroke
				(width 0.1524)
				(type default)
			)
			(layer "F.SilkS")
		)
		(fp_line
			(start 0.508 -0.9398)
			(end -0.508 -0.9398)
			(stroke
				(width 0.1524)
				(type default)
			)
			(layer "F.SilkS")
		)
		(fp_rect
			(start -0.508 0.9398)
			(end 0.508 -0.9398)
			(stroke
				(width 0)
				(type default)
			)
			(fill no)
			(layer "F.CrtYd")
		)
		(fp_rect
			(start -0.508 0.9398)
			(end 0.508 -0.9398)
			(stroke
				(width 0)
				(type default)
			)
			(fill no)
			(layer "F.Fab")
		)
		(pad "1" smd custom
			(at 0 -0.4445 270)
			(size 0.1397 0.1397)
			(layers "F.Cu" "F.Mask" "F.Paste")
			(net "AGND_P5V_B_1")
			(options
				(clearance outline)
				(anchor circle)
			)
			(primitives
				(gr_poly
					(pts
						(arc
							(start -0.1778 -0.2794)
							(mid -0.249642 -0.249642)
							(end -0.2794 -0.1778)
						)
						(arc
							(start -0.2794 0.1778)
							(mid -0.249642 0.249642)
							(end -0.1778 0.2794)
						)
						(arc
							(start 0.1778 0.2794)
							(mid 0.249642 0.249642)
							(end 0.2794 0.1778)
						)
						(arc
							(start 0.2794 -0.1778)
							(mid 0.249642 -0.249642)
							(end 0.1778 -0.2794)
						)
					)
					(width 0)
					(fill yes)
				)
			)
		)
		(pad "2" smd custom
			(at 0 0.4445 270)
			(size 0.1397 0.1397)
			(layers "F.Cu" "F.Mask" "F.Paste")
			(net "P5V_B_1_TRIP")
			(options
				(clearance outline)
				(anchor circle)
			)
			(primitives
				(gr_poly
					(pts
						(arc
							(start -0.1778 -0.2794)
							(mid -0.249642 -0.249642)
							(end -0.2794 -0.1778)
						)
						(arc
							(start -0.2794 0.1778)
							(mid -0.249642 0.249642)
							(end -0.1778 0.2794)
						)
						(arc
							(start 0.1778 0.2794)
							(mid 0.249642 0.249642)
							(end 0.2794 0.1778)
						)
						(arc
							(start 0.2794 -0.1778)
							(mid 0.249642 -0.249642)
							(end 0.1778 -0.2794)
						)
					)
					(width 0)
					(fill yes)
				)
			)
		)
	)
	(footprint ""
		(layer "F.Cu")
		(at 41.217596 -360.9594)
		(property "Reference" "R143"
			(at 0 0 0)
			(layer "F.SilkS")
			(hide yes)
			(effects
				(font
					(size 1.27 1.27)
				)
			)
		)
		(property "Value" "10KR2F-2-GP"
			(at 0.064008 -3.993896 0)
			(unlocked yes)
			(layer "F.Fab")
			(hide yes)
			(effects
				(font
					(size 1.016 1.016)
					(thickness 0.1524)
				)
			)
		)
		(property "Device Type" "R402H16"
			(at 0.064008 -5.517896 0)
			(unlocked yes)
			(layer "F.Fab")
			(hide yes)
			(effects
				(font
					(size 1.016 1.016)
					(thickness 0.1524)
				)
			)
		)
		(duplicate_pad_numbers_are_jumpers no)
		(fp_line
			(start -0.508 -0.9398)
			(end -0.508 0.9398)
			(stroke
				(width 0.1524)
				(type default)
			)
			(layer "F.SilkS")
		)
		(fp_line
			(start 0.508 -0.9398)
			(end -0.508 -0.9398)
			(stroke
				(width 0.1524)
				(type default)
			)
			(layer "F.SilkS")
		)
		(fp_rect
			(start -0.508 0.9398)
			(end 0.508 -0.9398)
			(stroke
				(width 0)
				(type default)
			)
			(fill no)
			(layer "F.CrtYd")
		)
		(fp_rect
			(start -0.508 0.9398)
			(end 0.508 -0.9398)
			(stroke
				(width 0)
				(type default)
			)
			(fill no)
			(layer "F.Fab")
		)
		(pad "1" smd custom
			(at 0 -0.4445)
			(size 0.1397 0.1397)
			(layers "F.Cu" "F.Mask" "F.Paste")
			(net "P3V3_IN")
			(options
				(clearance outline)
				(anchor circle)
			)
			(primitives
				(gr_poly
					(pts
						(arc
							(start -0.1778 -0.2794)
							(mid -0.249642 -0.249642)
							(end -0.2794 -0.1778)
						)
						(arc
							(start -0.2794 0.1778)
							(mid -0.249642 0.249642)
							(end -0.1778 0.2794)
						)
						(arc
							(start 0.1778 0.2794)
							(mid 0.249642 0.249642)
							(end 0.2794 0.1778)
						)
						(arc
							(start 0.2794 -0.1778)
							(mid 0.249642 -0.249642)
							(end 0.1778 -0.2794)
						)
					)
					(width 0)
					(fill yes)
				)
			)
		)
		(pad "2" smd custom
			(at 0 0.4445)
			(size 0.1397 0.1397)
			(layers "F.Cu" "F.Mask" "F.Paste")
			(net "FAN_EN")
			(options
				(clearance outline)
				(anchor circle)
			)
			(primitives
				(gr_poly
					(pts
						(arc
							(start -0.1778 -0.2794)
							(mid -0.249642 -0.249642)
							(end -0.2794 -0.1778)
						)
						(arc
							(start -0.2794 0.1778)
							(mid -0.249642 0.249642)
							(end -0.1778 0.2794)
						)
						(arc
							(start 0.1778 0.2794)
							(mid 0.249642 0.249642)
							(end 0.2794 0.1778)
						)
						(arc
							(start 0.2794 -0.1778)
							(mid 0.249642 -0.249642)
							(end 0.1778 -0.2794)
						)
					)
					(width 0)
					(fill yes)
				)
			)
		)
	)
	(footprint ""
		(layer "F.Cu")
		(at 97.863914 -39.705026)
		(property "Reference" "TP151"
			(at 0 0 0)
			(layer "F.SilkS")
			(hide yes)
			(effects
				(font
					(size 1.27 1.27)
				)
			)
		)
		(property "Value" "*"
			(at -0.0508 -1.6764 0)
			(unlocked yes)
			(layer "F.Fab")
			(hide yes)
			(effects
				(font
					(size 1.016 1.016)
					(thickness 0.1524)
				)
			)
		)
		(property "Device Type" "TPAD32"
			(at -0.0508 -3.2004 0)
			(unlocked yes)
			(layer "F.Fab")
			(hide yes)
			(effects
				(font
					(size 1.016 1.016)
					(thickness 0.1524)
				)
			)
		)
		(duplicate_pad_numbers_are_jumpers no)
		(fp_poly
			(pts
				(arc
					(start 0.4064 0)
					(mid -0.4064 0)
					(end 0.4064 0)
				)
			)
			(stroke
				(width 0)
				(type default)
			)
			(fill no)
			(layer "F.CrtYd")
		)
		(fp_poly
			(pts
				(arc
					(start 0.7112 0)
					(mid -0.7112 0)
					(end 0.7112 0)
				)
			)
			(stroke
				(width 0)
				(type default)
			)
			(fill no)
			(layer "F.Fab")
		)
		(pad "1" smd circle
			(at 0 0)
			(size 0.8128 0.8128)
			(layers "F.Cu" "F.Mask" "F.Paste")
			(net "ACT_HDD_26")
		)
	)
	(footprint ""
		(layer "F.Cu")
		(at 259.095494 -215.383618)
		(property "Reference" "TP1"
			(at 0 0 0)
			(layer "F.SilkS")
			(hide yes)
			(effects
				(font
					(size 1.27 1.27)
				)
			)
		)
		(property "Value" "*"
			(at -0.0508 -1.6764 0)
			(unlocked yes)
			(layer "F.Fab")
			(hide yes)
			(effects
				(font
					(size 1.016 1.016)
					(thickness 0.1524)
				)
			)
		)
		(property "Device Type" "TPAD32"
			(at -0.0508 -3.2004 0)
			(unlocked yes)
			(layer "F.Fab")
			(hide yes)
			(effects
				(font
					(size 1.016 1.016)
					(thickness 0.1524)
				)
			)
		)
		(duplicate_pad_numbers_are_jumpers no)
		(fp_poly
			(pts
				(arc
					(start 0.4064 0)
					(mid -0.4064 0)
					(end 0.4064 0)
				)
			)
			(stroke
				(width 0)
				(type default)
			)
			(fill no)
			(layer "F.CrtYd")
		)
		(fp_poly
			(pts
				(arc
					(start 0.7112 0)
					(mid -0.7112 0)
					(end 0.7112 0)
				)
			)
			(stroke
				(width 0)
				(type default)
			)
			(fill no)
			(layer "F.Fab")
		)
		(pad "1" smd circle
			(at 0 0)
			(size 0.8128 0.8128)
			(layers "F.Cu" "F.Mask" "F.Paste")
			(net "VOL_SEN_INT_N")
		)
	)
	(footprint ""
		(layer "F.Cu")
		(at 239.649 -311.912)
		(property "Reference" "R1096"
			(at 0 0 0)
			(layer "F.SilkS")
			(hide yes)
			(effects
				(font
					(size 1.27 1.27)
				)
			)
		)
		(property "Value" "0R2J-2-GP"
			(at 0.064008 -3.993896 0)
			(unlocked yes)
			(layer "F.Fab")
			(hide yes)
			(effects
				(font
					(size 1.016 1.016)
					(thickness 0.1524)
				)
			)
		)
		(property "Device Type" "R402H16"
			(at 0.064008 -5.517896 0)
			(unlocked yes)
			(layer "F.Fab")
			(hide yes)
			(effects
				(font
					(size 1.016 1.016)
					(thickness 0.1524)
				)
			)
		)
		(duplicate_pad_numbers_are_jumpers no)
		(fp_line
			(start -0.508 -0.9398)
			(end -0.508 0.9398)
			(stroke
				(width 0.1524)
				(type default)
			)
			(layer "F.SilkS")
		)
		(fp_line
			(start 0.508 -0.9398)
			(end -0.508 -0.9398)
			(stroke
				(width 0.1524)
				(type default)
			)
			(layer "F.SilkS")
		)
		(fp_rect
			(start -0.508 0.9398)
			(end 0.508 -0.9398)
			(stroke
				(width 0)
				(type default)
			)
			(fill no)
			(layer "F.CrtYd")
		)
		(fp_rect
			(start -0.508 0.9398)
			(end 0.508 -0.9398)
			(stroke
				(width 0)
				(type default)
			)
			(fill no)
			(layer "F.Fab")
		)
		(pad "1" smd custom
			(at 0 -0.4445)
			(size 0.1397 0.1397)
			(layers "F.Cu" "F.Mask" "F.Paste")
			(net "GND")
			(options
				(clearance outline)
				(anchor circle)
			)
			(primitives
				(gr_poly
					(pts
						(arc
							(start -0.1778 -0.2794)
							(mid -0.249642 -0.249642)
							(end -0.2794 -0.1778)
						)
						(arc
							(start -0.2794 0.1778)
							(mid -0.249642 0.249642)
							(end -0.1778 0.2794)
						)
						(arc
							(start 0.1778 0.2794)
							(mid 0.249642 0.249642)
							(end 0.2794 0.1778)
						)
						(arc
							(start 0.2794 -0.1778)
							(mid 0.249642 -0.249642)
							(end 0.1778 -0.2794)
						)
					)
					(width 0)
					(fill yes)
				)
			)
		)
		(pad "2" smd custom
			(at 0 0.4445)
			(size 0.1397 0.1397)
			(layers "F.Cu" "F.Mask" "F.Paste")
			(net "MAX31790_A_WD_ST")
			(options
				(clearance outline)
				(anchor circle)
			)
			(primitives
				(gr_poly
					(pts
						(arc
							(start -0.1778 -0.2794)
							(mid -0.249642 -0.249642)
							(end -0.2794 -0.1778)
						)
						(arc
							(start -0.2794 0.1778)
							(mid -0.249642 0.249642)
							(end -0.1778 0.2794)
						)
						(arc
							(start 0.1778 0.2794)
							(mid 0.249642 0.249642)
							(end 0.2794 0.1778)
						)
						(arc
							(start 0.2794 -0.1778)
							(mid 0.249642 -0.249642)
							(end 0.1778 -0.2794)
						)
					)
					(width 0)
					(fill yes)
				)
			)
		)
	)
	(footprint ""
		(layer "F.Cu")
		(at 180.721 -249.555 90)
		(property "Reference" "R247"
			(at 0 0 90)
			(layer "F.SilkS")
			(hide yes)
			(effects
				(font
					(size 1.27 1.27)
				)
			)
		)
		(property "Value" "4K7R2F-GP"
			(at 0.064008 -3.993896 90)
			(unlocked yes)
			(layer "F.Fab")
			(hide yes)
			(effects
				(font
					(size 1.016 1.016)
					(thickness 0.1524)
				)
			)
		)
		(property "Device Type" "R402H16"
			(at 0.064008 -5.517896 90)
			(unlocked yes)
			(layer "F.Fab")
			(hide yes)
			(effects
				(font
					(size 1.016 1.016)
					(thickness 0.1524)
				)
			)
		)
		(duplicate_pad_numbers_are_jumpers no)
		(fp_line
			(start 0.508 -0.9398)
			(end -0.508 -0.9398)
			(stroke
				(width 0.1524)
				(type default)
			)
			(layer "F.SilkS")
		)
		(fp_line
			(start -0.508 -0.9398)
			(end -0.508 0.9398)
			(stroke
				(width 0.1524)
				(type default)
			)
			(layer "F.SilkS")
		)
		(fp_rect
			(start -0.508 0.9398)
			(end 0.508 -0.9398)
			(stroke
				(width 0)
				(type default)
			)
			(fill no)
			(layer "F.CrtYd")
		)
		(fp_rect
			(start -0.508 0.9398)
			(end 0.508 -0.9398)
			(stroke
				(width 0)
				(type default)
			)
			(fill no)
			(layer "F.Fab")
		)
		(pad "1" smd custom
			(at 0 -0.4445 90)
			(size 0.1397 0.1397)
			(layers "F.Cu" "F.Mask" "F.Paste")
			(net "SW_PWR_R_HDD5")
			(options
				(clearance outline)
				(anchor circle)
			)
			(primitives
				(gr_poly
					(pts
						(arc
							(start -0.1778 -0.2794)
							(mid -0.249642 -0.249642)
							(end -0.2794 -0.1778)
						)
						(arc
							(start -0.2794 0.1778)
							(mid -0.249642 0.249642)
							(end -0.1778 0.2794)
						)
						(arc
							(start 0.1778 0.2794)
							(mid 0.249642 0.249642)
							(end 0.2794 0.1778)
						)
						(arc
							(start 0.2794 -0.1778)
							(mid 0.249642 -0.249642)
							(end 0.1778 -0.2794)
						)
					)
					(width 0)
					(fill yes)
				)
			)
		)
		(pad "2" smd custom
			(at 0 0.4445 90)
			(size 0.1397 0.1397)
			(layers "F.Cu" "F.Mask" "F.Paste")
			(net "GND")
			(options
				(clearance outline)
				(anchor circle)
			)
			(primitives
				(gr_poly
					(pts
						(arc
							(start -0.1778 -0.2794)
							(mid -0.249642 -0.249642)
							(end -0.2794 -0.1778)
						)
						(arc
							(start -0.2794 0.1778)
							(mid -0.249642 0.249642)
							(end -0.1778 0.2794)
						)
						(arc
							(start 0.1778 0.2794)
							(mid 0.249642 0.249642)
							(end 0.2794 0.1778)
						)
						(arc
							(start 0.2794 -0.1778)
							(mid 0.249642 -0.249642)
							(end 0.1778 -0.2794)
						)
					)
					(width 0)
					(fill yes)
				)
			)
		)
	)
	(footprint ""
		(layer "F.Cu")
		(at 375.543826 -102.413562 -90)
		(property "Reference" "R474"
			(at 0 0 270)
			(layer "F.SilkS")
			(hide yes)
			(effects
				(font
					(size 1.27 1.27)
				)
			)
		)
		(property "Value" "4K7R2F-GP"
			(at 0.064008 -3.993896 270)
			(unlocked yes)
			(layer "F.Fab")
			(hide yes)
			(effects
				(font
					(size 1.016 1.016)
					(thickness 0.1524)
				)
			)
		)
		(property "Device Type" "R402H16"
			(at 0.064008 -5.517896 270)
			(unlocked yes)
			(layer "F.Fab")
			(hide yes)
			(effects
				(font
					(size 1.016 1.016)
					(thickness 0.1524)
				)
			)
		)
		(duplicate_pad_numbers_are_jumpers no)
		(fp_line
			(start -0.508 -0.9398)
			(end -0.508 0.9398)
			(stroke
				(width 0.1524)
				(type default)
			)
			(layer "F.SilkS")
		)
		(fp_line
			(start 0.508 -0.9398)
			(end -0.508 -0.9398)
			(stroke
				(width 0.1524)
				(type default)
			)
			(layer "F.SilkS")
		)
		(fp_rect
			(start -0.508 0.9398)
			(end 0.508 -0.9398)
			(stroke
				(width 0)
				(type default)
			)
			(fill no)
			(layer "F.CrtYd")
		)
		(fp_rect
			(start -0.508 0.9398)
			(end 0.508 -0.9398)
			(stroke
				(width 0)
				(type default)
			)
			(fill no)
			(layer "F.Fab")
		)
		(pad "1" smd custom
			(at 0 -0.4445 270)
			(size 0.1397 0.1397)
			(layers "F.Cu" "F.Mask" "F.Paste")
			(net "DRIVE_B_20_FLT_LED")
			(options
				(clearance outline)
				(anchor circle)
			)
			(primitives
				(gr_poly
					(pts
						(arc
							(start -0.1778 -0.2794)
							(mid -0.249642 -0.249642)
							(end -0.2794 -0.1778)
						)
						(arc
							(start -0.2794 0.1778)
							(mid -0.249642 0.249642)
							(end -0.1778 0.2794)
						)
						(arc
							(start 0.1778 0.2794)
							(mid 0.249642 0.249642)
							(end 0.2794 0.1778)
						)
						(arc
							(start 0.2794 -0.1778)
							(mid 0.249642 -0.249642)
							(end 0.1778 -0.2794)
						)
					)
					(width 0)
					(fill yes)
				)
			)
		)
		(pad "2" smd custom
			(at 0 0.4445 270)
			(size 0.1397 0.1397)
			(layers "F.Cu" "F.Mask" "F.Paste")
			(net "GND")
			(options
				(clearance outline)
				(anchor circle)
			)
			(primitives
				(gr_poly
					(pts
						(arc
							(start -0.1778 -0.2794)
							(mid -0.249642 -0.249642)
							(end -0.2794 -0.1778)
						)
						(arc
							(start -0.2794 0.1778)
							(mid -0.249642 0.249642)
							(end -0.1778 0.2794)
						)
						(arc
							(start 0.1778 0.2794)
							(mid 0.249642 0.249642)
							(end 0.2794 0.1778)
						)
						(arc
							(start 0.2794 -0.1778)
							(mid 0.249642 -0.249642)
							(end 0.1778 -0.2794)
						)
					)
					(width 0)
					(fill yes)
				)
			)
		)
	)
	(footprint ""
		(layer "F.Cu")
		(at 115.4176 -27.2034 180)
		(property "Reference" "Q135"
			(at 0 0 180)
			(layer "F.SilkS")
			(hide yes)
			(effects
				(font
					(size 1.27 1.27)
				)
			)
		)
		(property "Value" "AO4406AL-GP"
			(at -3.707384 -1.5367 180)
			(unlocked yes)
			(layer "F.Fab")
			(hide yes)
			(effects
				(font
					(size 1.016 1.016)
					(thickness 0.1524)
				)
			)
		)
		(property "Device Type" "SOIC8H69"
			(at -3.707384 -3.0607 180)
			(unlocked yes)
			(layer "F.Fab")
			(hide yes)
			(effects
				(font
					(size 1.016 1.016)
					(thickness 0.1524)
				)
			)
		)
		(duplicate_pad_numbers_are_jumpers no)
		(fp_line
			(start 2.1336 1.4224)
			(end 2.1336 -1.4224)
			(stroke
				(width 0.1524)
				(type default)
			)
			(layer "F.SilkS")
		)
		(fp_line
			(start 2.1336 -1.4224)
			(end -2.7432 -1.4224)
			(stroke
				(width 0.1524)
				(type default)
			)
			(layer "F.SilkS")
		)
		(fp_line
			(start -2.1844 -0.0508)
			(end -2.7178 0.508)
			(stroke
				(width 0.1524)
				(type default)
			)
			(layer "F.SilkS")
		)
		(fp_line
			(start -2.6289 3.4417)
			(end -2.6289 1.4732)
			(stroke
				(width 0.381)
				(type default)
			)
			(layer "F.SilkS")
		)
		(fp_line
			(start -2.7178 -0.508)
			(end -2.1844 -0.0508)
			(stroke
				(width 0.1524)
				(type default)
			)
			(layer "F.SilkS")
		)
		(fp_line
			(start -2.7432 1.4224)
			(end 2.1336 1.4224)
			(stroke
				(width 0.1524)
				(type default)
			)
			(layer "F.SilkS")
		)
		(fp_line
			(start -2.7432 1.4224)
			(end -2.6416 1.4224)
			(stroke
				(width 0.1524)
				(type default)
			)
			(layer "F.SilkS")
		)
		(fp_line
			(start -2.7432 -1.4224)
			(end -2.7432 1.4224)
			(stroke
				(width 0.1524)
				(type default)
			)
			(layer "F.SilkS")
		)
		(fp_poly
			(pts
				(xy -2.2098 -1.4224) (xy -2.2098 1.4224) (xy 2.2098 1.4224) (xy 2.2098 -1.4224)
			)
			(stroke
				(width 0)
				(type default)
			)
			(fill yes)
			(layer "F.SilkS")
		)
		(fp_rect
			(start -2.450084 2.999994)
			(end 2.450084 -2.999994)
			(stroke
				(width 0)
				(type default)
			)
			(fill no)
			(layer "F.CrtYd")
		)
		(fp_poly
			(pts
				(xy -2.8194 3.6322) (xy -2.8194 -3.6322) (xy 2.8194 -3.6322) (xy 2.8194 1.18364) (xy 2.450084 1.18364)
				(xy 2.450084 -2.999994) (xy -2.450084 -2.999994) (xy -2.450084 2.999994) (xy 2.450084 2.999994)
				(xy 2.450084 1.18618) (xy 2.8194 1.18618) (xy 2.8194 3.6322)
			)
			(stroke
				(width 0)
				(type default)
			)
			(fill no)
			(layer "F.CrtYd")
		)
		(fp_rect
			(start -2.8194 3.6322)
			(end 2.8194 -3.6322)
			(stroke
				(width 0)
				(type default)
			)
			(fill no)
			(layer "F.Fab")
		)
		(pad "1" smd rect
			(at -1.905 2.54 180)
			(size 0.635 1.651)
			(layers "F.Cu" "F.Mask" "F.Paste")
			(net "P5V_HDD27")
		)
		(pad "2" smd rect
			(at -0.635 2.54 180)
			(size 0.635 1.651)
			(layers "F.Cu" "F.Mask" "F.Paste")
			(net "P5V_HDD27")
		)
		(pad "3" smd rect
			(at 0.635 2.54 180)
			(size 0.635 1.651)
			(layers "F.Cu" "F.Mask" "F.Paste")
			(net "P5V_HDD27")
		)
		(pad "4" smd rect
			(at 1.905 2.54 180)
			(size 0.635 1.651)
			(layers "F.Cu" "F.Mask" "F.Paste")
			(net "SW_HDD_P27")
		)
		(pad "5" smd rect
			(at 1.905 -2.54 180)
			(size 0.635 1.651)
			(layers "F.Cu" "F.Mask" "F.Paste")
			(net "P5V_B_2")
		)
		(pad "6" smd rect
			(at 0.635 -2.54 180)
			(size 0.635 1.651)
			(layers "F.Cu" "F.Mask" "F.Paste")
			(net "P5V_B_2")
		)
		(pad "7" smd rect
			(at -0.635 -2.54 180)
			(size 0.635 1.651)
			(layers "F.Cu" "F.Mask" "F.Paste")
			(net "P5V_B_2")
		)
		(pad "8" smd rect
			(at -1.905 -2.54 180)
			(size 0.635 1.651)
			(layers "F.Cu" "F.Mask" "F.Paste")
			(net "P5V_B_2")
		)
	)
	(footprint ""
		(layer "F.Cu")
		(at 149.225 -19.558 90)
		(property "Reference" "R727"
			(at 0 0 90)
			(layer "F.SilkS")
			(hide yes)
			(effects
				(font
					(size 1.27 1.27)
				)
			)
		)
		(property "Value" "4K7R2F-GP"
			(at 0.064008 -3.993896 90)
			(unlocked yes)
			(layer "F.Fab")
			(hide yes)
			(effects
				(font
					(size 1.016 1.016)
					(thickness 0.1524)
				)
			)
		)
		(property "Device Type" "R402H16"
			(at 0.064008 -5.517896 90)
			(unlocked yes)
			(layer "F.Fab")
			(hide yes)
			(effects
				(font
					(size 1.016 1.016)
					(thickness 0.1524)
				)
			)
		)
		(duplicate_pad_numbers_are_jumpers no)
		(fp_line
			(start 0.508 -0.9398)
			(end -0.508 -0.9398)
			(stroke
				(width 0.1524)
				(type default)
			)
			(layer "F.SilkS")
		)
		(fp_line
			(start -0.508 -0.9398)
			(end -0.508 0.9398)
			(stroke
				(width 0.1524)
				(type default)
			)
			(layer "F.SilkS")
		)
		(fp_rect
			(start -0.508 0.9398)
			(end 0.508 -0.9398)
			(stroke
				(width 0)
				(type default)
			)
			(fill no)
			(layer "F.CrtYd")
		)
		(fp_rect
			(start -0.508 0.9398)
			(end 0.508 -0.9398)
			(stroke
				(width 0)
				(type default)
			)
			(fill no)
			(layer "F.Fab")
		)
		(pad "1" smd custom
			(at 0 -0.4445 90)
			(size 0.1397 0.1397)
			(layers "F.Cu" "F.Mask" "F.Paste")
			(net "SW_PWR_R_HDD28")
			(options
				(clearance outline)
				(anchor circle)
			)
			(primitives
				(gr_poly
					(pts
						(arc
							(start -0.1778 -0.2794)
							(mid -0.249642 -0.249642)
							(end -0.2794 -0.1778)
						)
						(arc
							(start -0.2794 0.1778)
							(mid -0.249642 0.249642)
							(end -0.1778 0.2794)
						)
						(arc
							(start 0.1778 0.2794)
							(mid 0.249642 0.249642)
							(end 0.2794 0.1778)
						)
						(arc
							(start 0.2794 -0.1778)
							(mid 0.249642 -0.249642)
							(end 0.1778 -0.2794)
						)
					)
					(width 0)
					(fill yes)
				)
			)
		)
		(pad "2" smd custom
			(at 0 0.4445 90)
			(size 0.1397 0.1397)
			(layers "F.Cu" "F.Mask" "F.Paste")
			(net "GND")
			(options
				(clearance outline)
				(anchor circle)
			)
			(primitives
				(gr_poly
					(pts
						(arc
							(start -0.1778 -0.2794)
							(mid -0.249642 -0.249642)
							(end -0.2794 -0.1778)
						)
						(arc
							(start -0.2794 0.1778)
							(mid -0.249642 0.249642)
							(end -0.1778 0.2794)
						)
						(arc
							(start 0.1778 0.2794)
							(mid 0.249642 0.249642)
							(end 0.2794 0.1778)
						)
						(arc
							(start 0.2794 -0.1778)
							(mid 0.249642 -0.249642)
							(end 0.1778 -0.2794)
						)
					)
					(width 0)
					(fill yes)
				)
			)
		)
	)
	(footprint ""
		(layer "F.Cu")
		(at 476.5294 -131.6228)
		(property "Reference" "R603"
			(at 0 0 0)
			(layer "F.SilkS")
			(hide yes)
			(effects
				(font
					(size 1.27 1.27)
				)
			)
		)
		(property "Value" "220R3F-1-GP"
			(at -0.0254 -2.5146 0)
			(unlocked yes)
			(layer "F.Fab")
			(hide yes)
			(effects
				(font
					(size 1.016 1.016)
					(thickness 0.1524)
				)
			)
		)
		(property "Device Type" "R603H22"
			(at -0.0254 -4.0386 0)
			(unlocked yes)
			(layer "F.Fab")
			(hide yes)
			(effects
				(font
					(size 1.016 1.016)
					(thickness 0.1524)
				)
			)
		)
		(duplicate_pad_numbers_are_jumpers no)
		(fp_line
			(start -0.4826 0)
			(end -0.2032 0)
			(stroke
				(width 0.2032)
				(type default)
			)
			(layer "F.SilkS")
		)
		(fp_line
			(start 0.2032 0)
			(end 0.4826 0)
			(stroke
				(width 0.2032)
				(type default)
			)
			(layer "F.SilkS")
		)
		(fp_rect
			(start -0.5842 1.3335)
			(end 0.5842 -1.3335)
			(stroke
				(width 0)
				(type default)
			)
			(fill no)
			(layer "F.CrtYd")
		)
		(fp_rect
			(start -0.5842 1.3335)
			(end 0.5842 -1.3335)
			(stroke
				(width 0)
				(type default)
			)
			(fill no)
			(layer "F.Fab")
		)
		(pad "1" smd custom
			(at 0 -0.762)
			(size 0.2159 0.2159)
			(layers "F.Cu" "F.Mask" "F.Paste")
			(net "HDD_PRSNT_23")
			(options
				(clearance outline)
				(anchor circle)
			)
			(primitives
				(gr_poly
					(pts
						(arc
							(start -0.3302 -0.4318)
							(mid -0.402042 -0.402042)
							(end -0.4318 -0.3302)
						)
						(arc
							(start -0.4318 0.3302)
							(mid -0.402042 0.402042)
							(end -0.3302 0.4318)
						)
						(arc
							(start 0.3302 0.4318)
							(mid 0.402042 0.402042)
							(end 0.4318 0.3302)
						)
						(arc
							(start 0.4318 -0.3302)
							(mid 0.402042 -0.402042)
							(end 0.3302 -0.4318)
						)
					)
					(width 0)
					(fill yes)
				)
			)
		)
		(pad "2" smd custom
			(at 0 0.762)
			(size 0.2159 0.2159)
			(layers "F.Cu" "F.Mask" "F.Paste")
			(net "DRIVE_B_23_INS")
			(options
				(clearance outline)
				(anchor circle)
			)
			(primitives
				(gr_poly
					(pts
						(arc
							(start -0.3302 -0.4318)
							(mid -0.402042 -0.402042)
							(end -0.4318 -0.3302)
						)
						(arc
							(start -0.4318 0.3302)
							(mid -0.402042 0.402042)
							(end -0.3302 0.4318)
						)
						(arc
							(start 0.3302 0.4318)
							(mid 0.402042 0.402042)
							(end 0.4318 0.3302)
						)
						(arc
							(start 0.4318 -0.3302)
							(mid 0.402042 -0.402042)
							(end 0.3302 -0.4318)
						)
					)
					(width 0)
					(fill yes)
				)
			)
		)
	)
	(footprint ""
		(layer "F.Cu")
		(at 35.687 -32.7914 180)
		(property "Reference" "R626"
			(at 0 0 180)
			(layer "F.SilkS")
			(hide yes)
			(effects
				(font
					(size 1.27 1.27)
				)
			)
		)
		(property "Value" "220R3F-1-GP"
			(at -0.0254 -2.5146 180)
			(unlocked yes)
			(layer "F.Fab")
			(hide yes)
			(effects
				(font
					(size 1.016 1.016)
					(thickness 0.1524)
				)
			)
		)
		(property "Device Type" "R603H22"
			(at -0.0254 -4.0386 180)
			(unlocked yes)
			(layer "F.Fab")
			(hide yes)
			(effects
				(font
					(size 1.016 1.016)
					(thickness 0.1524)
				)
			)
		)
		(duplicate_pad_numbers_are_jumpers no)
		(fp_line
			(start 0.2032 0)
			(end 0.4826 0)
			(stroke
				(width 0.2032)
				(type default)
			)
			(layer "F.SilkS")
		)
		(fp_line
			(start -0.4826 0)
			(end -0.2032 0)
			(stroke
				(width 0.2032)
				(type default)
			)
			(layer "F.SilkS")
		)
		(fp_rect
			(start -0.5842 1.3335)
			(end 0.5842 -1.3335)
			(stroke
				(width 0)
				(type default)
			)
			(fill no)
			(layer "F.CrtYd")
		)
		(fp_rect
			(start -0.5842 1.3335)
			(end 0.5842 -1.3335)
			(stroke
				(width 0)
				(type default)
			)
			(fill no)
			(layer "F.Fab")
		)
		(pad "1" smd custom
			(at 0 -0.762 180)
			(size 0.2159 0.2159)
			(layers "F.Cu" "F.Mask" "F.Paste")
			(net "HDD_PRSNT_24")
			(options
				(clearance outline)
				(anchor circle)
			)
			(primitives
				(gr_poly
					(pts
						(arc
							(start -0.3302 -0.4318)
							(mid -0.402042 -0.402042)
							(end -0.4318 -0.3302)
						)
						(arc
							(start -0.4318 0.3302)
							(mid -0.402042 0.402042)
							(end -0.3302 0.4318)
						)
						(arc
							(start 0.3302 0.4318)
							(mid 0.402042 0.402042)
							(end 0.4318 0.3302)
						)
						(arc
							(start 0.4318 -0.3302)
							(mid 0.402042 -0.402042)
							(end 0.3302 -0.4318)
						)
					)
					(width 0)
					(fill yes)
				)
			)
		)
		(pad "2" smd custom
			(at 0 0.762 180)
			(size 0.2159 0.2159)
			(layers "F.Cu" "F.Mask" "F.Paste")
			(net "DRIVE_B_24_INS")
			(options
				(clearance outline)
				(anchor circle)
			)
			(primitives
				(gr_poly
					(pts
						(arc
							(start -0.3302 -0.4318)
							(mid -0.402042 -0.402042)
							(end -0.4318 -0.3302)
						)
						(arc
							(start -0.4318 0.3302)
							(mid -0.402042 0.402042)
							(end -0.3302 0.4318)
						)
						(arc
							(start 0.3302 0.4318)
							(mid 0.402042 0.402042)
							(end 0.4318 0.3302)
						)
						(arc
							(start 0.4318 -0.3302)
							(mid 0.402042 -0.402042)
							(end 0.3302 -0.4318)
						)
					)
					(width 0)
					(fill yes)
				)
			)
		)
	)
	(footprint ""
		(layer "F.Cu")
		(at 470.193878 -217.413586 -90)
		(property "Reference" "R322"
			(at 0 0 270)
			(layer "F.SilkS")
			(hide yes)
			(effects
				(font
					(size 1.27 1.27)
				)
			)
		)
		(property "Value" "4K7R2F-GP"
			(at 0.064008 -3.993896 270)
			(unlocked yes)
			(layer "F.Fab")
			(hide yes)
			(effects
				(font
					(size 1.016 1.016)
					(thickness 0.1524)
				)
			)
		)
		(property "Device Type" "R402H16"
			(at 0.064008 -5.517896 270)
			(unlocked yes)
			(layer "F.Fab")
			(hide yes)
			(effects
				(font
					(size 1.016 1.016)
					(thickness 0.1524)
				)
			)
		)
		(duplicate_pad_numbers_are_jumpers no)
		(fp_line
			(start -0.508 -0.9398)
			(end -0.508 0.9398)
			(stroke
				(width 0.1524)
				(type default)
			)
			(layer "F.SilkS")
		)
		(fp_line
			(start 0.508 -0.9398)
			(end -0.508 -0.9398)
			(stroke
				(width 0.1524)
				(type default)
			)
			(layer "F.SilkS")
		)
		(fp_rect
			(start -0.508 0.9398)
			(end 0.508 -0.9398)
			(stroke
				(width 0)
				(type default)
			)
			(fill no)
			(layer "F.CrtYd")
		)
		(fp_rect
			(start -0.508 0.9398)
			(end 0.508 -0.9398)
			(stroke
				(width 0)
				(type default)
			)
			(fill no)
			(layer "F.Fab")
		)
		(pad "1" smd custom
			(at 0 -0.4445 270)
			(size 0.1397 0.1397)
			(layers "F.Cu" "F.Mask" "F.Paste")
			(net "DRIVE_B_11_FLT_LED")
			(options
				(clearance outline)
				(anchor circle)
			)
			(primitives
				(gr_poly
					(pts
						(arc
							(start -0.1778 -0.2794)
							(mid -0.249642 -0.249642)
							(end -0.2794 -0.1778)
						)
						(arc
							(start -0.2794 0.1778)
							(mid -0.249642 0.249642)
							(end -0.1778 0.2794)
						)
						(arc
							(start 0.1778 0.2794)
							(mid 0.249642 0.249642)
							(end 0.2794 0.1778)
						)
						(arc
							(start 0.2794 -0.1778)
							(mid 0.249642 -0.249642)
							(end 0.1778 -0.2794)
						)
					)
					(width 0)
					(fill yes)
				)
			)
		)
		(pad "2" smd custom
			(at 0 0.4445 270)
			(size 0.1397 0.1397)
			(layers "F.Cu" "F.Mask" "F.Paste")
			(net "GND")
			(options
				(clearance outline)
				(anchor circle)
			)
			(primitives
				(gr_poly
					(pts
						(arc
							(start -0.1778 -0.2794)
							(mid -0.249642 -0.249642)
							(end -0.2794 -0.1778)
						)
						(arc
							(start -0.2794 0.1778)
							(mid -0.249642 0.249642)
							(end -0.1778 0.2794)
						)
						(arc
							(start 0.1778 0.2794)
							(mid 0.249642 0.249642)
							(end 0.2794 0.1778)
						)
						(arc
							(start 0.2794 -0.1778)
							(mid 0.249642 -0.249642)
							(end 0.1778 -0.2794)
						)
					)
					(width 0)
					(fill yes)
				)
			)
		)
	)
	(footprint ""
		(layer "F.Cu")
		(at 398.907 -243.586 180)
		(property "Reference" "R294"
			(at 0 0 180)
			(layer "F.SilkS")
			(hide yes)
			(effects
				(font
					(size 1.27 1.27)
				)
			)
		)
		(property "Value" "0R2J-2-GP"
			(at 0.064008 -3.993896 180)
			(unlocked yes)
			(layer "F.Fab")
			(hide yes)
			(effects
				(font
					(size 1.016 1.016)
					(thickness 0.1524)
				)
			)
		)
		(property "Device Type" "R402H16"
			(at 0.064008 -5.517896 180)
			(unlocked yes)
			(layer "F.Fab")
			(hide yes)
			(effects
				(font
					(size 1.016 1.016)
					(thickness 0.1524)
				)
			)
		)
		(duplicate_pad_numbers_are_jumpers no)
		(fp_line
			(start 0.508 -0.9398)
			(end -0.508 -0.9398)
			(stroke
				(width 0.1524)
				(type default)
			)
			(layer "F.SilkS")
		)
		(fp_line
			(start -0.508 -0.9398)
			(end -0.508 0.9398)
			(stroke
				(width 0.1524)
				(type default)
			)
			(layer "F.SilkS")
		)
		(fp_rect
			(start -0.508 0.9398)
			(end 0.508 -0.9398)
			(stroke
				(width 0)
				(type default)
			)
			(fill no)
			(layer "F.CrtYd")
		)
		(fp_rect
			(start -0.508 0.9398)
			(end 0.508 -0.9398)
			(stroke
				(width 0)
				(type default)
			)
			(fill no)
			(layer "F.Fab")
		)
		(pad "1" smd custom
			(at 0 -0.4445 180)
			(size 0.1397 0.1397)
			(layers "F.Cu" "F.Mask" "F.Paste")
			(net "DRIVE_B_8_PWR")
			(options
				(clearance outline)
				(anchor circle)
			)
			(primitives
				(gr_poly
					(pts
						(arc
							(start -0.1778 -0.2794)
							(mid -0.249642 -0.249642)
							(end -0.2794 -0.1778)
						)
						(arc
							(start -0.2794 0.1778)
							(mid -0.249642 0.249642)
							(end -0.1778 0.2794)
						)
						(arc
							(start 0.1778 0.2794)
							(mid 0.249642 0.249642)
							(end 0.2794 0.1778)
						)
						(arc
							(start 0.2794 -0.1778)
							(mid 0.249642 -0.249642)
							(end 0.1778 -0.2794)
						)
					)
					(width 0)
					(fill yes)
				)
			)
		)
		(pad "2" smd custom
			(at 0 0.4445 180)
			(size 0.1397 0.1397)
			(layers "F.Cu" "F.Mask" "F.Paste")
			(net "SW_PWR_R_HDD8")
			(options
				(clearance outline)
				(anchor circle)
			)
			(primitives
				(gr_poly
					(pts
						(arc
							(start -0.1778 -0.2794)
							(mid -0.249642 -0.249642)
							(end -0.2794 -0.1778)
						)
						(arc
							(start -0.2794 0.1778)
							(mid -0.249642 0.249642)
							(end -0.1778 0.2794)
						)
						(arc
							(start 0.1778 0.2794)
							(mid 0.249642 0.249642)
							(end 0.2794 0.1778)
						)
						(arc
							(start 0.2794 -0.1778)
							(mid 0.249642 -0.249642)
							(end 0.1778 -0.2794)
						)
					)
					(width 0)
					(fill yes)
				)
			)
		)
	)
	(footprint ""
		(layer "F.Cu")
		(at 254.537972 -372.32971 180)
		(property "Reference" "C556"
			(at 0 0 180)
			(layer "F.SilkS")
			(hide yes)
			(effects
				(font
					(size 1.27 1.27)
				)
			)
		)
		(property "Value" "SCD1U16V2KX-3GP"
			(at 1.1811 -2.7051 180)
			(unlocked yes)
			(layer "F.Fab")
			(hide yes)
			(effects
				(font
					(size 1.016 1.016)
					(thickness 0.1524)
				)
			)
		)
		(property "Device Type" "C402H22"
			(at 1.1811 -4.2291 180)
			(unlocked yes)
			(layer "F.Fab")
			(hide yes)
			(effects
				(font
					(size 1.016 1.016)
					(thickness 0.1524)
				)
			)
		)
		(duplicate_pad_numbers_are_jumpers no)
		(fp_rect
			(start -0.4318 0.9525)
			(end 0.4318 -0.9525)
			(stroke
				(width 0)
				(type default)
			)
			(fill no)
			(layer "F.CrtYd")
		)
		(fp_rect
			(start -0.4318 0.9525)
			(end 0.4318 -0.9525)
			(stroke
				(width 0)
				(type default)
			)
			(fill no)
			(layer "F.Fab")
		)
		(pad "1" smd custom
			(at 0 -0.4445 180)
			(size 0.1524 0.1524)
			(layers "F.Cu" "F.Mask" "F.Paste")
			(net "MB3_CM_VOUT_R")
			(options
				(clearance outline)
				(anchor circle)
			)
			(primitives
				(gr_poly
					(pts
						(arc
							(start 0.3048 -0.2032)
							(mid 0.275042 -0.275042)
							(end 0.2032 -0.3048)
						)
						(arc
							(start -0.2032 -0.3048)
							(mid -0.275042 -0.275042)
							(end -0.3048 -0.2032)
						)
						(arc
							(start -0.3048 0.2032)
							(mid -0.275042 0.275042)
							(end -0.2032 0.3048)
						)
						(arc
							(start 0.2032 0.3048)
							(mid 0.275042 0.275042)
							(end 0.3048 0.2032)
						)
					)
					(width 0)
					(fill yes)
				)
			)
		)
		(pad "2" smd custom
			(at 0 0.4445 180)
			(size 0.1524 0.1524)
			(layers "F.Cu" "F.Mask" "F.Paste")
			(net "AGND_CURRENT_DPB")
			(options
				(clearance outline)
				(anchor circle)
			)
			(primitives
				(gr_poly
					(pts
						(arc
							(start 0.3048 -0.2032)
							(mid 0.275042 -0.275042)
							(end 0.2032 -0.3048)
						)
						(arc
							(start -0.2032 -0.3048)
							(mid -0.275042 -0.275042)
							(end -0.3048 -0.2032)
						)
						(arc
							(start -0.3048 0.2032)
							(mid -0.275042 0.275042)
							(end -0.2032 0.3048)
						)
						(arc
							(start 0.2032 0.3048)
							(mid 0.275042 0.275042)
							(end 0.3048 0.2032)
						)
					)
					(width 0)
					(fill yes)
				)
			)
		)
	)
	(footprint ""
		(layer "F.Cu")
		(at 261.212076 -198.496682)
		(property "Reference" "TC2"
			(at 0 0 0)
			(layer "F.SilkS")
			(hide yes)
			(effects
				(font
					(size 1.27 1.27)
				)
			)
		)
		(property "Value" "SE270U16VM-8-GP"
			(at -4.5974 -2.54 0)
			(unlocked yes)
			(layer "F.Fab")
			(hide yes)
			(effects
				(font
					(size 1.016 1.016)
					(thickness 0.1524)
				)
			)
		)
		(property "Device Type" "SE361416H394"
			(at -4.5974 -4.064 0)
			(unlocked yes)
			(layer "F.Fab")
			(hide yes)
			(effects
				(font
					(size 1.016 1.016)
					(thickness 0.1524)
				)
			)
		)
		(duplicate_pad_numbers_are_jumpers no)
		(fp_line
			(start -3.556 -3.4163)
			(end -2.3622 -4.6101)
			(stroke
				(width 0.1524)
				(type default)
			)
			(layer "F.SilkS")
		)
		(fp_line
			(start -3.556 4.6101)
			(end -3.556 -3.4163)
			(stroke
				(width 0.1524)
				(type default)
			)
			(layer "F.SilkS")
		)
		(fp_line
			(start -2.3622 -4.6101)
			(end 2.3622 -4.6101)
			(stroke
				(width 0.1524)
				(type default)
			)
			(layer "F.SilkS")
		)
		(fp_line
			(start 2.3622 -4.6101)
			(end 3.556 -3.4163)
			(stroke
				(width 0.1524)
				(type default)
			)
			(layer "F.SilkS")
		)
		(fp_line
			(start 3.556 -3.4163)
			(end 3.556 4.6101)
			(stroke
				(width 0.1524)
				(type default)
			)
			(layer "F.SilkS")
		)
		(fp_line
			(start 3.556 4.6101)
			(end -3.556 4.6101)
			(stroke
				(width 0.1524)
				(type default)
			)
			(layer "F.SilkS")
		)
		(fp_rect
			(start -3.302 3.6449)
			(end 3.302 -3.6449)
			(stroke
				(width 0)
				(type default)
			)
			(fill no)
			(layer "F.CrtYd")
		)
		(fp_poly
			(pts
				(xy 3.81 4.6863) (xy 3.81 -3.4925) (xy 3.302 -3.4925) (xy 3.302 3.6449) (xy -3.302 3.6449) (xy -3.302 -3.6449)
				(xy 3.302 -3.6449) (xy 3.302 -3.5052) (xy 3.81 -3.5052) (xy 3.81 -4.6863) (xy -3.81 -4.6863) (xy -3.81 4.6863)
			)
			(stroke
				(width 0)
				(type default)
			)
			(fill no)
			(layer "F.CrtYd")
		)
		(fp_rect
			(start -3.81 4.6863)
			(end 3.81 -4.6863)
			(stroke
				(width 0)
				(type default)
			)
			(fill no)
			(layer "F.Fab")
		)
		(pad "1" smd rect
			(at 0 -2.574036)
			(size 1.4224 3.556)
			(layers "F.Cu" "F.Mask" "F.Paste")
			(net "P12V_B")
		)
		(pad "2" smd rect
			(at 0 2.574036)
			(size 1.4224 3.556)
			(layers "F.Cu" "F.Mask" "F.Paste")
			(net "GND")
		)
	)
	(footprint ""
		(layer "F.Cu")
		(at 420.243 -372.11 90)
		(property "Reference" "R954"
			(at 0 0 90)
			(layer "F.SilkS")
			(hide yes)
			(effects
				(font
					(size 1.27 1.27)
				)
			)
		)
		(property "Value" "100KR2F-L1-GP"
			(at 0.064008 -3.993896 90)
			(unlocked yes)
			(layer "F.Fab")
			(hide yes)
			(effects
				(font
					(size 1.016 1.016)
					(thickness 0.1524)
				)
			)
		)
		(property "Device Type" "R402H16"
			(at 0.064008 -5.517896 90)
			(unlocked yes)
			(layer "F.Fab")
			(hide yes)
			(effects
				(font
					(size 1.016 1.016)
					(thickness 0.1524)
				)
			)
		)
		(duplicate_pad_numbers_are_jumpers no)
		(fp_line
			(start 0.508 -0.9398)
			(end -0.508 -0.9398)
			(stroke
				(width 0.1524)
				(type default)
			)
			(layer "F.SilkS")
		)
		(fp_line
			(start -0.508 -0.9398)
			(end -0.508 0.9398)
			(stroke
				(width 0.1524)
				(type default)
			)
			(layer "F.SilkS")
		)
		(fp_rect
			(start -0.508 0.9398)
			(end 0.508 -0.9398)
			(stroke
				(width 0)
				(type default)
			)
			(fill no)
			(layer "F.CrtYd")
		)
		(fp_rect
			(start -0.508 0.9398)
			(end 0.508 -0.9398)
			(stroke
				(width 0)
				(type default)
			)
			(fill no)
			(layer "F.Fab")
		)
		(pad "1" smd custom
			(at 0 -0.4445 90)
			(size 0.1397 0.1397)
			(layers "F.Cu" "F.Mask" "F.Paste")
			(net "P3V3_IN")
			(options
				(clearance outline)
				(anchor circle)
			)
			(primitives
				(gr_poly
					(pts
						(arc
							(start -0.1778 -0.2794)
							(mid -0.249642 -0.249642)
							(end -0.2794 -0.1778)
						)
						(arc
							(start -0.2794 0.1778)
							(mid -0.249642 0.249642)
							(end -0.1778 0.2794)
						)
						(arc
							(start 0.1778 0.2794)
							(mid 0.249642 0.249642)
							(end 0.2794 0.1778)
						)
						(arc
							(start 0.2794 -0.1778)
							(mid 0.249642 -0.249642)
							(end 0.1778 -0.2794)
						)
					)
					(width 0)
					(fill yes)
				)
			)
		)
		(pad "2" smd custom
			(at 0 0.4445 90)
			(size 0.1397 0.1397)
			(layers "F.Cu" "F.Mask" "F.Paste")
			(net "FAN_3_INS_N")
			(options
				(clearance outline)
				(anchor circle)
			)
			(primitives
				(gr_poly
					(pts
						(arc
							(start -0.1778 -0.2794)
							(mid -0.249642 -0.249642)
							(end -0.2794 -0.1778)
						)
						(arc
							(start -0.2794 0.1778)
							(mid -0.249642 0.249642)
							(end -0.1778 0.2794)
						)
						(arc
							(start 0.1778 0.2794)
							(mid 0.249642 0.249642)
							(end 0.2794 0.1778)
						)
						(arc
							(start 0.2794 -0.1778)
							(mid 0.249642 -0.249642)
							(end 0.1778 -0.2794)
						)
					)
					(width 0)
					(fill yes)
				)
			)
		)
	)
	(footprint ""
		(layer "F.Cu")
		(at 86.0806 -18.4404 -90)
		(property "Reference" "R676"
			(at 0 0 270)
			(layer "F.SilkS")
			(hide yes)
			(effects
				(font
					(size 1.27 1.27)
				)
			)
		)
		(property "Value" "1KR2F-3-GP"
			(at 0.064008 -3.993896 270)
			(unlocked yes)
			(layer "F.Fab")
			(hide yes)
			(effects
				(font
					(size 1.016 1.016)
					(thickness 0.1524)
				)
			)
		)
		(property "Device Type" "R402H16"
			(at 0.064008 -5.517896 270)
			(unlocked yes)
			(layer "F.Fab")
			(hide yes)
			(effects
				(font
					(size 1.016 1.016)
					(thickness 0.1524)
				)
			)
		)
		(duplicate_pad_numbers_are_jumpers no)
		(fp_line
			(start -0.508 -0.9398)
			(end -0.508 0.9398)
			(stroke
				(width 0.1524)
				(type default)
			)
			(layer "F.SilkS")
		)
		(fp_line
			(start 0.508 -0.9398)
			(end -0.508 -0.9398)
			(stroke
				(width 0.1524)
				(type default)
			)
			(layer "F.SilkS")
		)
		(fp_rect
			(start -0.508 0.9398)
			(end 0.508 -0.9398)
			(stroke
				(width 0)
				(type default)
			)
			(fill no)
			(layer "F.CrtYd")
		)
		(fp_rect
			(start -0.508 0.9398)
			(end 0.508 -0.9398)
			(stroke
				(width 0)
				(type default)
			)
			(fill no)
			(layer "F.Fab")
		)
		(pad "1" smd custom
			(at 0 -0.4445 270)
			(size 0.1397 0.1397)
			(layers "F.Cu" "F.Mask" "F.Paste")
			(net "P3V3_STBY_B")
			(options
				(clearance outline)
				(anchor circle)
			)
			(primitives
				(gr_poly
					(pts
						(arc
							(start -0.1778 -0.2794)
							(mid -0.249642 -0.249642)
							(end -0.2794 -0.1778)
						)
						(arc
							(start -0.2794 0.1778)
							(mid -0.249642 0.249642)
							(end -0.1778 0.2794)
						)
						(arc
							(start 0.1778 0.2794)
							(mid 0.249642 0.249642)
							(end 0.2794 0.1778)
						)
						(arc
							(start 0.2794 -0.1778)
							(mid 0.249642 -0.249642)
							(end 0.1778 -0.2794)
						)
					)
					(width 0)
					(fill yes)
				)
			)
		)
		(pad "2" smd custom
			(at 0 0.4445 270)
			(size 0.1397 0.1397)
			(layers "F.Cu" "F.Mask" "F.Paste")
			(net "SW_PWR_R_HDD26")
			(options
				(clearance outline)
				(anchor circle)
			)
			(primitives
				(gr_poly
					(pts
						(arc
							(start -0.1778 -0.2794)
							(mid -0.249642 -0.249642)
							(end -0.2794 -0.1778)
						)
						(arc
							(start -0.2794 0.1778)
							(mid -0.249642 0.249642)
							(end -0.1778 0.2794)
						)
						(arc
							(start 0.1778 0.2794)
							(mid 0.249642 0.249642)
							(end 0.2794 0.1778)
						)
						(arc
							(start 0.2794 -0.1778)
							(mid 0.249642 -0.249642)
							(end 0.1778 -0.2794)
						)
					)
					(width 0)
					(fill yes)
				)
			)
		)
	)
	(footprint ""
		(layer "F.Cu")
		(at 483.300024 -28.910026 -90)
		(property "Reference" "HDDSAS35"
			(at 0 0 270)
			(layer "F.SilkS")
			(hide yes)
			(effects
				(font
					(size 1.27 1.27)
				)
			)
		)
		(property "Value" "SKT-SAS15P-14P-45-GP"
			(at -20.7645 -8.9789 270)
			(unlocked yes)
			(layer "F.Fab")
			(hide yes)
			(effects
				(font
					(size 1.016 1.016)
					(thickness 0.1524)
				)
			)
		)
		(property "Device Type" "10120818-001C-TRLF"
			(at -20.7645 -10.5029 270)
			(unlocked yes)
			(layer "F.Fab")
			(hide yes)
			(effects
				(font
					(size 1.016 1.016)
					(thickness 0.1524)
				)
			)
		)
		(duplicate_pad_numbers_are_jumpers no)
		(fp_line
			(start 1.651 4.2926)
			(end 1.651 3.0099)
			(stroke
				(width 0.1524)
				(type default)
			)
			(layer "F.SilkS")
		)
		(fp_line
			(start 8.509 4.2926)
			(end 1.651 4.2926)
			(stroke
				(width 0.1524)
				(type default)
			)
			(layer "F.SilkS")
		)
		(fp_line
			(start -23.4188 3.0099)
			(end -23.4188 -3.2512)
			(stroke
				(width 0.1524)
				(type default)
			)
			(layer "F.SilkS")
		)
		(fp_line
			(start 1.651 3.0099)
			(end -23.4188 3.0099)
			(stroke
				(width 0.1524)
				(type default)
			)
			(layer "F.SilkS")
		)
		(fp_line
			(start 8.509 3.0099)
			(end 8.509 4.2926)
			(stroke
				(width 0.1524)
				(type default)
			)
			(layer "F.SilkS")
		)
		(fp_line
			(start 23.4188 3.0099)
			(end 8.509 3.0099)
			(stroke
				(width 0.1524)
				(type default)
			)
			(layer "F.SilkS")
		)
		(fp_line
			(start -23.4188 -3.2512)
			(end 23.4188 -3.2512)
			(stroke
				(width 0.1524)
				(type default)
			)
			(layer "F.SilkS")
		)
		(fp_line
			(start 23.4188 -3.2512)
			(end 23.4188 3.0099)
			(stroke
				(width 0.1524)
				(type default)
			)
			(layer "F.SilkS")
		)
		(fp_line
			(start 15.5067 -3.3401)
			(end 16.2687 -3.3401)
			(stroke
				(width 0.3302)
				(type default)
			)
			(layer "F.SilkS")
		)
		(fp_poly
			(pts
				(xy 15.868904 -3.230372) (xy 16.503904 -3.865372) (xy 15.233904 -3.865372)
			)
			(stroke
				(width 0)
				(type default)
			)
			(fill yes)
			(layer "F.SilkS")
		)
		(fp_poly
			(pts
				(xy -22.8727 -2.7559) (xy 22.8727 -2.7559) (xy 22.8727 2.7559) (xy 8.255 2.7559) (xy 8.255 3.5179)
				(xy 1.905 3.5179) (xy 1.905 2.7559) (xy -22.8727 2.7559)
			)
			(stroke
				(width 0)
				(type default)
			)
			(fill no)
			(layer "F.CrtYd")
		)
		(fp_poly
			(pts
				(xy 1.397 4.5466) (xy 1.397 3.2639) (xy -23.6728 3.2639) (xy -23.6728 -3.5052) (xy 23.6728 -3.5052)
				(xy 23.6728 -0.00635) (xy 22.8727 -0.00635) (xy 22.8727 -2.7559) (xy -22.8727 -2.7559) (xy -22.8727 2.7559)
				(xy 1.905 2.7559) (xy 1.905 3.5179) (xy 8.255 3.5179) (xy 8.255 2.7559) (xy 22.8727 2.7559) (xy 22.8727 0.00635)
				(xy 23.6728 0.00635) (xy 23.6728 3.2639) (xy 8.763 3.2639) (xy 8.763 4.5466)
			)
			(stroke
				(width 0)
				(type default)
			)
			(fill no)
			(layer "F.CrtYd")
		)
		(fp_poly
			(pts
				(xy 1.397 4.5466) (xy 1.397 3.2639) (xy -23.6728 3.2639) (xy -23.6728 -3.5052) (xy 23.6728 -3.5052)
				(xy 23.6728 3.2639) (xy 8.763 3.2639) (xy 8.763 4.5466)
			)
			(stroke
				(width 0)
				(type default)
			)
			(fill no)
			(layer "F.Fab")
		)
		(pad "" np_thru_hole circle
			(at -18.874994 0 270)
			(size 0.254 0.254)
			(drill 1.3462)
			(layers "*.Cu" "*.Mask")
			(clearance 0.9017)
			(thermal_gap 0.9017)
		)
		(pad "" np_thru_hole circle
			(at 18.874994 0 270)
			(size 0.254 0.254)
			(drill 0.9398)
			(layers "*.Cu" "*.Mask")
			(clearance 0.6985)
			(thermal_gap 0.6985)
		)
		(pad "G1" smd rect
			(at 21.874988 0 270)
			(size 2.5908 2.5908)
			(layers "F.Cu" "F.Mask" "F.Paste")
			(net "GND")
		)
		(pad "G2" smd rect
			(at -21.874988 0 270)
			(size 2.5908 2.5908)
			(layers "F.Cu" "F.Mask" "F.Paste")
			(net "GND")
		)
		(pad "P1" smd rect
			(at 1.905 -1.82499 270)
			(size 0.6096 2.3622)
			(layers "F.Cu" "F.Mask" "F.Paste")
			(net "Net_1619")
		)
		(pad "P2" smd rect
			(at 0.635 -1.82499 270)
			(size 0.6096 2.3622)
			(layers "F.Cu" "F.Mask" "F.Paste")
			(net "Net_1620")
		)
		(pad "P3" smd rect
			(at -0.635 -1.82499 270)
			(size 0.6096 2.3622)
			(layers "F.Cu" "F.Mask" "F.Paste")
			(net "Net_1621")
		)
		(pad "P4" smd rect
			(at -1.905 -1.82499 270)
			(size 0.6096 2.3622)
			(layers "F.Cu" "F.Mask" "F.Paste")
			(net "GND")
		)
		(pad "P5" smd rect
			(at -3.175 -1.82499 270)
			(size 0.6096 2.3622)
			(layers "F.Cu" "F.Mask" "F.Paste")
			(net "HDD_PRSNT_35")
		)
		(pad "P6" smd rect
			(at -4.445 -1.82499 270)
			(size 0.6096 2.3622)
			(layers "F.Cu" "F.Mask" "F.Paste")
			(net "GND")
		)
		(pad "P7" smd rect
			(at -5.715 -1.82499 270)
			(size 0.6096 2.3622)
			(layers "F.Cu" "F.Mask" "F.Paste")
			(net "5V_PRE_35")
		)
		(pad "P8" smd rect
			(at -6.985 -1.82499 270)
			(size 0.6096 2.3622)
			(layers "F.Cu" "F.Mask" "F.Paste")
			(net "P5V_HDD35")
		)
		(pad "P9" smd rect
			(at -8.255 -1.82499 270)
			(size 0.6096 2.3622)
			(layers "F.Cu" "F.Mask" "F.Paste")
			(net "P5V_HDD35")
		)
		(pad "P10" smd rect
			(at -9.525 -1.82499 270)
			(size 0.6096 2.3622)
			(layers "F.Cu" "F.Mask" "F.Paste")
			(net "GND")
		)
		(pad "P11" smd rect
			(at -10.795 -1.82499 270)
			(size 0.6096 2.3622)
			(layers "F.Cu" "F.Mask" "F.Paste")
			(net "ACT_HDD_35")
		)
		(pad "P12" smd rect
			(at -12.065 -1.82499 270)
			(size 0.6096 2.3622)
			(layers "F.Cu" "F.Mask" "F.Paste")
			(net "GND")
		)
		(pad "P13" smd rect
			(at -13.335 -1.82499 270)
			(size 0.6096 2.3622)
			(layers "F.Cu" "F.Mask" "F.Paste")
			(net "12V_PRE_35")
		)
		(pad "P14" smd rect
			(at -14.605 -1.82499 270)
			(size 0.6096 2.3622)
			(layers "F.Cu" "F.Mask" "F.Paste")
			(net "P12V_HDD35")
		)
		(pad "P15" smd rect
			(at -15.875 -1.82499 270)
			(size 0.6096 2.3622)
			(layers "F.Cu" "F.Mask" "F.Paste")
			(net "P12V_HDD35")
		)
		(pad "S1" smd rect
			(at 15.875 -1.82499 270)
			(size 0.6096 2.3622)
			(layers "F.Cu" "F.Mask" "F.Paste")
			(net "GND")
		)
		(pad "S2" smd rect
			(at 14.605 -1.82499 270)
			(size 0.6096 2.3622)
			(layers "F.Cu" "F.Mask" "F.Paste")
			(net "SAS_HDD_RX_P35")
		)
		(pad "S3" smd rect
			(at 13.335 -1.82499 270)
			(size 0.6096 2.3622)
			(layers "F.Cu" "F.Mask" "F.Paste")
			(net "SAS_HDD_RX_N35")
		)
		(pad "S4" smd rect
			(at 12.065 -1.82499 270)
			(size 0.6096 2.3622)
			(layers "F.Cu" "F.Mask" "F.Paste")
			(net "GND")
		)
		(pad "S5" smd rect
			(at 10.795 -1.82499 270)
			(size 0.6096 2.3622)
			(layers "F.Cu" "F.Mask" "F.Paste")
			(net "PHY_DRV_B_TO_SCC_B_35_DN")
		)
		(pad "S6" smd rect
			(at 9.525 -1.82499 270)
			(size 0.6096 2.3622)
			(layers "F.Cu" "F.Mask" "F.Paste")
			(net "PHY_DRV_B_TO_SCC_B_35_DP")
		)
		(pad "S7" smd rect
			(at 8.255 -1.82499 270)
			(size 0.6096 2.3622)
			(layers "F.Cu" "F.Mask" "F.Paste")
			(net "GND")
		)
		(pad "S8" smd rect
			(at 7.480046 2.845054 270)
			(size 0.508 2.3622)
			(layers "F.Cu" "F.Mask" "F.Paste")
			(net "GND")
		)
		(pad "S9" smd rect
			(at 6.679946 2.845054 270)
			(size 0.508 2.3622)
			(layers "F.Cu" "F.Mask" "F.Paste")
			(net "Net_460")
		)
		(pad "S10" smd rect
			(at 5.8801 2.845054 270)
			(size 0.508 2.3622)
			(layers "F.Cu" "F.Mask" "F.Paste")
			(net "Net_352")
		)
		(pad "S11" smd rect
			(at 5.08 2.845054 270)
			(size 0.508 2.3622)
			(layers "F.Cu" "F.Mask" "F.Paste")
			(net "GND")
		)
		(pad "S12" smd rect
			(at 4.2799 2.845054 270)
			(size 0.508 2.3622)
			(layers "F.Cu" "F.Mask" "F.Paste")
			(net "Net_388")
		)
		(pad "S13" smd rect
			(at 3.480054 2.845054 270)
			(size 0.508 2.3622)
			(layers "F.Cu" "F.Mask" "F.Paste")
			(net "Net_424")
		)
		(pad "S14" smd rect
			(at 2.679954 2.845054 270)
			(size 0.508 2.3622)
			(layers "F.Cu" "F.Mask" "F.Paste")
			(net "GND")
		)
		(zone
			(layer "F.Cu")
			(hatch none 0.5)
			(connect_pads
				(clearance 0)
			)
			(min_thickness 0.25)
			(keepout
				(tracks allowed)
				(vias not_allowed)
				(pads allowed)
				(copperpour not_allowed)
				(footprints allowed)
			)
			(placement
				(enabled no)
				(sheetname "")
			)
			(fill
				(thermal_gap 0.5)
				(thermal_bridge_width 0.5)
				(island_removal_mode 0)
			)
			(polygon
				(pts
					(xy 486.957624 -45.648626) (xy 479.883724 -45.648626) (xy 479.883724 -52.582826) (xy 480.988624 -52.582826)
					(xy 480.988624 -48.468026) (xy 485.611424 -48.468026) (xy 485.611424 -52.582826) (xy 486.957624 -52.582826)
				)
			)
		)
		(zone
			(layer "F.Cu")
			(hatch none 0.5)
			(connect_pads
				(clearance 0)
			)
			(min_thickness 0.25)
			(keepout
				(tracks not_allowed)
				(vias allowed)
				(pads allowed)
				(copperpour not_allowed)
				(footprints allowed)
			)
			(placement
				(enabled no)
				(sheetname "")
			)
			(fill
				(thermal_gap 0.5)
				(thermal_bridge_width 0.5)
				(island_removal_mode 0)
			)
			(polygon
				(pts
					(xy 486.957624 -45.648626) (xy 479.883724 -45.648626) (xy 479.883724 -52.582826) (xy 480.988624 -52.582826)
					(xy 480.988624 -48.468026) (xy 485.611424 -48.468026) (xy 485.611424 -52.582826) (xy 486.957624 -52.582826)
				)
			)
		)
		(zone
			(layer "F.Cu")
			(hatch none 0.5)
			(connect_pads
				(clearance 0)
			)
			(min_thickness 0.25)
			(keepout
				(tracks not_allowed)
				(vias allowed)
				(pads allowed)
				(copperpour not_allowed)
				(footprints allowed)
			)
			(placement
				(enabled no)
				(sheetname "")
			)
			(fill
				(thermal_gap 0.5)
				(thermal_bridge_width 0.5)
				(island_removal_mode 0)
			)
			(polygon
				(pts
					(xy 486.957624 -12.171426) (xy 479.883724 -12.171426) (xy 479.883724 -5.237226) (xy 480.988624 -5.237226)
					(xy 480.988624 -9.352026) (xy 485.611424 -9.352026) (xy 485.611424 -5.237226) (xy 486.957624 -5.237226)
				)
			)
		)
		(zone
			(layer "F.Cu")
			(hatch none 0.5)
			(connect_pads
				(clearance 0)
			)
			(min_thickness 0.25)
			(keepout
				(tracks allowed)
				(vias not_allowed)
				(pads allowed)
				(copperpour not_allowed)
				(footprints allowed)
			)
			(placement
				(enabled no)
				(sheetname "")
			)
			(fill
				(thermal_gap 0.5)
				(thermal_bridge_width 0.5)
				(island_removal_mode 0)
			)
			(polygon
				(pts
					(xy 486.957624 -12.171426) (xy 479.883724 -12.171426) (xy 479.883724 -5.237226) (xy 480.988624 -5.237226)
					(xy 480.988624 -9.352026) (xy 485.611424 -9.352026) (xy 485.611424 -5.237226) (xy 486.957624 -5.237226)
				)
			)
		)
		(zone
			(layers "F.Cu" "B.Cu" "In1.Cu" "In2.Cu" "In3.Cu" "In4.Cu" "In5.Cu" "In6.Cu")
			(hatch none 0.5)
			(connect_pads
				(clearance 0)
			)
			(min_thickness 0.25)
			(keepout
				(tracks not_allowed)
				(vias allowed)
				(pads allowed)
				(copperpour not_allowed)
				(footprints allowed)
			)
			(placement
				(enabled no)
				(sheetname "")
			)
			(fill
				(thermal_gap 0.5)
				(thermal_bridge_width 0.5)
				(island_removal_mode 0)
			)
			(polygon
				(pts
					(arc
						(start 484.074724 -10.035032)
						(mid 482.525324 -10.035032)
						(end 484.074724 -10.035032)
					)
				)
			)
		)
		(zone
			(layers "F.Cu" "B.Cu" "In1.Cu" "In2.Cu" "In3.Cu" "In4.Cu" "In5.Cu" "In6.Cu")
			(hatch none 0.5)
			(connect_pads
				(clearance 0)
			)
			(min_thickness 0.25)
			(keepout
				(tracks not_allowed)
				(vias allowed)
				(pads allowed)
				(copperpour not_allowed)
				(footprints allowed)
			)
			(placement
				(enabled no)
				(sheetname "")
			)
			(fill
				(thermal_gap 0.5)
				(thermal_bridge_width 0.5)
				(island_removal_mode 0)
			)
			(polygon
				(pts
					(arc
						(start 484.277924 -47.78502)
						(mid 482.322124 -47.78502)
						(end 484.277924 -47.78502)
					)
				)
			)
		)
	)
	(footprint ""
		(layer "F.Cu")
		(at 257.331972 -349.399606 90)
		(property "Reference" "Q201"
			(at 0 0 90)
			(layer "F.SilkS")
			(hide yes)
			(effects
				(font
					(size 1.27 1.27)
				)
			)
		)
		(property "Value" "IRFH8201TRPBF-GP"
			(at -4.2164 -4.3688 90)
			(unlocked yes)
			(layer "F.Fab")
			(hide yes)
			(effects
				(font
					(size 1.016 1.016)
					(thickness 0.1524)
				)
			)
		)
		(property "Device Type" "PPAK-5PH42"
			(at -4.2164 -5.8928 90)
			(unlocked yes)
			(layer "F.Fab")
			(hide yes)
			(effects
				(font
					(size 1.016 1.016)
					(thickness 0.1524)
				)
			)
		)
		(duplicate_pad_numbers_are_jumpers no)
		(fp_line
			(start 2.8956 -2.794)
			(end 2.8956 4.826)
			(stroke
				(width 0.1524)
				(type default)
			)
			(layer "F.SilkS")
		)
		(fp_line
			(start -2.8956 -2.794)
			(end 2.8956 -2.794)
			(stroke
				(width 0.1524)
				(type default)
			)
			(layer "F.SilkS")
		)
		(fp_line
			(start 2.8956 4.826)
			(end -2.8956 4.826)
			(stroke
				(width 0.1524)
				(type default)
			)
			(layer "F.SilkS")
		)
		(fp_line
			(start -2.8956 4.826)
			(end -2.8956 -2.794)
			(stroke
				(width 0.1524)
				(type default)
			)
			(layer "F.SilkS")
		)
		(fp_line
			(start -1.9431 4.9276)
			(end -3.0353 4.9276)
			(stroke
				(width 0.3302)
				(type default)
			)
			(layer "F.SilkS")
		)
		(fp_line
			(start -3.0353 4.9276)
			(end -3.0353 3.9624)
			(stroke
				(width 0.3302)
				(type default)
			)
			(layer "F.SilkS")
		)
		(fp_poly
			(pts
				(xy -2.3622 5.334) (xy -1.4986 5.334) (xy -1.9304 4.9022)
			)
			(stroke
				(width 0)
				(type default)
			)
			(fill yes)
			(layer "F.SilkS")
		)
		(fp_poly
			(pts
				(xy 0.3556 -0.3556) (xy 2.6416 -0.3556) (xy 2.6416 -2.54) (xy 0.3556 -2.54)
			)
			(stroke
				(width 0)
				(type default)
			)
			(fill yes)
			(layer "F.Paste")
		)
		(fp_poly
			(pts
				(xy -2.6416 -0.3556) (xy -0.3556 -0.3556) (xy -0.3556 -2.54) (xy -2.6416 -2.54)
			)
			(stroke
				(width 0)
				(type default)
			)
			(fill yes)
			(layer "F.Paste")
		)
		(fp_poly
			(pts
				(xy 0.3556 2.54) (xy 2.6416 2.54) (xy 2.6416 0.3556) (xy 0.3556 0.3556)
			)
			(stroke
				(width 0)
				(type default)
			)
			(fill yes)
			(layer "F.Paste")
		)
		(fp_poly
			(pts
				(xy -2.6416 2.54) (xy -0.3556 2.54) (xy -0.3556 0.3556) (xy -2.6416 0.3556)
			)
			(stroke
				(width 0)
				(type default)
			)
			(fill yes)
			(layer "F.Paste")
		)
		(fp_rect
			(start -2.5781 3.9878)
			(end 2.5781 -2.1082)
			(stroke
				(width 0)
				(type default)
			)
			(fill no)
			(layer "F.CrtYd")
		)
		(fp_poly
			(pts
				(xy -3.1496 5.08) (xy -3.1496 -3.048) (xy 3.1496 -3.048) (xy 3.1496 3.9751) (xy 2.5781 3.9751) (xy 2.5781 -2.1082)
				(xy -2.5781 -2.1082) (xy -2.5781 3.9878) (xy 3.1496 3.9878) (xy 3.1496 5.08)
			)
			(stroke
				(width 0)
				(type default)
			)
			(fill no)
			(layer "F.CrtYd")
		)
		(fp_rect
			(start -3.1496 5.08)
			(end 3.1496 -3.048)
			(stroke
				(width 0)
				(type default)
			)
			(fill no)
			(layer "F.Fab")
		)
		(pad "1" smd rect
			(at -1.905 3.81 90)
			(size 0.762 1.524)
			(layers "F.Cu" "F.Mask" "F.Paste")
			(net "P12V_B")
		)
		(pad "2" smd rect
			(at -0.635 3.81 90)
			(size 0.762 1.524)
			(layers "F.Cu" "F.Mask" "F.Paste")
			(net "P12V_B")
		)
		(pad "3" smd rect
			(at 0.635 3.81 90)
			(size 0.762 1.524)
			(layers "F.Cu" "F.Mask" "F.Paste")
			(net "P12V_B")
		)
		(pad "4" smd rect
			(at 1.905 3.81 90)
			(size 0.762 1.524)
			(layers "F.Cu" "F.Mask" "F.Paste")
			(net "MB3_12V_CTRL_GATE1")
		)
		(pad "5" smd rect
			(at 0 0 90)
			(size 5.2832 5.08)
			(layers "F.Cu" "F.Mask" "F.Paste")
			(net "MB3_P12V_IN_R")
		)
		(pad "6" smd rect
			(at 0.635 -2.032 90)
			(size 0.0254 0.0254)
			(layers "F.Cu" "F.Mask" "F.Paste")
			(net "MB3_P12V_IN_R")
		)
		(pad "7" smd rect
			(at -0.635 -2.032 90)
			(size 0.0254 0.0254)
			(layers "F.Cu" "F.Mask" "F.Paste")
			(net "MB3_P12V_IN_R")
		)
		(pad "8" smd rect
			(at -1.905 -2.032 90)
			(size 0.0254 0.0254)
			(layers "F.Cu" "F.Mask" "F.Paste")
			(net "MB3_P12V_IN_R")
		)
	)
	(footprint ""
		(layer "F.Cu")
		(at 463.058002 -231.62895 -90)
		(property "Reference" "R1136"
			(at 0 0 270)
			(layer "F.SilkS")
			(hide yes)
			(effects
				(font
					(size 1.27 1.27)
				)
			)
		)
		(property "Value" "0R2J-2-GP"
			(at 0.064008 -3.993896 270)
			(unlocked yes)
			(layer "F.Fab")
			(hide yes)
			(effects
				(font
					(size 1.016 1.016)
					(thickness 0.1524)
				)
			)
		)
		(property "Device Type" "R402H16"
			(at 0.064008 -5.517896 270)
			(unlocked yes)
			(layer "F.Fab")
			(hide yes)
			(effects
				(font
					(size 1.016 1.016)
					(thickness 0.1524)
				)
			)
		)
		(duplicate_pad_numbers_are_jumpers no)
		(fp_line
			(start -0.508 -0.9398)
			(end -0.508 0.9398)
			(stroke
				(width 0.1524)
				(type default)
			)
			(layer "F.SilkS")
		)
		(fp_line
			(start 0.508 -0.9398)
			(end -0.508 -0.9398)
			(stroke
				(width 0.1524)
				(type default)
			)
			(layer "F.SilkS")
		)
		(fp_rect
			(start -0.508 0.9398)
			(end 0.508 -0.9398)
			(stroke
				(width 0)
				(type default)
			)
			(fill no)
			(layer "F.CrtYd")
		)
		(fp_rect
			(start -0.508 0.9398)
			(end 0.508 -0.9398)
			(stroke
				(width 0)
				(type default)
			)
			(fill no)
			(layer "F.Fab")
		)
		(pad "1" smd custom
			(at 0 -0.4445 270)
			(size 0.1397 0.1397)
			(layers "F.Cu" "F.Mask" "F.Paste")
			(net "P12V_B_PGOOD")
			(options
				(clearance outline)
				(anchor circle)
			)
			(primitives
				(gr_poly
					(pts
						(arc
							(start -0.1778 -0.2794)
							(mid -0.249642 -0.249642)
							(end -0.2794 -0.1778)
						)
						(arc
							(start -0.2794 0.1778)
							(mid -0.249642 0.249642)
							(end -0.1778 0.2794)
						)
						(arc
							(start 0.1778 0.2794)
							(mid 0.249642 0.249642)
							(end 0.2794 0.1778)
						)
						(arc
							(start 0.2794 -0.1778)
							(mid 0.249642 -0.249642)
							(end 0.1778 -0.2794)
						)
					)
					(width 0)
					(fill yes)
				)
			)
		)
		(pad "2" smd custom
			(at 0 0.4445 270)
			(size 0.1397 0.1397)
			(layers "F.Cu" "F.Mask" "F.Paste")
			(net "P5V_B_3_EN_R")
			(options
				(clearance outline)
				(anchor circle)
			)
			(primitives
				(gr_poly
					(pts
						(arc
							(start -0.1778 -0.2794)
							(mid -0.249642 -0.249642)
							(end -0.2794 -0.1778)
						)
						(arc
							(start -0.2794 0.1778)
							(mid -0.249642 0.249642)
							(end -0.1778 0.2794)
						)
						(arc
							(start 0.1778 0.2794)
							(mid 0.249642 0.249642)
							(end 0.2794 0.1778)
						)
						(arc
							(start 0.2794 -0.1778)
							(mid 0.249642 -0.249642)
							(end 0.1778 -0.2794)
						)
					)
					(width 0)
					(fill yes)
				)
			)
		)
	)
	(footprint ""
		(layer "F.Cu")
		(at 161.544 -148.082 -90)
		(property "Reference" "R438"
			(at 0 0 270)
			(layer "F.SilkS")
			(hide yes)
			(effects
				(font
					(size 1.27 1.27)
				)
			)
		)
		(property "Value" "10KR2F-2-GP"
			(at 0.064008 -3.993896 270)
			(unlocked yes)
			(layer "F.Fab")
			(hide yes)
			(effects
				(font
					(size 1.016 1.016)
					(thickness 0.1524)
				)
			)
		)
		(property "Device Type" "R402H16"
			(at 0.064008 -5.517896 270)
			(unlocked yes)
			(layer "F.Fab")
			(hide yes)
			(effects
				(font
					(size 1.016 1.016)
					(thickness 0.1524)
				)
			)
		)
		(duplicate_pad_numbers_are_jumpers no)
		(fp_line
			(start -0.508 -0.9398)
			(end -0.508 0.9398)
			(stroke
				(width 0.1524)
				(type default)
			)
			(layer "F.SilkS")
		)
		(fp_line
			(start 0.508 -0.9398)
			(end -0.508 -0.9398)
			(stroke
				(width 0.1524)
				(type default)
			)
			(layer "F.SilkS")
		)
		(fp_rect
			(start -0.508 0.9398)
			(end 0.508 -0.9398)
			(stroke
				(width 0)
				(type default)
			)
			(fill no)
			(layer "F.CrtYd")
		)
		(fp_rect
			(start -0.508 0.9398)
			(end 0.508 -0.9398)
			(stroke
				(width 0)
				(type default)
			)
			(fill no)
			(layer "F.Fab")
		)
		(pad "1" smd custom
			(at 0 -0.4445 270)
			(size 0.1397 0.1397)
			(layers "F.Cu" "F.Mask" "F.Paste")
			(net "P3V3_STBY_B")
			(options
				(clearance outline)
				(anchor circle)
			)
			(primitives
				(gr_poly
					(pts
						(arc
							(start -0.1778 -0.2794)
							(mid -0.249642 -0.249642)
							(end -0.2794 -0.1778)
						)
						(arc
							(start -0.2794 0.1778)
							(mid -0.249642 0.249642)
							(end -0.1778 0.2794)
						)
						(arc
							(start 0.1778 0.2794)
							(mid 0.249642 0.249642)
							(end 0.2794 0.1778)
						)
						(arc
							(start 0.2794 -0.1778)
							(mid 0.249642 -0.249642)
							(end 0.1778 -0.2794)
						)
					)
					(width 0)
					(fill yes)
				)
			)
		)
		(pad "2" smd custom
			(at 0 0.4445 270)
			(size 0.1397 0.1397)
			(layers "F.Cu" "F.Mask" "F.Paste")
			(net "HDD_PRSNT_16")
			(options
				(clearance outline)
				(anchor circle)
			)
			(primitives
				(gr_poly
					(pts
						(arc
							(start -0.1778 -0.2794)
							(mid -0.249642 -0.249642)
							(end -0.2794 -0.1778)
						)
						(arc
							(start -0.2794 0.1778)
							(mid -0.249642 0.249642)
							(end -0.1778 0.2794)
						)
						(arc
							(start 0.1778 0.2794)
							(mid 0.249642 0.249642)
							(end 0.2794 0.1778)
						)
						(arc
							(start 0.2794 -0.1778)
							(mid 0.249642 -0.249642)
							(end 0.1778 -0.2794)
						)
					)
					(width 0)
					(fill yes)
				)
			)
		)
	)
	(footprint ""
		(layer "F.Cu")
		(at 314.569348 -213.153752)
		(property "Reference" "R300"
			(at 0 0 0)
			(layer "F.SilkS")
			(hide yes)
			(effects
				(font
					(size 1.27 1.27)
				)
			)
		)
		(property "Value" "130R3F-GP"
			(at -0.0254 -2.5146 0)
			(unlocked yes)
			(layer "F.Fab")
			(hide yes)
			(effects
				(font
					(size 1.016 1.016)
					(thickness 0.1524)
				)
			)
		)
		(property "Device Type" "R603H22"
			(at -0.0254 -4.0386 0)
			(unlocked yes)
			(layer "F.Fab")
			(hide yes)
			(effects
				(font
					(size 1.016 1.016)
					(thickness 0.1524)
				)
			)
		)
		(duplicate_pad_numbers_are_jumpers no)
		(fp_line
			(start -0.4826 0)
			(end -0.2032 0)
			(stroke
				(width 0.2032)
				(type default)
			)
			(layer "F.SilkS")
		)
		(fp_line
			(start 0.2032 0)
			(end 0.4826 0)
			(stroke
				(width 0.2032)
				(type default)
			)
			(layer "F.SilkS")
		)
		(fp_rect
			(start -0.5842 1.3335)
			(end 0.5842 -1.3335)
			(stroke
				(width 0)
				(type default)
			)
			(fill no)
			(layer "F.CrtYd")
		)
		(fp_rect
			(start -0.5842 1.3335)
			(end 0.5842 -1.3335)
			(stroke
				(width 0)
				(type default)
			)
			(fill no)
			(layer "F.Fab")
		)
		(pad "1" smd custom
			(at 0 -0.762)
			(size 0.2159 0.2159)
			(layers "F.Cu" "F.Mask" "F.Paste")
			(net "P5V_B_3")
			(options
				(clearance outline)
				(anchor circle)
			)
			(primitives
				(gr_poly
					(pts
						(arc
							(start -0.3302 -0.4318)
							(mid -0.402042 -0.402042)
							(end -0.4318 -0.3302)
						)
						(arc
							(start -0.4318 0.3302)
							(mid -0.402042 0.402042)
							(end -0.3302 0.4318)
						)
						(arc
							(start 0.3302 0.4318)
							(mid 0.402042 0.402042)
							(end 0.4318 0.3302)
						)
						(arc
							(start 0.4318 -0.3302)
							(mid 0.402042 -0.402042)
							(end 0.3302 -0.4318)
						)
					)
					(width 0)
					(fill yes)
				)
			)
		)
		(pad "2" smd custom
			(at 0 0.762)
			(size 0.2159 0.2159)
			(layers "F.Cu" "F.Mask" "F.Paste")
			(net "FLT_HDD6")
			(options
				(clearance outline)
				(anchor circle)
			)
			(primitives
				(gr_poly
					(pts
						(arc
							(start -0.3302 -0.4318)
							(mid -0.402042 -0.402042)
							(end -0.4318 -0.3302)
						)
						(arc
							(start -0.4318 0.3302)
							(mid -0.402042 0.402042)
							(end -0.3302 0.4318)
						)
						(arc
							(start 0.3302 0.4318)
							(mid 0.402042 0.402042)
							(end 0.4318 0.3302)
						)
						(arc
							(start 0.4318 -0.3302)
							(mid 0.402042 -0.402042)
							(end 0.3302 -0.4318)
						)
					)
					(width 0)
					(fill yes)
				)
			)
		)
	)
	(footprint ""
		(layer "F.Cu")
		(at 366.395 -138.938 -90)
		(property "Reference" "Q87"
			(at 0 0 270)
			(layer "F.SilkS")
			(hide yes)
			(effects
				(font
					(size 1.27 1.27)
				)
			)
		)
		(property "Value" "AO4406AL-GP"
			(at -3.707384 -1.5367 270)
			(unlocked yes)
			(layer "F.Fab")
			(hide yes)
			(effects
				(font
					(size 1.016 1.016)
					(thickness 0.1524)
				)
			)
		)
		(property "Device Type" "SOIC8H69"
			(at -3.707384 -3.0607 270)
			(unlocked yes)
			(layer "F.Fab")
			(hide yes)
			(effects
				(font
					(size 1.016 1.016)
					(thickness 0.1524)
				)
			)
		)
		(duplicate_pad_numbers_are_jumpers no)
		(fp_line
			(start -2.6289 3.4417)
			(end -2.6289 1.4732)
			(stroke
				(width 0.381)
				(type default)
			)
			(layer "F.SilkS")
		)
		(fp_line
			(start -2.7432 1.4224)
			(end -2.6416 1.4224)
			(stroke
				(width 0.1524)
				(type default)
			)
			(layer "F.SilkS")
		)
		(fp_line
			(start -2.7432 1.4224)
			(end 2.1336 1.4224)
			(stroke
				(width 0.1524)
				(type default)
			)
			(layer "F.SilkS")
		)
		(fp_line
			(start 2.1336 1.4224)
			(end 2.1336 -1.4224)
			(stroke
				(width 0.1524)
				(type default)
			)
			(layer "F.SilkS")
		)
		(fp_line
			(start -2.1844 -0.0508)
			(end -2.7178 0.508)
			(stroke
				(width 0.1524)
				(type default)
			)
			(layer "F.SilkS")
		)
		(fp_line
			(start -2.7178 -0.508)
			(end -2.1844 -0.0508)
			(stroke
				(width 0.1524)
				(type default)
			)
			(layer "F.SilkS")
		)
		(fp_line
			(start -2.7432 -1.4224)
			(end -2.7432 1.4224)
			(stroke
				(width 0.1524)
				(type default)
			)
			(layer "F.SilkS")
		)
		(fp_line
			(start 2.1336 -1.4224)
			(end -2.7432 -1.4224)
			(stroke
				(width 0.1524)
				(type default)
			)
			(layer "F.SilkS")
		)
		(fp_poly
			(pts
				(xy -2.2098 -1.4224) (xy -2.2098 1.4224) (xy 2.2098 1.4224) (xy 2.2098 -1.4224)
			)
			(stroke
				(width 0)
				(type default)
			)
			(fill yes)
			(layer "F.SilkS")
		)
		(fp_rect
			(start -2.450084 2.999994)
			(end 2.450084 -2.999994)
			(stroke
				(width 0)
				(type default)
			)
			(fill no)
			(layer "F.CrtYd")
		)
		(fp_poly
			(pts
				(xy -2.8194 3.6322) (xy -2.8194 -3.6322) (xy 2.8194 -3.6322) (xy 2.8194 1.18364) (xy 2.450084 1.18364)
				(xy 2.450084 -2.999994) (xy -2.450084 -2.999994) (xy -2.450084 2.999994) (xy 2.450084 2.999994)
				(xy 2.450084 1.18618) (xy 2.8194 1.18618) (xy 2.8194 3.6322)
			)
			(stroke
				(width 0)
				(type default)
			)
			(fill no)
			(layer "F.CrtYd")
		)
		(fp_rect
			(start -2.8194 3.6322)
			(end 2.8194 -3.6322)
			(stroke
				(width 0)
				(type default)
			)
			(fill no)
			(layer "F.Fab")
		)
		(pad "1" smd rect
			(at -1.905 2.54 270)
			(size 0.635 1.651)
			(layers "F.Cu" "F.Mask" "F.Paste")
			(net "P5V_HDD19")
		)
		(pad "2" smd rect
			(at -0.635 2.54 270)
			(size 0.635 1.651)
			(layers "F.Cu" "F.Mask" "F.Paste")
			(net "P5V_HDD19")
		)
		(pad "3" smd rect
			(at 0.635 2.54 270)
			(size 0.635 1.651)
			(layers "F.Cu" "F.Mask" "F.Paste")
			(net "P5V_HDD19")
		)
		(pad "4" smd rect
			(at 1.905 2.54 270)
			(size 0.635 1.651)
			(layers "F.Cu" "F.Mask" "F.Paste")
			(net "SW_HDD_P19")
		)
		(pad "5" smd rect
			(at 1.905 -2.54 270)
			(size 0.635 1.651)
			(layers "F.Cu" "F.Mask" "F.Paste")
			(net "P5V_B_3")
		)
		(pad "6" smd rect
			(at 0.635 -2.54 270)
			(size 0.635 1.651)
			(layers "F.Cu" "F.Mask" "F.Paste")
			(net "P5V_B_3")
		)
		(pad "7" smd rect
			(at -0.635 -2.54 270)
			(size 0.635 1.651)
			(layers "F.Cu" "F.Mask" "F.Paste")
			(net "P5V_B_3")
		)
		(pad "8" smd rect
			(at -1.905 -2.54 270)
			(size 0.635 1.651)
			(layers "F.Cu" "F.Mask" "F.Paste")
			(net "P5V_B_3")
		)
	)
	(footprint ""
		(layer "F.Cu")
		(at 170.815 -375.412)
		(property "Reference" "C539"
			(at 0 0 0)
			(layer "F.SilkS")
			(hide yes)
			(effects
				(font
					(size 1.27 1.27)
				)
			)
		)
		(property "Value" "SC1KP50V2KX-1GP"
			(at 1.1811 -2.7051 0)
			(unlocked yes)
			(layer "F.Fab")
			(hide yes)
			(effects
				(font
					(size 1.016 1.016)
					(thickness 0.1524)
				)
			)
		)
		(property "Device Type" "C402H22"
			(at 1.1811 -4.2291 0)
			(unlocked yes)
			(layer "F.Fab")
			(hide yes)
			(effects
				(font
					(size 1.016 1.016)
					(thickness 0.1524)
				)
			)
		)
		(duplicate_pad_numbers_are_jumpers no)
		(fp_rect
			(start -0.4318 0.9525)
			(end 0.4318 -0.9525)
			(stroke
				(width 0)
				(type default)
			)
			(fill no)
			(layer "F.CrtYd")
		)
		(fp_rect
			(start -0.4318 0.9525)
			(end 0.4318 -0.9525)
			(stroke
				(width 0)
				(type default)
			)
			(fill no)
			(layer "F.Fab")
		)
		(pad "1" smd custom
			(at 0 -0.4445)
			(size 0.1524 0.1524)
			(layers "F.Cu" "F.Mask" "F.Paste")
			(net "MB0_TEMP_B")
			(options
				(clearance outline)
				(anchor circle)
			)
			(primitives
				(gr_poly
					(pts
						(arc
							(start 0.3048 -0.2032)
							(mid 0.275042 -0.275042)
							(end 0.2032 -0.3048)
						)
						(arc
							(start -0.2032 -0.3048)
							(mid -0.275042 -0.275042)
							(end -0.3048 -0.2032)
						)
						(arc
							(start -0.3048 0.2032)
							(mid -0.275042 0.275042)
							(end -0.2032 0.3048)
						)
						(arc
							(start 0.2032 0.3048)
							(mid 0.275042 0.275042)
							(end 0.3048 0.2032)
						)
					)
					(width 0)
					(fill yes)
				)
			)
		)
		(pad "2" smd custom
			(at 0 0.4445)
			(size 0.1524 0.1524)
			(layers "F.Cu" "F.Mask" "F.Paste")
			(net "MB0_TEMP_E")
			(options
				(clearance outline)
				(anchor circle)
			)
			(primitives
				(gr_poly
					(pts
						(arc
							(start 0.3048 -0.2032)
							(mid 0.275042 -0.275042)
							(end 0.2032 -0.3048)
						)
						(arc
							(start -0.2032 -0.3048)
							(mid -0.275042 -0.275042)
							(end -0.3048 -0.2032)
						)
						(arc
							(start -0.3048 0.2032)
							(mid -0.275042 0.275042)
							(end -0.2032 0.3048)
						)
						(arc
							(start 0.2032 0.3048)
							(mid 0.275042 0.275042)
							(end 0.3048 0.2032)
						)
					)
					(width 0)
					(fill yes)
				)
			)
		)
	)
	(footprint ""
		(layer "F.Cu")
		(at 329.819 -160.401 180)
		(property "Reference" "C271"
			(at 0 0 180)
			(layer "F.SilkS")
			(hide yes)
			(effects
				(font
					(size 1.27 1.27)
				)
			)
		)
		(property "Value" "SC1U25V3KX-GP"
			(at 0 -2.8194 180)
			(unlocked yes)
			(layer "F.Fab")
			(hide yes)
			(effects
				(font
					(size 1.016 1.016)
					(thickness 0.1524)
				)
			)
		)
		(property "Device Type" "C603H36"
			(at 0 -4.3434 180)
			(unlocked yes)
			(layer "F.Fab")
			(hide yes)
			(effects
				(font
					(size 1.016 1.016)
					(thickness 0.1524)
				)
			)
		)
		(duplicate_pad_numbers_are_jumpers no)
		(fp_line
			(start 0.508 0)
			(end -0.508 0)
			(stroke
				(width 0.2032)
				(type default)
			)
			(layer "F.SilkS")
		)
		(fp_rect
			(start -0.5842 1.3335)
			(end 0.5842 -1.3335)
			(stroke
				(width 0)
				(type default)
			)
			(fill no)
			(layer "F.CrtYd")
		)
		(fp_rect
			(start -0.5842 1.3335)
			(end 0.5842 -1.3335)
			(stroke
				(width 0)
				(type default)
			)
			(fill no)
			(layer "F.Fab")
		)
		(pad "1" smd custom
			(at 0 -0.762 180)
			(size 0.2159 0.2159)
			(layers "F.Cu" "F.Mask" "F.Paste")
			(net "P12V_HDD18")
			(options
				(clearance outline)
				(anchor circle)
			)
			(primitives
				(gr_poly
					(pts
						(arc
							(start -0.3302 -0.4318)
							(mid -0.402042 -0.402042)
							(end -0.4318 -0.3302)
						)
						(arc
							(start -0.4318 0.3302)
							(mid -0.402042 0.402042)
							(end -0.3302 0.4318)
						)
						(arc
							(start 0.3302 0.4318)
							(mid 0.402042 0.402042)
							(end 0.4318 0.3302)
						)
						(arc
							(start 0.4318 -0.3302)
							(mid 0.402042 -0.402042)
							(end 0.3302 -0.4318)
						)
					)
					(width 0)
					(fill yes)
				)
			)
		)
		(pad "2" smd custom
			(at 0 0.762 180)
			(size 0.2159 0.2159)
			(layers "F.Cu" "F.Mask" "F.Paste")
			(net "GND")
			(options
				(clearance outline)
				(anchor circle)
			)
			(primitives
				(gr_poly
					(pts
						(arc
							(start -0.3302 -0.4318)
							(mid -0.402042 -0.402042)
							(end -0.4318 -0.3302)
						)
						(arc
							(start -0.4318 0.3302)
							(mid -0.402042 0.402042)
							(end -0.3302 0.4318)
						)
						(arc
							(start 0.3302 0.4318)
							(mid 0.402042 0.402042)
							(end 0.4318 0.3302)
						)
						(arc
							(start 0.4318 -0.3302)
							(mid 0.402042 -0.402042)
							(end 0.3302 -0.4318)
						)
					)
					(width 0)
					(fill yes)
				)
			)
		)
	)
	(footprint ""
		(layer "F.Cu")
		(at 436.412386 -119.178578 180)
		(property "Reference" "R1172"
			(at 0 0 180)
			(layer "F.SilkS")
			(hide yes)
			(effects
				(font
					(size 1.27 1.27)
				)
			)
		)
		(property "Value" "619KR2F-GP"
			(at 0.064008 -3.993896 180)
			(unlocked yes)
			(layer "F.Fab")
			(hide yes)
			(effects
				(font
					(size 1.016 1.016)
					(thickness 0.1524)
				)
			)
		)
		(property "Device Type" "R402H16"
			(at 0.064008 -5.517896 180)
			(unlocked yes)
			(layer "F.Fab")
			(hide yes)
			(effects
				(font
					(size 1.016 1.016)
					(thickness 0.1524)
				)
			)
		)
		(duplicate_pad_numbers_are_jumpers no)
		(fp_line
			(start 0.508 -0.9398)
			(end -0.508 -0.9398)
			(stroke
				(width 0.1524)
				(type default)
			)
			(layer "F.SilkS")
		)
		(fp_line
			(start -0.508 -0.9398)
			(end -0.508 0.9398)
			(stroke
				(width 0.1524)
				(type default)
			)
			(layer "F.SilkS")
		)
		(fp_rect
			(start -0.508 0.9398)
			(end 0.508 -0.9398)
			(stroke
				(width 0)
				(type default)
			)
			(fill no)
			(layer "F.CrtYd")
		)
		(fp_rect
			(start -0.508 0.9398)
			(end 0.508 -0.9398)
			(stroke
				(width 0)
				(type default)
			)
			(fill no)
			(layer "F.Fab")
		)
		(pad "1" smd custom
			(at 0 -0.4445 180)
			(size 0.1397 0.1397)
			(layers "F.Cu" "F.Mask" "F.Paste")
			(net "P5V_B_4_RF")
			(options
				(clearance outline)
				(anchor circle)
			)
			(primitives
				(gr_poly
					(pts
						(arc
							(start -0.1778 -0.2794)
							(mid -0.249642 -0.249642)
							(end -0.2794 -0.1778)
						)
						(arc
							(start -0.2794 0.1778)
							(mid -0.249642 0.249642)
							(end -0.1778 0.2794)
						)
						(arc
							(start 0.1778 0.2794)
							(mid 0.249642 0.249642)
							(end 0.2794 0.1778)
						)
						(arc
							(start 0.2794 -0.1778)
							(mid 0.249642 -0.249642)
							(end 0.1778 -0.2794)
						)
					)
					(width 0)
					(fill yes)
				)
			)
		)
		(pad "2" smd custom
			(at 0 0.4445 180)
			(size 0.1397 0.1397)
			(layers "F.Cu" "F.Mask" "F.Paste")
			(net "AGND_P5V_B_4")
			(options
				(clearance outline)
				(anchor circle)
			)
			(primitives
				(gr_poly
					(pts
						(arc
							(start -0.1778 -0.2794)
							(mid -0.249642 -0.249642)
							(end -0.2794 -0.1778)
						)
						(arc
							(start -0.2794 0.1778)
							(mid -0.249642 0.249642)
							(end -0.1778 0.2794)
						)
						(arc
							(start 0.1778 0.2794)
							(mid 0.249642 0.249642)
							(end 0.2794 0.1778)
						)
						(arc
							(start 0.2794 -0.1778)
							(mid 0.249642 -0.249642)
							(end 0.1778 -0.2794)
						)
					)
					(width 0)
					(fill yes)
				)
			)
		)
	)
	(footprint ""
		(layer "F.Cu")
		(at 46.228 -35.687 -90)
		(property "Reference" "C359"
			(at 0 0 270)
			(layer "F.SilkS")
			(hide yes)
			(effects
				(font
					(size 1.27 1.27)
				)
			)
		)
		(property "Value" "SC4D7U25V5KX-1-GP"
			(at -0.0762 -6.1214 270)
			(unlocked yes)
			(layer "F.Fab")
			(hide yes)
			(effects
				(font
					(size 1.016 1.016)
					(thickness 0.1524)
				)
			)
		)
		(property "Device Type" "C805H58"
			(at -0.0762 -8.1534 270)
			(unlocked yes)
			(layer "F.Fab")
			(hide yes)
			(effects
				(font
					(size 1.016 1.016)
					(thickness 0.1524)
				)
			)
		)
		(duplicate_pad_numbers_are_jumpers no)
		(fp_line
			(start 0.635 0)
			(end -0.635 0)
			(stroke
				(width 0.508)
				(type default)
			)
			(layer "F.SilkS")
		)
		(fp_rect
			(start -0.9652 1.778)
			(end 0.9652 -1.778)
			(stroke
				(width 0)
				(type default)
			)
			(fill no)
			(layer "F.CrtYd")
		)
		(fp_poly
			(pts
				(xy -0.9652 -1.778) (xy 0.9652 -1.778) (xy 0.9652 1.778) (xy -0.9652 1.778)
			)
			(stroke
				(width 0)
				(type default)
			)
			(fill no)
			(layer "F.Fab")
		)
		(pad "1" smd rect
			(at 0 -0.9652 270)
			(size 1.397 1.143)
			(layers "F.Cu" "F.Mask" "F.Paste")
			(net "P12V_HDD25")
		)
		(pad "2" smd rect
			(at 0 0.9652 270)
			(size 1.397 1.143)
			(layers "F.Cu" "F.Mask" "F.Paste")
			(net "GND")
		)
	)
	(footprint ""
		(layer "F.Cu")
		(at 384.734562 -129.66065 -90)
		(property "Reference" "C289"
			(at 0 0 270)
			(layer "F.SilkS")
			(hide yes)
			(effects
				(font
					(size 1.27 1.27)
				)
			)
		)
		(property "Value" "SCD01U16V1KX-GP"
			(at -2.8321 -1.7399 270)
			(unlocked yes)
			(layer "F.Fab")
			(hide yes)
			(effects
				(font
					(size 1.016 1.016)
					(thickness 0.1524)
				)
			)
		)
		(property "Device Type" "C0201H13"
			(at -2.8321 -3.2639 270)
			(unlocked yes)
			(layer "F.Fab")
			(hide yes)
			(effects
				(font
					(size 1.016 1.016)
					(thickness 0.1524)
				)
			)
		)
		(duplicate_pad_numbers_are_jumpers no)
		(fp_rect
			(start -0.2794 0.6477)
			(end 0.2794 -0.6477)
			(stroke
				(width 0)
				(type default)
			)
			(fill no)
			(layer "F.CrtYd")
		)
		(fp_rect
			(start -0.2794 0.6477)
			(end 0.2794 -0.6477)
			(stroke
				(width 0)
				(type default)
			)
			(fill no)
			(layer "F.Fab")
		)
		(pad "1" smd custom
			(at 0 -0.2794 270)
			(size 0.0762 0.0762)
			(layers "F.Cu" "F.Mask" "F.Paste")
			(net "SAS_HDD_RX_P20")
			(options
				(clearance outline)
				(anchor circle)
			)
			(primitives
				(gr_poly
					(pts
						(arc
							(start 0.1524 -0.127)
							(mid 0.137521 -0.162921)
							(end 0.1016 -0.1778)
						)
						(arc
							(start -0.1016 -0.1778)
							(mid -0.137521 -0.162921)
							(end -0.1524 -0.127)
						)
						(arc
							(start -0.1524 0.127)
							(mid -0.137521 0.162921)
							(end -0.1016 0.1778)
						)
						(arc
							(start 0.1016 0.1778)
							(mid 0.137521 0.162921)
							(end 0.1524 0.127)
						)
					)
					(width 0)
					(fill yes)
				)
			)
		)
		(pad "2" smd custom
			(at 0 0.2794 270)
			(size 0.0762 0.0762)
			(layers "F.Cu" "F.Mask" "F.Paste")
			(net "PHY_SCC_B_TO_DRV_B_20_DP")
			(options
				(clearance outline)
				(anchor circle)
			)
			(primitives
				(gr_poly
					(pts
						(arc
							(start 0.1524 -0.127)
							(mid 0.137521 -0.162921)
							(end 0.1016 -0.1778)
						)
						(arc
							(start -0.1016 -0.1778)
							(mid -0.137521 -0.162921)
							(end -0.1524 -0.127)
						)
						(arc
							(start -0.1524 0.127)
							(mid -0.137521 0.162921)
							(end -0.1016 0.1778)
						)
						(arc
							(start 0.1016 0.1778)
							(mid 0.137521 0.162921)
							(end 0.1524 0.127)
						)
					)
					(width 0)
					(fill yes)
				)
			)
		)
	)
	(footprint ""
		(layer "F.Cu")
		(at 439.036714 -119.646446 90)
		(property "Reference" "R1165"
			(at 0 0 90)
			(layer "F.SilkS")
			(hide yes)
			(effects
				(font
					(size 1.27 1.27)
				)
			)
		)
		(property "Value" "100KR2F-L1-GP"
			(at 0.064008 -3.993896 90)
			(unlocked yes)
			(layer "F.Fab")
			(hide yes)
			(effects
				(font
					(size 1.016 1.016)
					(thickness 0.1524)
				)
			)
		)
		(property "Device Type" "R402H16"
			(at 0.064008 -5.517896 90)
			(unlocked yes)
			(layer "F.Fab")
			(hide yes)
			(effects
				(font
					(size 1.016 1.016)
					(thickness 0.1524)
				)
			)
		)
		(duplicate_pad_numbers_are_jumpers no)
		(fp_line
			(start 0.508 -0.9398)
			(end -0.508 -0.9398)
			(stroke
				(width 0.1524)
				(type default)
			)
			(layer "F.SilkS")
		)
		(fp_line
			(start -0.508 -0.9398)
			(end -0.508 0.9398)
			(stroke
				(width 0.1524)
				(type default)
			)
			(layer "F.SilkS")
		)
		(fp_rect
			(start -0.508 0.9398)
			(end 0.508 -0.9398)
			(stroke
				(width 0)
				(type default)
			)
			(fill no)
			(layer "F.CrtYd")
		)
		(fp_rect
			(start -0.508 0.9398)
			(end 0.508 -0.9398)
			(stroke
				(width 0)
				(type default)
			)
			(fill no)
			(layer "F.Fab")
		)
		(pad "1" smd custom
			(at 0 -0.4445 90)
			(size 0.1397 0.1397)
			(layers "F.Cu" "F.Mask" "F.Paste")
			(net "AGND_P5V_B_4")
			(options
				(clearance outline)
				(anchor circle)
			)
			(primitives
				(gr_poly
					(pts
						(arc
							(start -0.1778 -0.2794)
							(mid -0.249642 -0.249642)
							(end -0.2794 -0.1778)
						)
						(arc
							(start -0.2794 0.1778)
							(mid -0.249642 0.249642)
							(end -0.1778 0.2794)
						)
						(arc
							(start 0.1778 0.2794)
							(mid 0.249642 0.249642)
							(end 0.2794 0.1778)
						)
						(arc
							(start 0.2794 -0.1778)
							(mid 0.249642 -0.249642)
							(end 0.1778 -0.2794)
						)
					)
					(width 0)
					(fill yes)
				)
			)
		)
		(pad "2" smd custom
			(at 0 0.4445 90)
			(size 0.1397 0.1397)
			(layers "F.Cu" "F.Mask" "F.Paste")
			(net "P5V_B_4_MODE")
			(options
				(clearance outline)
				(anchor circle)
			)
			(primitives
				(gr_poly
					(pts
						(arc
							(start -0.1778 -0.2794)
							(mid -0.249642 -0.249642)
							(end -0.2794 -0.1778)
						)
						(arc
							(start -0.2794 0.1778)
							(mid -0.249642 0.249642)
							(end -0.1778 0.2794)
						)
						(arc
							(start 0.1778 0.2794)
							(mid 0.249642 0.249642)
							(end 0.2794 0.1778)
						)
						(arc
							(start 0.2794 -0.1778)
							(mid 0.249642 -0.249642)
							(end 0.1778 -0.2794)
						)
					)
					(width 0)
					(fill yes)
				)
			)
		)
	)
	(footprint ""
		(layer "F.Cu")
		(at 37.76853 -361.4928 90)
		(property "Reference" "U2"
			(at 0 0 90)
			(layer "F.SilkS")
			(hide yes)
			(effects
				(font
					(size 1.27 1.27)
				)
			)
		)
		(property "Value" "74LVC1G32DC-1GP"
			(at -2.3368 -8.6868 90)
			(unlocked yes)
			(layer "F.Fab")
			(hide yes)
			(effects
				(font
					(size 1.016 1.016)
					(thickness 0.1524)
				)
			)
		)
		(property "Device Type" "SC70-5H44"
			(at -2.3114 -10.414 90)
			(unlocked yes)
			(layer "F.Fab")
			(hide yes)
			(effects
				(font
					(size 1.016 1.016)
					(thickness 0.1524)
				)
			)
		)
		(duplicate_pad_numbers_are_jumpers no)
		(fp_line
			(start 1.3843 -1.8034)
			(end 1.3843 -1.1176)
			(stroke
				(width 0.3302)
				(type default)
			)
			(layer "F.SilkS")
		)
		(fp_line
			(start 0.6604 -1.8034)
			(end 1.3843 -1.8034)
			(stroke
				(width 0.3302)
				(type default)
			)
			(layer "F.SilkS")
		)
		(fp_line
			(start 1.27 -1.7018)
			(end 1.27 1.7018)
			(stroke
				(width 0.1524)
				(type default)
			)
			(layer "F.SilkS")
		)
		(fp_line
			(start -1.27 -1.7018)
			(end 1.27 -1.7018)
			(stroke
				(width 0.1524)
				(type default)
			)
			(layer "F.SilkS")
		)
		(fp_line
			(start 1.27 1.7018)
			(end -1.27 1.7018)
			(stroke
				(width 0.1524)
				(type default)
			)
			(layer "F.SilkS")
		)
		(fp_line
			(start -1.27 1.7018)
			(end -1.27 -1.7018)
			(stroke
				(width 0.1524)
				(type default)
			)
			(layer "F.SilkS")
		)
		(fp_rect
			(start -1.524 1.9558)
			(end 1.524 -1.9558)
			(stroke
				(width 0)
				(type default)
			)
			(fill no)
			(layer "F.CrtYd")
		)
		(fp_poly
			(pts
				(xy -1.524 -1.9558) (xy 1.524 -1.9558) (xy 1.524 1.9558) (xy -1.524 1.9558)
			)
			(stroke
				(width 0)
				(type default)
			)
			(fill no)
			(layer "F.Fab")
		)
		(pad "1" smd rect
			(at 0.65024 -0.8255 90)
			(size 0.4064 1.2192)
			(layers "F.Cu" "F.Mask" "F.Paste")
			(net "SCC_A_FULL_PWR_EN")
		)
		(pad "2" smd rect
			(at 0 -0.8255 90)
			(size 0.4064 1.2192)
			(layers "F.Cu" "F.Mask" "F.Paste")
			(net "SCC_B_FULL_PWR_EN")
		)
		(pad "3" smd rect
			(at -0.65024 -0.8255 90)
			(size 0.4064 1.2192)
			(layers "F.Cu" "F.Mask" "F.Paste")
			(net "GND")
		)
		(pad "4" smd rect
			(at -0.65024 0.8255 90)
			(size 0.4064 1.2192)
			(layers "F.Cu" "F.Mask" "F.Paste")
			(net "FAN_EN")
		)
		(pad "5" smd rect
			(at 0.65024 0.8255 90)
			(size 0.4064 1.2192)
			(layers "F.Cu" "F.Mask" "F.Paste")
			(net "P3V3_IN")
		)
	)
	(footprint ""
		(layer "F.Cu")
		(at 128.93548 -129.99085 90)
		(property "Reference" "VIA31"
			(at 0 0 90)
			(layer "F.SilkS")
			(hide yes)
			(effects
				(font
					(size 1.27 1.27)
				)
			)
		)
		(property "Value" "100OHM-8L-2D36MM-L18-GP"
			(at 3.8989 0.5715 90)
			(unlocked yes)
			(layer "F.Fab")
			(hide yes)
			(effects
				(font
					(size 1.016 1.016)
					(thickness 0.1524)
				)
			)
		)
		(property "Device Type" "VIA-PCIE-4P-414097"
			(at 3.8989 -0.9525 90)
			(unlocked yes)
			(layer "F.Fab")
			(hide yes)
			(effects
				(font
					(size 1.016 1.016)
					(thickness 0.1524)
				)
			)
		)
		(duplicate_pad_numbers_are_jumpers no)
		(fp_rect
			(start -2.0701 0.4826)
			(end 2.0701 -0.4826)
			(stroke
				(width 0)
				(type default)
			)
			(fill no)
			(layer "F.CrtYd")
		)
		(fp_rect
			(start -2.0701 0.4826)
			(end 2.0701 -0.4826)
			(stroke
				(width 0)
				(type default)
			)
			(fill no)
			(layer "F.Fab")
		)
		(pad "1" thru_hole circle
			(at -1.5875 0 90)
			(size 0.508 0.508)
			(drill 0.254)
			(layers "*.Cu" "*.Mask")
			(remove_unused_layers no)
			(net "GND")
			(clearance 0.2286)
			(thermal_gap 0.2286)
		)
		(pad "2" thru_hole circle
			(at -0.5715 0 90)
			(size 0.508 0.508)
			(drill 0.254)
			(layers "*.Cu" "*.Mask")
			(remove_unused_layers no)
			(net "PHY_SCC_B_TO_DRV_B_15_DP")
			(clearance 0.2286)
			(thermal_gap 0.2286)
		)
		(pad "3" thru_hole circle
			(at 0.5715 0 90)
			(size 0.508 0.508)
			(drill 0.254)
			(layers "*.Cu" "*.Mask")
			(remove_unused_layers no)
			(net "PHY_SCC_B_TO_DRV_B_15_DN")
			(clearance 0.2286)
			(thermal_gap 0.2286)
		)
		(pad "4" thru_hole circle
			(at 1.5875 0 90)
			(size 0.508 0.508)
			(drill 0.254)
			(layers "*.Cu" "*.Mask")
			(remove_unused_layers no)
			(net "GND")
			(clearance 0.2286)
			(thermal_gap 0.2286)
		)
	)
	(footprint ""
		(layer "F.Cu")
		(at 473.964 -35.56 90)
		(property "Reference" "R876"
			(at 0 0 90)
			(layer "F.SilkS")
			(hide yes)
			(effects
				(font
					(size 1.27 1.27)
				)
			)
		)
		(property "Value" "2R6F-GP"
			(at -0.0508 -4.8514 90)
			(unlocked yes)
			(layer "F.Fab")
			(hide yes)
			(effects
				(font
					(size 1.016 1.016)
					(thickness 0.1524)
				)
			)
		)
		(property "Device Type" "R1206H26"
			(at 0 -6.3754 90)
			(unlocked yes)
			(layer "F.Fab")
			(hide yes)
			(effects
				(font
					(size 1.016 1.016)
					(thickness 0.1524)
				)
			)
		)
		(duplicate_pad_numbers_are_jumpers no)
		(fp_line
			(start 1.016 -2.2352)
			(end 1.016 2.2352)
			(stroke
				(width 0.1524)
				(type default)
			)
			(layer "F.SilkS")
		)
		(fp_line
			(start -1.016 -2.2352)
			(end 1.016 -2.2352)
			(stroke
				(width 0.1524)
				(type default)
			)
			(layer "F.SilkS")
		)
		(fp_line
			(start 1.016 2.2352)
			(end -1.016 2.2352)
			(stroke
				(width 0.1524)
				(type default)
			)
			(layer "F.SilkS")
		)
		(fp_line
			(start -1.016 2.2352)
			(end -1.016 -2.2352)
			(stroke
				(width 0.1524)
				(type default)
			)
			(layer "F.SilkS")
		)
		(fp_rect
			(start -1.0922 2.3114)
			(end 1.0922 -2.3114)
			(stroke
				(width 0)
				(type default)
			)
			(fill no)
			(layer "F.CrtYd")
		)
		(fp_poly
			(pts
				(xy -1.0922 -2.3114) (xy 1.0922 -2.3114) (xy 1.0922 2.3114) (xy -1.0922 2.3114)
			)
			(stroke
				(width 0)
				(type default)
			)
			(fill no)
			(layer "F.Fab")
		)
		(pad "1" smd rect
			(at 0 -1.397 90)
			(size 1.651 1.27)
			(layers "F.Cu" "F.Mask" "F.Paste")
			(net "P12V_HDD35")
		)
		(pad "2" smd rect
			(at 0 1.397 90)
			(size 1.651 1.27)
			(layers "F.Cu" "F.Mask" "F.Paste")
			(net "12V_PRE_35")
		)
	)
	(footprint ""
		(layer "F.Cu")
		(at 172.847 -214.249)
		(property "Reference" "R284"
			(at 0 0 0)
			(layer "F.SilkS")
			(hide yes)
			(effects
				(font
					(size 1.27 1.27)
				)
			)
		)
		(property "Value" "130R3F-GP"
			(at -0.0254 -2.5146 0)
			(unlocked yes)
			(layer "F.Fab")
			(hide yes)
			(effects
				(font
					(size 1.016 1.016)
					(thickness 0.1524)
				)
			)
		)
		(property "Device Type" "R603H22"
			(at -0.0254 -4.0386 0)
			(unlocked yes)
			(layer "F.Fab")
			(hide yes)
			(effects
				(font
					(size 1.016 1.016)
					(thickness 0.1524)
				)
			)
		)
		(duplicate_pad_numbers_are_jumpers no)
		(fp_line
			(start -0.4826 0)
			(end -0.2032 0)
			(stroke
				(width 0.2032)
				(type default)
			)
			(layer "F.SilkS")
		)
		(fp_line
			(start 0.2032 0)
			(end 0.4826 0)
			(stroke
				(width 0.2032)
				(type default)
			)
			(layer "F.SilkS")
		)
		(fp_rect
			(start -0.5842 1.3335)
			(end 0.5842 -1.3335)
			(stroke
				(width 0)
				(type default)
			)
			(fill no)
			(layer "F.CrtYd")
		)
		(fp_rect
			(start -0.5842 1.3335)
			(end 0.5842 -1.3335)
			(stroke
				(width 0)
				(type default)
			)
			(fill no)
			(layer "F.Fab")
		)
		(pad "1" smd custom
			(at 0 -0.762)
			(size 0.2159 0.2159)
			(layers "F.Cu" "F.Mask" "F.Paste")
			(net "P5V_B_1")
			(options
				(clearance outline)
				(anchor circle)
			)
			(primitives
				(gr_poly
					(pts
						(arc
							(start -0.3302 -0.4318)
							(mid -0.402042 -0.402042)
							(end -0.4318 -0.3302)
						)
						(arc
							(start -0.4318 0.3302)
							(mid -0.402042 0.402042)
							(end -0.3302 0.4318)
						)
						(arc
							(start 0.3302 0.4318)
							(mid 0.402042 0.402042)
							(end 0.4318 0.3302)
						)
						(arc
							(start 0.4318 -0.3302)
							(mid 0.402042 -0.402042)
							(end 0.3302 -0.4318)
						)
					)
					(width 0)
					(fill yes)
				)
			)
		)
		(pad "2" smd custom
			(at 0 0.762)
			(size 0.2159 0.2159)
			(layers "F.Cu" "F.Mask" "F.Paste")
			(net "FLT_HDD5")
			(options
				(clearance outline)
				(anchor circle)
			)
			(primitives
				(gr_poly
					(pts
						(arc
							(start -0.3302 -0.4318)
							(mid -0.402042 -0.402042)
							(end -0.4318 -0.3302)
						)
						(arc
							(start -0.4318 0.3302)
							(mid -0.402042 0.402042)
							(end -0.3302 0.4318)
						)
						(arc
							(start 0.3302 0.4318)
							(mid 0.402042 0.402042)
							(end 0.4318 0.3302)
						)
						(arc
							(start 0.4318 -0.3302)
							(mid 0.402042 -0.402042)
							(end 0.3302 -0.4318)
						)
					)
					(width 0)
					(fill yes)
				)
			)
		)
	)
	(footprint ""
		(layer "F.Cu")
		(at 251.064522 -358.622346)
		(property "Reference" "R1044"
			(at 0 0 0)
			(layer "F.SilkS")
			(hide yes)
			(effects
				(font
					(size 1.27 1.27)
				)
			)
		)
		(property "Value" "75KR2F-GP"
			(at 0.064008 -3.993896 0)
			(unlocked yes)
			(layer "F.Fab")
			(hide yes)
			(effects
				(font
					(size 1.016 1.016)
					(thickness 0.1524)
				)
			)
		)
		(property "Device Type" "R402H16"
			(at 0.064008 -5.517896 0)
			(unlocked yes)
			(layer "F.Fab")
			(hide yes)
			(effects
				(font
					(size 1.016 1.016)
					(thickness 0.1524)
				)
			)
		)
		(duplicate_pad_numbers_are_jumpers no)
		(fp_line
			(start -0.508 -0.9398)
			(end -0.508 0.9398)
			(stroke
				(width 0.1524)
				(type default)
			)
			(layer "F.SilkS")
		)
		(fp_line
			(start 0.508 -0.9398)
			(end -0.508 -0.9398)
			(stroke
				(width 0.1524)
				(type default)
			)
			(layer "F.SilkS")
		)
		(fp_rect
			(start -0.508 0.9398)
			(end 0.508 -0.9398)
			(stroke
				(width 0)
				(type default)
			)
			(fill no)
			(layer "F.CrtYd")
		)
		(fp_rect
			(start -0.508 0.9398)
			(end 0.508 -0.9398)
			(stroke
				(width 0)
				(type default)
			)
			(fill no)
			(layer "F.Fab")
		)
		(pad "1" smd custom
			(at 0 -0.4445)
			(size 0.1397 0.1397)
			(layers "F.Cu" "F.Mask" "F.Paste")
			(net "MB3_ISET_R")
			(options
				(clearance outline)
				(anchor circle)
			)
			(primitives
				(gr_poly
					(pts
						(arc
							(start -0.1778 -0.2794)
							(mid -0.249642 -0.249642)
							(end -0.2794 -0.1778)
						)
						(arc
							(start -0.2794 0.1778)
							(mid -0.249642 0.249642)
							(end -0.1778 0.2794)
						)
						(arc
							(start 0.1778 0.2794)
							(mid 0.249642 0.249642)
							(end 0.2794 0.1778)
						)
						(arc
							(start 0.2794 -0.1778)
							(mid 0.249642 -0.249642)
							(end 0.1778 -0.2794)
						)
					)
					(width 0)
					(fill yes)
				)
			)
		)
		(pad "2" smd custom
			(at 0 0.4445)
			(size 0.1397 0.1397)
			(layers "F.Cu" "F.Mask" "F.Paste")
			(net "AGND_CURRENT_DPB")
			(options
				(clearance outline)
				(anchor circle)
			)
			(primitives
				(gr_poly
					(pts
						(arc
							(start -0.1778 -0.2794)
							(mid -0.249642 -0.249642)
							(end -0.2794 -0.1778)
						)
						(arc
							(start -0.2794 0.1778)
							(mid -0.249642 0.249642)
							(end -0.1778 0.2794)
						)
						(arc
							(start 0.1778 0.2794)
							(mid 0.249642 0.249642)
							(end 0.2794 0.1778)
						)
						(arc
							(start 0.2794 -0.1778)
							(mid 0.249642 -0.249642)
							(end 0.1778 -0.2794)
						)
					)
					(width 0)
					(fill yes)
				)
			)
		)
	)
	(footprint ""
		(layer "F.Cu")
		(at 329.278996 -369.697 180)
		(property "Reference" "R942"
			(at 0 0 180)
			(layer "F.SilkS")
			(hide yes)
			(effects
				(font
					(size 1.27 1.27)
				)
			)
		)
		(property "Value" "4K7R2F-GP"
			(at 0.064008 -3.993896 180)
			(unlocked yes)
			(layer "F.Fab")
			(hide yes)
			(effects
				(font
					(size 1.016 1.016)
					(thickness 0.1524)
				)
			)
		)
		(property "Device Type" "R402H16"
			(at 0.064008 -5.517896 180)
			(unlocked yes)
			(layer "F.Fab")
			(hide yes)
			(effects
				(font
					(size 1.016 1.016)
					(thickness 0.1524)
				)
			)
		)
		(duplicate_pad_numbers_are_jumpers no)
		(fp_line
			(start 0.508 -0.9398)
			(end -0.508 -0.9398)
			(stroke
				(width 0.1524)
				(type default)
			)
			(layer "F.SilkS")
		)
		(fp_line
			(start -0.508 -0.9398)
			(end -0.508 0.9398)
			(stroke
				(width 0.1524)
				(type default)
			)
			(layer "F.SilkS")
		)
		(fp_rect
			(start -0.508 0.9398)
			(end 0.508 -0.9398)
			(stroke
				(width 0)
				(type default)
			)
			(fill no)
			(layer "F.CrtYd")
		)
		(fp_rect
			(start -0.508 0.9398)
			(end 0.508 -0.9398)
			(stroke
				(width 0)
				(type default)
			)
			(fill no)
			(layer "F.Fab")
		)
		(pad "1" smd custom
			(at 0 -0.4445 180)
			(size 0.1397 0.1397)
			(layers "F.Cu" "F.Mask" "F.Paste")
			(net "P12V_IN")
			(options
				(clearance outline)
				(anchor circle)
			)
			(primitives
				(gr_poly
					(pts
						(arc
							(start -0.1778 -0.2794)
							(mid -0.249642 -0.249642)
							(end -0.2794 -0.1778)
						)
						(arc
							(start -0.2794 0.1778)
							(mid -0.249642 0.249642)
							(end -0.1778 0.2794)
						)
						(arc
							(start 0.1778 0.2794)
							(mid 0.249642 0.249642)
							(end 0.2794 0.1778)
						)
						(arc
							(start 0.2794 -0.1778)
							(mid 0.249642 -0.249642)
							(end 0.1778 -0.2794)
						)
					)
					(width 0)
					(fill yes)
				)
			)
		)
		(pad "2" smd custom
			(at 0 0.4445 180)
			(size 0.1397 0.1397)
			(layers "F.Cu" "F.Mask" "F.Paste")
			(net "FAN_2_TACH0")
			(options
				(clearance outline)
				(anchor circle)
			)
			(primitives
				(gr_poly
					(pts
						(arc
							(start -0.1778 -0.2794)
							(mid -0.249642 -0.249642)
							(end -0.2794 -0.1778)
						)
						(arc
							(start -0.2794 0.1778)
							(mid -0.249642 0.249642)
							(end -0.1778 0.2794)
						)
						(arc
							(start 0.1778 0.2794)
							(mid 0.249642 0.249642)
							(end 0.2794 0.1778)
						)
						(arc
							(start 0.2794 -0.1778)
							(mid 0.249642 -0.249642)
							(end 0.1778 -0.2794)
						)
					)
					(width 0)
					(fill yes)
				)
			)
		)
	)
	(footprint ""
		(layer "F.Cu")
		(at 460.060802 -230.63835 -90)
		(property "Reference" "R1138"
			(at 0 0 270)
			(layer "F.SilkS")
			(hide yes)
			(effects
				(font
					(size 1.27 1.27)
				)
			)
		)
		(property "Value" "10KR2F-2-GP"
			(at 0.064008 -3.993896 270)
			(unlocked yes)
			(layer "F.Fab")
			(hide yes)
			(effects
				(font
					(size 1.016 1.016)
					(thickness 0.1524)
				)
			)
		)
		(property "Device Type" "R402H16"
			(at 0.064008 -5.517896 270)
			(unlocked yes)
			(layer "F.Fab")
			(hide yes)
			(effects
				(font
					(size 1.016 1.016)
					(thickness 0.1524)
				)
			)
		)
		(duplicate_pad_numbers_are_jumpers no)
		(fp_line
			(start -0.508 -0.9398)
			(end -0.508 0.9398)
			(stroke
				(width 0.1524)
				(type default)
			)
			(layer "F.SilkS")
		)
		(fp_line
			(start 0.508 -0.9398)
			(end -0.508 -0.9398)
			(stroke
				(width 0.1524)
				(type default)
			)
			(layer "F.SilkS")
		)
		(fp_rect
			(start -0.508 0.9398)
			(end 0.508 -0.9398)
			(stroke
				(width 0)
				(type default)
			)
			(fill no)
			(layer "F.CrtYd")
		)
		(fp_rect
			(start -0.508 0.9398)
			(end 0.508 -0.9398)
			(stroke
				(width 0)
				(type default)
			)
			(fill no)
			(layer "F.Fab")
		)
		(pad "1" smd custom
			(at 0 -0.4445 270)
			(size 0.1397 0.1397)
			(layers "F.Cu" "F.Mask" "F.Paste")
			(net "P5V_B_3_EN_R")
			(options
				(clearance outline)
				(anchor circle)
			)
			(primitives
				(gr_poly
					(pts
						(arc
							(start -0.1778 -0.2794)
							(mid -0.249642 -0.249642)
							(end -0.2794 -0.1778)
						)
						(arc
							(start -0.2794 0.1778)
							(mid -0.249642 0.249642)
							(end -0.1778 0.2794)
						)
						(arc
							(start 0.1778 0.2794)
							(mid 0.249642 0.249642)
							(end 0.2794 0.1778)
						)
						(arc
							(start 0.2794 -0.1778)
							(mid 0.249642 -0.249642)
							(end 0.1778 -0.2794)
						)
					)
					(width 0)
					(fill yes)
				)
			)
		)
		(pad "2" smd custom
			(at 0 0.4445 270)
			(size 0.1397 0.1397)
			(layers "F.Cu" "F.Mask" "F.Paste")
			(net "GND")
			(options
				(clearance outline)
				(anchor circle)
			)
			(primitives
				(gr_poly
					(pts
						(arc
							(start -0.1778 -0.2794)
							(mid -0.249642 -0.249642)
							(end -0.2794 -0.1778)
						)
						(arc
							(start -0.2794 0.1778)
							(mid -0.249642 0.249642)
							(end -0.1778 0.2794)
						)
						(arc
							(start 0.1778 0.2794)
							(mid 0.249642 0.249642)
							(end 0.2794 0.1778)
						)
						(arc
							(start 0.2794 -0.1778)
							(mid 0.249642 -0.249642)
							(end 0.1778 -0.2794)
						)
					)
					(width 0)
					(fill yes)
				)
			)
		)
	)
	(footprint ""
		(layer "F.Cu")
		(at 361.315 -267.843 180)
		(property "Reference" "C121"
			(at 0 0 180)
			(layer "F.SilkS")
			(hide yes)
			(effects
				(font
					(size 1.27 1.27)
				)
			)
		)
		(property "Value" "SC1U16V3KX-5GP"
			(at 0 -2.8194 180)
			(unlocked yes)
			(layer "F.Fab")
			(hide yes)
			(effects
				(font
					(size 1.016 1.016)
					(thickness 0.1524)
				)
			)
		)
		(property "Device Type" "C603H36"
			(at 0 -4.3434 180)
			(unlocked yes)
			(layer "F.Fab")
			(hide yes)
			(effects
				(font
					(size 1.016 1.016)
					(thickness 0.1524)
				)
			)
		)
		(duplicate_pad_numbers_are_jumpers no)
		(fp_line
			(start 0.508 0)
			(end -0.508 0)
			(stroke
				(width 0.2032)
				(type default)
			)
			(layer "F.SilkS")
		)
		(fp_rect
			(start -0.5842 1.3335)
			(end 0.5842 -1.3335)
			(stroke
				(width 0)
				(type default)
			)
			(fill no)
			(layer "F.CrtYd")
		)
		(fp_rect
			(start -0.5842 1.3335)
			(end 0.5842 -1.3335)
			(stroke
				(width 0)
				(type default)
			)
			(fill no)
			(layer "F.Fab")
		)
		(pad "1" smd custom
			(at 0 -0.762 180)
			(size 0.2159 0.2159)
			(layers "F.Cu" "F.Mask" "F.Paste")
			(net "P5V_HDD7")
			(options
				(clearance outline)
				(anchor circle)
			)
			(primitives
				(gr_poly
					(pts
						(arc
							(start -0.3302 -0.4318)
							(mid -0.402042 -0.402042)
							(end -0.4318 -0.3302)
						)
						(arc
							(start -0.4318 0.3302)
							(mid -0.402042 0.402042)
							(end -0.3302 0.4318)
						)
						(arc
							(start 0.3302 0.4318)
							(mid 0.402042 0.402042)
							(end 0.4318 0.3302)
						)
						(arc
							(start 0.4318 -0.3302)
							(mid 0.402042 -0.402042)
							(end 0.3302 -0.4318)
						)
					)
					(width 0)
					(fill yes)
				)
			)
		)
		(pad "2" smd custom
			(at 0 0.762 180)
			(size 0.2159 0.2159)
			(layers "F.Cu" "F.Mask" "F.Paste")
			(net "GND")
			(options
				(clearance outline)
				(anchor circle)
			)
			(primitives
				(gr_poly
					(pts
						(arc
							(start -0.3302 -0.4318)
							(mid -0.402042 -0.402042)
							(end -0.4318 -0.3302)
						)
						(arc
							(start -0.4318 0.3302)
							(mid -0.402042 0.402042)
							(end -0.3302 0.4318)
						)
						(arc
							(start 0.3302 0.4318)
							(mid 0.402042 0.402042)
							(end 0.4318 0.3302)
						)
						(arc
							(start 0.4318 -0.3302)
							(mid 0.402042 -0.402042)
							(end 0.3302 -0.4318)
						)
					)
					(width 0)
					(fill yes)
				)
			)
		)
	)
	(footprint ""
		(layer "F.Cu")
		(at 219.142564 -107.414568)
		(property "Reference" "R142"
			(at 0 0 0)
			(layer "F.SilkS")
			(hide yes)
			(effects
				(font
					(size 1.27 1.27)
				)
			)
		)
		(property "Value" "1KR2F-3-GP"
			(at 0.064008 -3.993896 0)
			(unlocked yes)
			(layer "F.Fab")
			(hide yes)
			(effects
				(font
					(size 1.016 1.016)
					(thickness 0.1524)
				)
			)
		)
		(property "Device Type" "R402H16"
			(at 0.064008 -5.517896 0)
			(unlocked yes)
			(layer "F.Fab")
			(hide yes)
			(effects
				(font
					(size 1.016 1.016)
					(thickness 0.1524)
				)
			)
		)
		(duplicate_pad_numbers_are_jumpers no)
		(fp_line
			(start -0.508 -0.9398)
			(end -0.508 0.9398)
			(stroke
				(width 0.1524)
				(type default)
			)
			(layer "F.SilkS")
		)
		(fp_line
			(start 0.508 -0.9398)
			(end -0.508 -0.9398)
			(stroke
				(width 0.1524)
				(type default)
			)
			(layer "F.SilkS")
		)
		(fp_rect
			(start -0.508 0.9398)
			(end 0.508 -0.9398)
			(stroke
				(width 0)
				(type default)
			)
			(fill no)
			(layer "F.CrtYd")
		)
		(fp_rect
			(start -0.508 0.9398)
			(end 0.508 -0.9398)
			(stroke
				(width 0)
				(type default)
			)
			(fill no)
			(layer "F.Fab")
		)
		(pad "1" smd custom
			(at 0 -0.4445)
			(size 0.1397 0.1397)
			(layers "F.Cu" "F.Mask" "F.Paste")
			(net "P3V3_STBY_B")
			(options
				(clearance outline)
				(anchor circle)
			)
			(primitives
				(gr_poly
					(pts
						(arc
							(start -0.1778 -0.2794)
							(mid -0.249642 -0.249642)
							(end -0.2794 -0.1778)
						)
						(arc
							(start -0.2794 0.1778)
							(mid -0.249642 0.249642)
							(end -0.1778 0.2794)
						)
						(arc
							(start 0.1778 0.2794)
							(mid 0.249642 0.249642)
							(end 0.2794 0.1778)
						)
						(arc
							(start 0.2794 -0.1778)
							(mid 0.249642 -0.249642)
							(end 0.1778 -0.2794)
						)
					)
					(width 0)
					(fill yes)
				)
			)
		)
		(pad "2" smd custom
			(at 0 0.4445)
			(size 0.1397 0.1397)
			(layers "F.Cu" "F.Mask" "F.Paste")
			(net "I2C_BMC_B_EXP_B_SDA")
			(options
				(clearance outline)
				(anchor circle)
			)
			(primitives
				(gr_poly
					(pts
						(arc
							(start -0.1778 -0.2794)
							(mid -0.249642 -0.249642)
							(end -0.2794 -0.1778)
						)
						(arc
							(start -0.2794 0.1778)
							(mid -0.249642 0.249642)
							(end -0.1778 0.2794)
						)
						(arc
							(start 0.1778 0.2794)
							(mid 0.249642 0.249642)
							(end 0.2794 0.1778)
						)
						(arc
							(start 0.2794 -0.1778)
							(mid 0.249642 -0.249642)
							(end 0.1778 -0.2794)
						)
					)
					(width 0)
					(fill yes)
				)
			)
		)
	)
	(footprint ""
		(layer "F.Cu")
		(at 182.118 -19.177)
		(property "Reference" "R748"
			(at 0 0 0)
			(layer "F.SilkS")
			(hide yes)
			(effects
				(font
					(size 1.27 1.27)
				)
			)
		)
		(property "Value" "0R2J-2-GP"
			(at 0.064008 -3.993896 0)
			(unlocked yes)
			(layer "F.Fab")
			(hide yes)
			(effects
				(font
					(size 1.016 1.016)
					(thickness 0.1524)
				)
			)
		)
		(property "Device Type" "R402H16"
			(at 0.064008 -5.517896 0)
			(unlocked yes)
			(layer "F.Fab")
			(hide yes)
			(effects
				(font
					(size 1.016 1.016)
					(thickness 0.1524)
				)
			)
		)
		(duplicate_pad_numbers_are_jumpers no)
		(fp_line
			(start -0.508 -0.9398)
			(end -0.508 0.9398)
			(stroke
				(width 0.1524)
				(type default)
			)
			(layer "F.SilkS")
		)
		(fp_line
			(start 0.508 -0.9398)
			(end -0.508 -0.9398)
			(stroke
				(width 0.1524)
				(type default)
			)
			(layer "F.SilkS")
		)
		(fp_rect
			(start -0.508 0.9398)
			(end 0.508 -0.9398)
			(stroke
				(width 0)
				(type default)
			)
			(fill no)
			(layer "F.CrtYd")
		)
		(fp_rect
			(start -0.508 0.9398)
			(end 0.508 -0.9398)
			(stroke
				(width 0)
				(type default)
			)
			(fill no)
			(layer "F.Fab")
		)
		(pad "1" smd custom
			(at 0 -0.4445)
			(size 0.1397 0.1397)
			(layers "F.Cu" "F.Mask" "F.Paste")
			(net "DRIVE_B_29_PWR")
			(options
				(clearance outline)
				(anchor circle)
			)
			(primitives
				(gr_poly
					(pts
						(arc
							(start -0.1778 -0.2794)
							(mid -0.249642 -0.249642)
							(end -0.2794 -0.1778)
						)
						(arc
							(start -0.2794 0.1778)
							(mid -0.249642 0.249642)
							(end -0.1778 0.2794)
						)
						(arc
							(start 0.1778 0.2794)
							(mid 0.249642 0.249642)
							(end 0.2794 0.1778)
						)
						(arc
							(start 0.2794 -0.1778)
							(mid 0.249642 -0.249642)
							(end 0.1778 -0.2794)
						)
					)
					(width 0)
					(fill yes)
				)
			)
		)
		(pad "2" smd custom
			(at 0 0.4445)
			(size 0.1397 0.1397)
			(layers "F.Cu" "F.Mask" "F.Paste")
			(net "SW_PWR_R_HDD29")
			(options
				(clearance outline)
				(anchor circle)
			)
			(primitives
				(gr_poly
					(pts
						(arc
							(start -0.1778 -0.2794)
							(mid -0.249642 -0.249642)
							(end -0.2794 -0.1778)
						)
						(arc
							(start -0.2794 0.1778)
							(mid -0.249642 0.249642)
							(end -0.1778 0.2794)
						)
						(arc
							(start 0.1778 0.2794)
							(mid 0.249642 0.249642)
							(end 0.2794 0.1778)
						)
						(arc
							(start 0.2794 -0.1778)
							(mid 0.249642 -0.249642)
							(end 0.1778 -0.2794)
						)
					)
					(width 0)
					(fill yes)
				)
			)
		)
	)
	(footprint ""
		(layer "F.Cu")
		(at 64.0588 -18.750026 -90)
		(property "Reference" "VIA52"
			(at 0 0 270)
			(layer "F.SilkS")
			(hide yes)
			(effects
				(font
					(size 1.27 1.27)
				)
			)
		)
		(property "Value" "100OHM-8L-2D36MM-L16-GP"
			(at -3.4036 -0.4572 270)
			(unlocked yes)
			(layer "F.Fab")
			(hide yes)
			(effects
				(font
					(size 1.016 1.016)
					(thickness 0.1524)
				)
			)
		)
		(property "Device Type" "VIA-PCIE-4P-427097"
			(at -3.4036 -1.9812 270)
			(unlocked yes)
			(layer "F.Fab")
			(hide yes)
			(effects
				(font
					(size 1.016 1.016)
					(thickness 0.1524)
				)
			)
		)
		(duplicate_pad_numbers_are_jumpers no)
		(fp_rect
			(start -2.1336 0.4826)
			(end 2.1336 -0.4826)
			(stroke
				(width 0)
				(type default)
			)
			(fill no)
			(layer "F.CrtYd")
		)
		(fp_rect
			(start -2.1336 0.4826)
			(end 2.1336 -0.4826)
			(stroke
				(width 0)
				(type default)
			)
			(fill no)
			(layer "F.Fab")
		)
		(pad "1" thru_hole circle
			(at -1.651 0 270)
			(size 0.508 0.508)
			(drill 0.254)
			(layers "*.Cu" "*.Mask")
			(remove_unused_layers no)
			(net "GND")
			(clearance 0.2286)
			(thermal_gap 0.2286)
		)
		(pad "2" thru_hole circle
			(at -0.635 0 270)
			(size 0.508 0.508)
			(drill 0.254)
			(layers "*.Cu" "*.Mask")
			(remove_unused_layers no)
			(net "PHY_DRV_B_TO_SCC_B_25_DP")
			(clearance 0.2286)
			(thermal_gap 0.2286)
		)
		(pad "3" thru_hole circle
			(at 0.635 0 270)
			(size 0.508 0.508)
			(drill 0.254)
			(layers "*.Cu" "*.Mask")
			(remove_unused_layers no)
			(net "PHY_DRV_B_TO_SCC_B_25_DN")
			(clearance 0.2286)
			(thermal_gap 0.2286)
		)
		(pad "4" thru_hole circle
			(at 1.651 0 270)
			(size 0.508 0.508)
			(drill 0.254)
			(layers "*.Cu" "*.Mask")
			(remove_unused_layers no)
			(net "GND")
			(clearance 0.2286)
			(thermal_gap 0.2286)
		)
	)
	(footprint ""
		(layer "F.Cu")
		(at 231.07904 -233.01198)
		(property "Reference" "R65"
			(at 0 0 0)
			(layer "F.SilkS")
			(hide yes)
			(effects
				(font
					(size 1.27 1.27)
				)
			)
		)
		(property "Value" "4K7R2F-GP"
			(at 0.064008 -3.993896 0)
			(unlocked yes)
			(layer "F.Fab")
			(hide yes)
			(effects
				(font
					(size 1.016 1.016)
					(thickness 0.1524)
				)
			)
		)
		(property "Device Type" "R402H16"
			(at 0.064008 -5.517896 0)
			(unlocked yes)
			(layer "F.Fab")
			(hide yes)
			(effects
				(font
					(size 1.016 1.016)
					(thickness 0.1524)
				)
			)
		)
		(duplicate_pad_numbers_are_jumpers no)
		(fp_line
			(start -0.508 -0.9398)
			(end -0.508 0.9398)
			(stroke
				(width 0.1524)
				(type default)
			)
			(layer "F.SilkS")
		)
		(fp_line
			(start 0.508 -0.9398)
			(end -0.508 -0.9398)
			(stroke
				(width 0.1524)
				(type default)
			)
			(layer "F.SilkS")
		)
		(fp_rect
			(start -0.508 0.9398)
			(end 0.508 -0.9398)
			(stroke
				(width 0)
				(type default)
			)
			(fill no)
			(layer "F.CrtYd")
		)
		(fp_rect
			(start -0.508 0.9398)
			(end 0.508 -0.9398)
			(stroke
				(width 0)
				(type default)
			)
			(fill no)
			(layer "F.Fab")
		)
		(pad "1" smd custom
			(at 0 -0.4445)
			(size 0.1397 0.1397)
			(layers "F.Cu" "F.Mask" "F.Paste")
			(net "P3V3_STBY_B")
			(options
				(clearance outline)
				(anchor circle)
			)
			(primitives
				(gr_poly
					(pts
						(arc
							(start -0.1778 -0.2794)
							(mid -0.249642 -0.249642)
							(end -0.2794 -0.1778)
						)
						(arc
							(start -0.2794 0.1778)
							(mid -0.249642 0.249642)
							(end -0.1778 0.2794)
						)
						(arc
							(start 0.1778 0.2794)
							(mid 0.249642 0.249642)
							(end 0.2794 0.1778)
						)
						(arc
							(start 0.2794 -0.1778)
							(mid 0.249642 -0.249642)
							(end 0.1778 -0.2794)
						)
					)
					(width 0)
					(fill yes)
				)
			)
		)
		(pad "2" smd custom
			(at 0 0.4445)
			(size 0.1397 0.1397)
			(layers "F.Cu" "F.Mask" "F.Paste")
			(net "IO_EXP1_A2")
			(options
				(clearance outline)
				(anchor circle)
			)
			(primitives
				(gr_poly
					(pts
						(arc
							(start -0.1778 -0.2794)
							(mid -0.249642 -0.249642)
							(end -0.2794 -0.1778)
						)
						(arc
							(start -0.2794 0.1778)
							(mid -0.249642 0.249642)
							(end -0.1778 0.2794)
						)
						(arc
							(start 0.1778 0.2794)
							(mid 0.249642 0.249642)
							(end 0.2794 0.1778)
						)
						(arc
							(start 0.2794 -0.1778)
							(mid 0.249642 -0.249642)
							(end 0.1778 -0.2794)
						)
					)
					(width 0)
					(fill yes)
				)
			)
		)
	)
	(footprint ""
		(layer "F.Cu")
		(at 315.3664 -340.812882)
		(property "Reference" "R120"
			(at 0 0 0)
			(layer "F.SilkS")
			(hide yes)
			(effects
				(font
					(size 1.27 1.27)
				)
			)
		)
		(property "Value" "4K7R2F-GP"
			(at 0.064008 -3.993896 0)
			(unlocked yes)
			(layer "F.Fab")
			(hide yes)
			(effects
				(font
					(size 1.016 1.016)
					(thickness 0.1524)
				)
			)
		)
		(property "Device Type" "R402H16"
			(at 0.064008 -5.517896 0)
			(unlocked yes)
			(layer "F.Fab")
			(hide yes)
			(effects
				(font
					(size 1.016 1.016)
					(thickness 0.1524)
				)
			)
		)
		(duplicate_pad_numbers_are_jumpers no)
		(fp_line
			(start -0.508 -0.9398)
			(end -0.508 0.9398)
			(stroke
				(width 0.1524)
				(type default)
			)
			(layer "F.SilkS")
		)
		(fp_line
			(start 0.508 -0.9398)
			(end -0.508 -0.9398)
			(stroke
				(width 0.1524)
				(type default)
			)
			(layer "F.SilkS")
		)
		(fp_rect
			(start -0.508 0.9398)
			(end 0.508 -0.9398)
			(stroke
				(width 0)
				(type default)
			)
			(fill no)
			(layer "F.CrtYd")
		)
		(fp_rect
			(start -0.508 0.9398)
			(end 0.508 -0.9398)
			(stroke
				(width 0)
				(type default)
			)
			(fill no)
			(layer "F.Fab")
		)
		(pad "1" smd custom
			(at 0 -0.4445)
			(size 0.1397 0.1397)
			(layers "F.Cu" "F.Mask" "F.Paste")
			(net "P3V3_IN")
			(options
				(clearance outline)
				(anchor circle)
			)
			(primitives
				(gr_poly
					(pts
						(arc
							(start -0.1778 -0.2794)
							(mid -0.249642 -0.249642)
							(end -0.2794 -0.1778)
						)
						(arc
							(start -0.2794 0.1778)
							(mid -0.249642 0.249642)
							(end -0.1778 0.2794)
						)
						(arc
							(start 0.1778 0.2794)
							(mid 0.249642 0.249642)
							(end 0.2794 0.1778)
						)
						(arc
							(start 0.2794 -0.1778)
							(mid 0.249642 -0.249642)
							(end 0.1778 -0.2794)
						)
					)
					(width 0)
					(fill yes)
				)
			)
		)
		(pad "2" smd custom
			(at 0 0.4445)
			(size 0.1397 0.1397)
			(layers "F.Cu" "F.Mask" "F.Paste")
			(net "PWM_CAMP_SEL2")
			(options
				(clearance outline)
				(anchor circle)
			)
			(primitives
				(gr_poly
					(pts
						(arc
							(start -0.1778 -0.2794)
							(mid -0.249642 -0.249642)
							(end -0.2794 -0.1778)
						)
						(arc
							(start -0.2794 0.1778)
							(mid -0.249642 0.249642)
							(end -0.1778 0.2794)
						)
						(arc
							(start 0.1778 0.2794)
							(mid 0.249642 0.249642)
							(end 0.2794 0.1778)
						)
						(arc
							(start 0.2794 -0.1778)
							(mid 0.249642 -0.249642)
							(end 0.1778 -0.2794)
						)
					)
					(width 0)
					(fill yes)
				)
			)
		)
	)
	(footprint ""
		(layer "F.Cu")
		(at 321.7164 -31.6484)
		(property "Reference" "C427"
			(at 0 0 0)
			(layer "F.SilkS")
			(hide yes)
			(effects
				(font
					(size 1.27 1.27)
				)
			)
		)
		(property "Value" "SCD01U50V2KX-1GP"
			(at 1.1811 -2.7051 0)
			(unlocked yes)
			(layer "F.Fab")
			(hide yes)
			(effects
				(font
					(size 1.016 1.016)
					(thickness 0.1524)
				)
			)
		)
		(property "Device Type" "C402H22"
			(at 1.1811 -4.2291 0)
			(unlocked yes)
			(layer "F.Fab")
			(hide yes)
			(effects
				(font
					(size 1.016 1.016)
					(thickness 0.1524)
				)
			)
		)
		(duplicate_pad_numbers_are_jumpers no)
		(fp_rect
			(start -0.4318 0.9525)
			(end 0.4318 -0.9525)
			(stroke
				(width 0)
				(type default)
			)
			(fill no)
			(layer "F.CrtYd")
		)
		(fp_rect
			(start -0.4318 0.9525)
			(end 0.4318 -0.9525)
			(stroke
				(width 0)
				(type default)
			)
			(fill no)
			(layer "F.Fab")
		)
		(pad "1" smd custom
			(at 0 -0.4445)
			(size 0.1524 0.1524)
			(layers "F.Cu" "F.Mask" "F.Paste")
			(net "HDD_PRSNT_30")
			(options
				(clearance outline)
				(anchor circle)
			)
			(primitives
				(gr_poly
					(pts
						(arc
							(start 0.3048 -0.2032)
							(mid 0.275042 -0.275042)
							(end 0.2032 -0.3048)
						)
						(arc
							(start -0.2032 -0.3048)
							(mid -0.275042 -0.275042)
							(end -0.3048 -0.2032)
						)
						(arc
							(start -0.3048 0.2032)
							(mid -0.275042 0.275042)
							(end -0.2032 0.3048)
						)
						(arc
							(start 0.2032 0.3048)
							(mid 0.275042 0.275042)
							(end 0.3048 0.2032)
						)
					)
					(width 0)
					(fill yes)
				)
			)
		)
		(pad "2" smd custom
			(at 0 0.4445)
			(size 0.1524 0.1524)
			(layers "F.Cu" "F.Mask" "F.Paste")
			(net "GND")
			(options
				(clearance outline)
				(anchor circle)
			)
			(primitives
				(gr_poly
					(pts
						(arc
							(start 0.3048 -0.2032)
							(mid 0.275042 -0.275042)
							(end 0.2032 -0.3048)
						)
						(arc
							(start -0.2032 -0.3048)
							(mid -0.275042 -0.275042)
							(end -0.3048 -0.2032)
						)
						(arc
							(start -0.3048 0.2032)
							(mid -0.275042 0.275042)
							(end -0.2032 0.3048)
						)
						(arc
							(start 0.2032 0.3048)
							(mid 0.275042 0.275042)
							(end 0.3048 0.2032)
						)
					)
					(width 0)
					(fill yes)
				)
			)
		)
	)
	(footprint ""
		(layer "F.Cu")
		(at 78.359 -248.158 180)
		(property "Reference" "R202"
			(at 0 0 180)
			(layer "F.SilkS")
			(hide yes)
			(effects
				(font
					(size 1.27 1.27)
				)
			)
		)
		(property "Value" "200KR2F-L-GP"
			(at 0.064008 -3.993896 180)
			(unlocked yes)
			(layer "F.Fab")
			(hide yes)
			(effects
				(font
					(size 1.016 1.016)
					(thickness 0.1524)
				)
			)
		)
		(property "Device Type" "R402H16"
			(at 0.064008 -5.517896 180)
			(unlocked yes)
			(layer "F.Fab")
			(hide yes)
			(effects
				(font
					(size 1.016 1.016)
					(thickness 0.1524)
				)
			)
		)
		(duplicate_pad_numbers_are_jumpers no)
		(fp_line
			(start 0.508 -0.9398)
			(end -0.508 -0.9398)
			(stroke
				(width 0.1524)
				(type default)
			)
			(layer "F.SilkS")
		)
		(fp_line
			(start -0.508 -0.9398)
			(end -0.508 0.9398)
			(stroke
				(width 0.1524)
				(type default)
			)
			(layer "F.SilkS")
		)
		(fp_rect
			(start -0.508 0.9398)
			(end 0.508 -0.9398)
			(stroke
				(width 0)
				(type default)
			)
			(fill no)
			(layer "F.CrtYd")
		)
		(fp_rect
			(start -0.508 0.9398)
			(end 0.508 -0.9398)
			(stroke
				(width 0)
				(type default)
			)
			(fill no)
			(layer "F.Fab")
		)
		(pad "1" smd custom
			(at 0 -0.4445 180)
			(size 0.1397 0.1397)
			(layers "F.Cu" "F.Mask" "F.Paste")
			(net "SW_HDD_R2")
			(options
				(clearance outline)
				(anchor circle)
			)
			(primitives
				(gr_poly
					(pts
						(arc
							(start -0.1778 -0.2794)
							(mid -0.249642 -0.249642)
							(end -0.2794 -0.1778)
						)
						(arc
							(start -0.2794 0.1778)
							(mid -0.249642 0.249642)
							(end -0.1778 0.2794)
						)
						(arc
							(start 0.1778 0.2794)
							(mid 0.249642 0.249642)
							(end 0.2794 0.1778)
						)
						(arc
							(start 0.2794 -0.1778)
							(mid 0.249642 -0.249642)
							(end 0.1778 -0.2794)
						)
					)
					(width 0)
					(fill yes)
				)
			)
		)
		(pad "2" smd custom
			(at 0 0.4445 180)
			(size 0.1397 0.1397)
			(layers "F.Cu" "F.Mask" "F.Paste")
			(net "SW_HDD_N2")
			(options
				(clearance outline)
				(anchor circle)
			)
			(primitives
				(gr_poly
					(pts
						(arc
							(start -0.1778 -0.2794)
							(mid -0.249642 -0.249642)
							(end -0.2794 -0.1778)
						)
						(arc
							(start -0.2794 0.1778)
							(mid -0.249642 0.249642)
							(end -0.1778 0.2794)
						)
						(arc
							(start 0.1778 0.2794)
							(mid 0.249642 0.249642)
							(end 0.2794 0.1778)
						)
						(arc
							(start 0.2794 -0.1778)
							(mid 0.249642 -0.249642)
							(end 0.1778 -0.2794)
						)
					)
					(width 0)
					(fill yes)
				)
			)
		)
	)
	(footprint ""
		(layer "F.Cu")
		(at 398.018 -253.873 -90)
		(property "Reference" "Q30"
			(at 0 0 270)
			(layer "F.SilkS")
			(hide yes)
			(effects
				(font
					(size 1.27 1.27)
				)
			)
		)
		(property "Value" "AO4406AL-GP"
			(at -3.707384 -1.5367 270)
			(unlocked yes)
			(layer "F.Fab")
			(hide yes)
			(effects
				(font
					(size 1.016 1.016)
					(thickness 0.1524)
				)
			)
		)
		(property "Device Type" "SOIC8H69"
			(at -3.707384 -3.0607 270)
			(unlocked yes)
			(layer "F.Fab")
			(hide yes)
			(effects
				(font
					(size 1.016 1.016)
					(thickness 0.1524)
				)
			)
		)
		(duplicate_pad_numbers_are_jumpers no)
		(fp_line
			(start -2.6289 3.4417)
			(end -2.6289 1.4732)
			(stroke
				(width 0.381)
				(type default)
			)
			(layer "F.SilkS")
		)
		(fp_line
			(start -2.7432 1.4224)
			(end -2.6416 1.4224)
			(stroke
				(width 0.1524)
				(type default)
			)
			(layer "F.SilkS")
		)
		(fp_line
			(start -2.7432 1.4224)
			(end 2.1336 1.4224)
			(stroke
				(width 0.1524)
				(type default)
			)
			(layer "F.SilkS")
		)
		(fp_line
			(start 2.1336 1.4224)
			(end 2.1336 -1.4224)
			(stroke
				(width 0.1524)
				(type default)
			)
			(layer "F.SilkS")
		)
		(fp_line
			(start -2.1844 -0.0508)
			(end -2.7178 0.508)
			(stroke
				(width 0.1524)
				(type default)
			)
			(layer "F.SilkS")
		)
		(fp_line
			(start -2.7178 -0.508)
			(end -2.1844 -0.0508)
			(stroke
				(width 0.1524)
				(type default)
			)
			(layer "F.SilkS")
		)
		(fp_line
			(start -2.7432 -1.4224)
			(end -2.7432 1.4224)
			(stroke
				(width 0.1524)
				(type default)
			)
			(layer "F.SilkS")
		)
		(fp_line
			(start 2.1336 -1.4224)
			(end -2.7432 -1.4224)
			(stroke
				(width 0.1524)
				(type default)
			)
			(layer "F.SilkS")
		)
		(fp_poly
			(pts
				(xy -2.2098 -1.4224) (xy -2.2098 1.4224) (xy 2.2098 1.4224) (xy 2.2098 -1.4224)
			)
			(stroke
				(width 0)
				(type default)
			)
			(fill yes)
			(layer "F.SilkS")
		)
		(fp_rect
			(start -2.450084 2.999994)
			(end 2.450084 -2.999994)
			(stroke
				(width 0)
				(type default)
			)
			(fill no)
			(layer "F.CrtYd")
		)
		(fp_poly
			(pts
				(xy -2.8194 3.6322) (xy -2.8194 -3.6322) (xy 2.8194 -3.6322) (xy 2.8194 1.18364) (xy 2.450084 1.18364)
				(xy 2.450084 -2.999994) (xy -2.450084 -2.999994) (xy -2.450084 2.999994) (xy 2.450084 2.999994)
				(xy 2.450084 1.18618) (xy 2.8194 1.18618) (xy 2.8194 3.6322)
			)
			(stroke
				(width 0)
				(type default)
			)
			(fill no)
			(layer "F.CrtYd")
		)
		(fp_rect
			(start -2.8194 3.6322)
			(end 2.8194 -3.6322)
			(stroke
				(width 0)
				(type default)
			)
			(fill no)
			(layer "F.Fab")
		)
		(pad "1" smd rect
			(at -1.905 2.54 270)
			(size 0.635 1.651)
			(layers "F.Cu" "F.Mask" "F.Paste")
			(net "P5V_HDD8")
		)
		(pad "2" smd rect
			(at -0.635 2.54 270)
			(size 0.635 1.651)
			(layers "F.Cu" "F.Mask" "F.Paste")
			(net "P5V_HDD8")
		)
		(pad "3" smd rect
			(at 0.635 2.54 270)
			(size 0.635 1.651)
			(layers "F.Cu" "F.Mask" "F.Paste")
			(net "P5V_HDD8")
		)
		(pad "4" smd rect
			(at 1.905 2.54 270)
			(size 0.635 1.651)
			(layers "F.Cu" "F.Mask" "F.Paste")
			(net "SW_HDD_P8")
		)
		(pad "5" smd rect
			(at 1.905 -2.54 270)
			(size 0.635 1.651)
			(layers "F.Cu" "F.Mask" "F.Paste")
			(net "P5V_B_3")
		)
		(pad "6" smd rect
			(at 0.635 -2.54 270)
			(size 0.635 1.651)
			(layers "F.Cu" "F.Mask" "F.Paste")
			(net "P5V_B_3")
		)
		(pad "7" smd rect
			(at -0.635 -2.54 270)
			(size 0.635 1.651)
			(layers "F.Cu" "F.Mask" "F.Paste")
			(net "P5V_B_3")
		)
		(pad "8" smd rect
			(at -1.905 -2.54 270)
			(size 0.635 1.651)
			(layers "F.Cu" "F.Mask" "F.Paste")
			(net "P5V_B_3")
		)
	)
	(footprint ""
		(layer "F.Cu")
		(at 332.232 -10.16 180)
		(property "Reference" "R768"
			(at 0 0 180)
			(layer "F.SilkS")
			(hide yes)
			(effects
				(font
					(size 1.27 1.27)
				)
			)
		)
		(property "Value" "1KR2F-3-GP"
			(at 0.064008 -3.993896 180)
			(unlocked yes)
			(layer "F.Fab")
			(hide yes)
			(effects
				(font
					(size 1.016 1.016)
					(thickness 0.1524)
				)
			)
		)
		(property "Device Type" "R402H16"
			(at 0.064008 -5.517896 180)
			(unlocked yes)
			(layer "F.Fab")
			(hide yes)
			(effects
				(font
					(size 1.016 1.016)
					(thickness 0.1524)
				)
			)
		)
		(duplicate_pad_numbers_are_jumpers no)
		(fp_line
			(start 0.508 -0.9398)
			(end -0.508 -0.9398)
			(stroke
				(width 0.1524)
				(type default)
			)
			(layer "F.SilkS")
		)
		(fp_line
			(start -0.508 -0.9398)
			(end -0.508 0.9398)
			(stroke
				(width 0.1524)
				(type default)
			)
			(layer "F.SilkS")
		)
		(fp_rect
			(start -0.508 0.9398)
			(end 0.508 -0.9398)
			(stroke
				(width 0)
				(type default)
			)
			(fill no)
			(layer "F.CrtYd")
		)
		(fp_rect
			(start -0.508 0.9398)
			(end 0.508 -0.9398)
			(stroke
				(width 0)
				(type default)
			)
			(fill no)
			(layer "F.Fab")
		)
		(pad "1" smd custom
			(at 0 -0.4445 180)
			(size 0.1397 0.1397)
			(layers "F.Cu" "F.Mask" "F.Paste")
			(net "P3V3_STBY_B")
			(options
				(clearance outline)
				(anchor circle)
			)
			(primitives
				(gr_poly
					(pts
						(arc
							(start -0.1778 -0.2794)
							(mid -0.249642 -0.249642)
							(end -0.2794 -0.1778)
						)
						(arc
							(start -0.2794 0.1778)
							(mid -0.249642 0.249642)
							(end -0.1778 0.2794)
						)
						(arc
							(start 0.1778 0.2794)
							(mid 0.249642 0.249642)
							(end 0.2794 0.1778)
						)
						(arc
							(start 0.2794 -0.1778)
							(mid 0.249642 -0.249642)
							(end 0.1778 -0.2794)
						)
					)
					(width 0)
					(fill yes)
				)
			)
		)
		(pad "2" smd custom
			(at 0 0.4445 180)
			(size 0.1397 0.1397)
			(layers "F.Cu" "F.Mask" "F.Paste")
			(net "SW_PWR_R_HDD30")
			(options
				(clearance outline)
				(anchor circle)
			)
			(primitives
				(gr_poly
					(pts
						(arc
							(start -0.1778 -0.2794)
							(mid -0.249642 -0.249642)
							(end -0.2794 -0.1778)
						)
						(arc
							(start -0.2794 0.1778)
							(mid -0.249642 0.249642)
							(end -0.1778 0.2794)
						)
						(arc
							(start 0.1778 0.2794)
							(mid 0.249642 0.249642)
							(end 0.2794 0.1778)
						)
						(arc
							(start 0.2794 -0.1778)
							(mid 0.249642 -0.249642)
							(end 0.1778 -0.2794)
						)
					)
					(width 0)
					(fill yes)
				)
			)
		)
	)
	(footprint ""
		(layer "F.Cu")
		(at 382.315974 -269.705074)
		(property "Reference" "TP61"
			(at 0 0 0)
			(layer "F.SilkS")
			(hide yes)
			(effects
				(font
					(size 1.27 1.27)
				)
			)
		)
		(property "Value" "*"
			(at -0.0508 -1.6764 0)
			(unlocked yes)
			(layer "F.Fab")
			(hide yes)
			(effects
				(font
					(size 1.016 1.016)
					(thickness 0.1524)
				)
			)
		)
		(property "Device Type" "TPAD32"
			(at -0.0508 -3.2004 0)
			(unlocked yes)
			(layer "F.Fab")
			(hide yes)
			(effects
				(font
					(size 1.016 1.016)
					(thickness 0.1524)
				)
			)
		)
		(duplicate_pad_numbers_are_jumpers no)
		(fp_poly
			(pts
				(arc
					(start 0.4064 0)
					(mid -0.4064 0)
					(end 0.4064 0)
				)
			)
			(stroke
				(width 0)
				(type default)
			)
			(fill no)
			(layer "F.CrtYd")
		)
		(fp_poly
			(pts
				(arc
					(start 0.7112 0)
					(mid -0.7112 0)
					(end 0.7112 0)
				)
			)
			(stroke
				(width 0)
				(type default)
			)
			(fill no)
			(layer "F.Fab")
		)
		(pad "1" smd circle
			(at 0 0)
			(size 0.8128 0.8128)
			(layers "F.Cu" "F.Mask" "F.Paste")
			(net "ACT_HDD_8")
		)
	)
	(footprint ""
		(layer "F.Cu")
		(at 241.554 -230.632 -90)
		(property "Reference" "Q33"
			(at 0 0 270)
			(layer "F.SilkS")
			(hide yes)
			(effects
				(font
					(size 1.27 1.27)
				)
			)
		)
		(property "Value" "SSM3K324R-GP"
			(at 0.127 -8.9662 270)
			(unlocked yes)
			(layer "F.Fab")
			(hide yes)
			(effects
				(font
					(size 1.016 1.016)
					(thickness 0.1524)
				)
			)
		)
		(property "Device Type" "SOT23DGS2D4H35"
			(at 0.127 -10.4902 270)
			(unlocked yes)
			(layer "F.Fab")
			(hide yes)
			(effects
				(font
					(size 1.016 1.016)
					(thickness 0.1524)
				)
			)
		)
		(duplicate_pad_numbers_are_jumpers no)
		(fp_line
			(start -1.651 1.778)
			(end 1.651 1.778)
			(stroke
				(width 0.1524)
				(type default)
			)
			(layer "F.SilkS")
		)
		(fp_line
			(start 1.651 1.778)
			(end 1.651 -1.778)
			(stroke
				(width 0.1524)
				(type default)
			)
			(layer "F.SilkS")
		)
		(fp_line
			(start -1.651 -1.778)
			(end -1.651 1.778)
			(stroke
				(width 0.1524)
				(type default)
			)
			(layer "F.SilkS")
		)
		(fp_line
			(start 1.651 -1.778)
			(end -1.651 -1.778)
			(stroke
				(width 0.1524)
				(type default)
			)
			(layer "F.SilkS")
		)
		(fp_poly
			(pts
				(xy -1.778 1.8796) (xy -1.778 -1.8796) (xy 1.778 -1.8796) (xy 1.778 1.8796)
			)
			(stroke
				(width 0)
				(type default)
			)
			(fill no)
			(layer "F.CrtYd")
		)
		(fp_poly
			(pts
				(xy -1.778 1.8796) (xy -1.778 -1.8796) (xy 1.778 -1.8796) (xy 1.778 1.8796)
			)
			(stroke
				(width 0)
				(type default)
			)
			(fill no)
			(layer "F.Fab")
		)
		(pad "D" smd custom
			(at 0 -0.9525 270)
			(size 0.1905 0.1905)
			(layers "F.Cu" "F.Mask" "F.Paste")
			(net "P3V3_STBY_B")
			(options
				(clearance outline)
				(anchor circle)
			)
			(primitives
				(gr_poly
					(pts
						(arc
							(start -0.1778 0.5715)
							(mid -0.321484 0.511984)
							(end -0.381 0.3683)
						)
						(arc
							(start -0.381 -0.3683)
							(mid -0.321484 -0.511984)
							(end -0.1778 -0.5715)
						)
						(arc
							(start 0.1778 -0.5715)
							(mid 0.321484 -0.511984)
							(end 0.381 -0.3683)
						)
						(arc
							(start 0.381 0.3683)
							(mid 0.321484 0.511984)
							(end 0.1778 0.5715)
						)
					)
					(width 0)
					(fill yes)
				)
			)
		)
		(pad "G" smd custom
			(at -0.98425 0.9525 270)
			(size 0.1905 0.1905)
			(layers "F.Cu" "F.Mask" "F.Paste")
			(net "SCC_FULL_PWR_EN_5V")
			(options
				(clearance outline)
				(anchor circle)
			)
			(primitives
				(gr_poly
					(pts
						(arc
							(start -0.1778 0.5715)
							(mid -0.321484 0.511984)
							(end -0.381 0.3683)
						)
						(arc
							(start -0.381 -0.3683)
							(mid -0.321484 -0.511984)
							(end -0.1778 -0.5715)
						)
						(arc
							(start 0.1778 -0.5715)
							(mid 0.321484 -0.511984)
							(end 0.381 -0.3683)
						)
						(arc
							(start 0.381 0.3683)
							(mid 0.321484 0.511984)
							(end 0.1778 0.5715)
						)
					)
					(width 0)
					(fill yes)
				)
			)
		)
		(pad "S" smd custom
			(at 0.98425 0.9525 270)
			(size 0.1905 0.1905)
			(layers "F.Cu" "F.Mask" "F.Paste")
			(net "GPIO_VCC_U10")
			(options
				(clearance outline)
				(anchor circle)
			)
			(primitives
				(gr_poly
					(pts
						(arc
							(start -0.1778 0.5715)
							(mid -0.321484 0.511984)
							(end -0.381 0.3683)
						)
						(arc
							(start -0.381 -0.3683)
							(mid -0.321484 -0.511984)
							(end -0.1778 -0.5715)
						)
						(arc
							(start 0.1778 -0.5715)
							(mid 0.321484 -0.511984)
							(end 0.381 -0.3683)
						)
						(arc
							(start 0.381 0.3683)
							(mid 0.321484 0.511984)
							(end 0.1778 0.5715)
						)
					)
					(width 0)
					(fill yes)
				)
			)
		)
	)
	(footprint ""
		(layer "F.Cu")
		(at 416.284664 -14.660626 -90)
		(property "Reference" "C458"
			(at 0 0 270)
			(layer "F.SilkS")
			(hide yes)
			(effects
				(font
					(size 1.27 1.27)
				)
			)
		)
		(property "Value" "SCD01U16V1KX-GP"
			(at -2.8321 -1.7399 270)
			(unlocked yes)
			(layer "F.Fab")
			(hide yes)
			(effects
				(font
					(size 1.016 1.016)
					(thickness 0.1524)
				)
			)
		)
		(property "Device Type" "C0201H13"
			(at -2.8321 -3.2639 270)
			(unlocked yes)
			(layer "F.Fab")
			(hide yes)
			(effects
				(font
					(size 1.016 1.016)
					(thickness 0.1524)
				)
			)
		)
		(duplicate_pad_numbers_are_jumpers no)
		(fp_rect
			(start -0.2794 0.6477)
			(end 0.2794 -0.6477)
			(stroke
				(width 0)
				(type default)
			)
			(fill no)
			(layer "F.CrtYd")
		)
		(fp_rect
			(start -0.2794 0.6477)
			(end 0.2794 -0.6477)
			(stroke
				(width 0)
				(type default)
			)
			(fill no)
			(layer "F.Fab")
		)
		(pad "1" smd custom
			(at 0 -0.2794 270)
			(size 0.0762 0.0762)
			(layers "F.Cu" "F.Mask" "F.Paste")
			(net "SAS_HDD_RX_P33")
			(options
				(clearance outline)
				(anchor circle)
			)
			(primitives
				(gr_poly
					(pts
						(arc
							(start 0.1524 -0.127)
							(mid 0.137521 -0.162921)
							(end 0.1016 -0.1778)
						)
						(arc
							(start -0.1016 -0.1778)
							(mid -0.137521 -0.162921)
							(end -0.1524 -0.127)
						)
						(arc
							(start -0.1524 0.127)
							(mid -0.137521 0.162921)
							(end -0.1016 0.1778)
						)
						(arc
							(start 0.1016 0.1778)
							(mid 0.137521 0.162921)
							(end 0.1524 0.127)
						)
					)
					(width 0)
					(fill yes)
				)
			)
		)
		(pad "2" smd custom
			(at 0 0.2794 270)
			(size 0.0762 0.0762)
			(layers "F.Cu" "F.Mask" "F.Paste")
			(net "PHY_SCC_B_TO_DRV_B_33_DP")
			(options
				(clearance outline)
				(anchor circle)
			)
			(primitives
				(gr_poly
					(pts
						(arc
							(start 0.1524 -0.127)
							(mid 0.137521 -0.162921)
							(end 0.1016 -0.1778)
						)
						(arc
							(start -0.1016 -0.1778)
							(mid -0.137521 -0.162921)
							(end -0.1524 -0.127)
						)
						(arc
							(start -0.1524 0.127)
							(mid -0.137521 0.162921)
							(end -0.1016 0.1778)
						)
						(arc
							(start 0.1016 0.1778)
							(mid 0.137521 0.162921)
							(end 0.1524 0.127)
						)
					)
					(width 0)
					(fill yes)
				)
			)
		)
	)
	(footprint ""
		(layer "F.Cu")
		(at 412.8262 -32.8676 180)
		(property "Reference" "R833"
			(at 0 0 180)
			(layer "F.SilkS")
			(hide yes)
			(effects
				(font
					(size 1.27 1.27)
				)
			)
		)
		(property "Value" "220R3F-1-GP"
			(at -0.0254 -2.5146 180)
			(unlocked yes)
			(layer "F.Fab")
			(hide yes)
			(effects
				(font
					(size 1.016 1.016)
					(thickness 0.1524)
				)
			)
		)
		(property "Device Type" "R603H22"
			(at -0.0254 -4.0386 180)
			(unlocked yes)
			(layer "F.Fab")
			(hide yes)
			(effects
				(font
					(size 1.016 1.016)
					(thickness 0.1524)
				)
			)
		)
		(duplicate_pad_numbers_are_jumpers no)
		(fp_line
			(start 0.2032 0)
			(end 0.4826 0)
			(stroke
				(width 0.2032)
				(type default)
			)
			(layer "F.SilkS")
		)
		(fp_line
			(start -0.4826 0)
			(end -0.2032 0)
			(stroke
				(width 0.2032)
				(type default)
			)
			(layer "F.SilkS")
		)
		(fp_rect
			(start -0.5842 1.3335)
			(end 0.5842 -1.3335)
			(stroke
				(width 0)
				(type default)
			)
			(fill no)
			(layer "F.CrtYd")
		)
		(fp_rect
			(start -0.5842 1.3335)
			(end 0.5842 -1.3335)
			(stroke
				(width 0)
				(type default)
			)
			(fill no)
			(layer "F.Fab")
		)
		(pad "1" smd custom
			(at 0 -0.762 180)
			(size 0.2159 0.2159)
			(layers "F.Cu" "F.Mask" "F.Paste")
			(net "HDD_PRSNT_33")
			(options
				(clearance outline)
				(anchor circle)
			)
			(primitives
				(gr_poly
					(pts
						(arc
							(start -0.3302 -0.4318)
							(mid -0.402042 -0.402042)
							(end -0.4318 -0.3302)
						)
						(arc
							(start -0.4318 0.3302)
							(mid -0.402042 0.402042)
							(end -0.3302 0.4318)
						)
						(arc
							(start 0.3302 0.4318)
							(mid 0.402042 0.402042)
							(end 0.4318 0.3302)
						)
						(arc
							(start 0.4318 -0.3302)
							(mid 0.402042 -0.402042)
							(end 0.3302 -0.4318)
						)
					)
					(width 0)
					(fill yes)
				)
			)
		)
		(pad "2" smd custom
			(at 0 0.762 180)
			(size 0.2159 0.2159)
			(layers "F.Cu" "F.Mask" "F.Paste")
			(net "DRIVE_B_33_INS")
			(options
				(clearance outline)
				(anchor circle)
			)
			(primitives
				(gr_poly
					(pts
						(arc
							(start -0.3302 -0.4318)
							(mid -0.402042 -0.402042)
							(end -0.4318 -0.3302)
						)
						(arc
							(start -0.4318 0.3302)
							(mid -0.402042 0.402042)
							(end -0.3302 0.4318)
						)
						(arc
							(start 0.3302 0.4318)
							(mid 0.402042 0.402042)
							(end 0.4318 0.3302)
						)
						(arc
							(start 0.4318 -0.3302)
							(mid 0.402042 -0.402042)
							(end 0.3302 -0.4318)
						)
					)
					(width 0)
					(fill yes)
				)
			)
		)
	)
	(footprint ""
		(layer "F.Cu")
		(at 213.10346 -164.00526 90)
		(property "Reference" "C12"
			(at 0 0 90)
			(layer "F.SilkS")
			(hide yes)
			(effects
				(font
					(size 1.27 1.27)
				)
			)
		)
		(property "Value" "SCD1U16V2KX-3GP"
			(at 1.1811 -2.7051 90)
			(unlocked yes)
			(layer "F.Fab")
			(hide yes)
			(effects
				(font
					(size 1.016 1.016)
					(thickness 0.1524)
				)
			)
		)
		(property "Device Type" "C402H22"
			(at 1.1811 -4.2291 90)
			(unlocked yes)
			(layer "F.Fab")
			(hide yes)
			(effects
				(font
					(size 1.016 1.016)
					(thickness 0.1524)
				)
			)
		)
		(duplicate_pad_numbers_are_jumpers no)
		(fp_rect
			(start -0.4318 0.9525)
			(end 0.4318 -0.9525)
			(stroke
				(width 0)
				(type default)
			)
			(fill no)
			(layer "F.CrtYd")
		)
		(fp_rect
			(start -0.4318 0.9525)
			(end 0.4318 -0.9525)
			(stroke
				(width 0)
				(type default)
			)
			(fill no)
			(layer "F.Fab")
		)
		(pad "1" smd custom
			(at 0 -0.4445 90)
			(size 0.1524 0.1524)
			(layers "F.Cu" "F.Mask" "F.Paste")
			(net "P3V3_STBY_B")
			(options
				(clearance outline)
				(anchor circle)
			)
			(primitives
				(gr_poly
					(pts
						(arc
							(start 0.3048 -0.2032)
							(mid 0.275042 -0.275042)
							(end 0.2032 -0.3048)
						)
						(arc
							(start -0.2032 -0.3048)
							(mid -0.275042 -0.275042)
							(end -0.3048 -0.2032)
						)
						(arc
							(start -0.3048 0.2032)
							(mid -0.275042 0.275042)
							(end -0.2032 0.3048)
						)
						(arc
							(start 0.2032 0.3048)
							(mid 0.275042 0.275042)
							(end 0.3048 0.2032)
						)
					)
					(width 0)
					(fill yes)
				)
			)
		)
		(pad "2" smd custom
			(at 0 0.4445 90)
			(size 0.1524 0.1524)
			(layers "F.Cu" "F.Mask" "F.Paste")
			(net "GND")
			(options
				(clearance outline)
				(anchor circle)
			)
			(primitives
				(gr_poly
					(pts
						(arc
							(start 0.3048 -0.2032)
							(mid 0.275042 -0.275042)
							(end 0.2032 -0.3048)
						)
						(arc
							(start -0.2032 -0.3048)
							(mid -0.275042 -0.275042)
							(end -0.3048 -0.2032)
						)
						(arc
							(start -0.3048 0.2032)
							(mid -0.275042 0.275042)
							(end -0.2032 0.3048)
						)
						(arc
							(start 0.2032 0.3048)
							(mid 0.275042 0.275042)
							(end 0.3048 0.2032)
						)
					)
					(width 0)
					(fill yes)
				)
			)
		)
	)
	(footprint ""
		(layer "F.Cu")
		(at 459.83017 -228.351842 -90)
		(property "Reference" "R1142"
			(at 0 0 270)
			(layer "F.SilkS")
			(hide yes)
			(effects
				(font
					(size 1.27 1.27)
				)
			)
		)
		(property "Value" "15KR2F-GP"
			(at 0.064008 -3.993896 270)
			(unlocked yes)
			(layer "F.Fab")
			(hide yes)
			(effects
				(font
					(size 1.016 1.016)
					(thickness 0.1524)
				)
			)
		)
		(property "Device Type" "R402H16"
			(at 0.064008 -5.517896 270)
			(unlocked yes)
			(layer "F.Fab")
			(hide yes)
			(effects
				(font
					(size 1.016 1.016)
					(thickness 0.1524)
				)
			)
		)
		(duplicate_pad_numbers_are_jumpers no)
		(fp_line
			(start -0.508 -0.9398)
			(end -0.508 0.9398)
			(stroke
				(width 0.1524)
				(type default)
			)
			(layer "F.SilkS")
		)
		(fp_line
			(start 0.508 -0.9398)
			(end -0.508 -0.9398)
			(stroke
				(width 0.1524)
				(type default)
			)
			(layer "F.SilkS")
		)
		(fp_rect
			(start -0.508 0.9398)
			(end 0.508 -0.9398)
			(stroke
				(width 0)
				(type default)
			)
			(fill no)
			(layer "F.CrtYd")
		)
		(fp_rect
			(start -0.508 0.9398)
			(end 0.508 -0.9398)
			(stroke
				(width 0)
				(type default)
			)
			(fill no)
			(layer "F.Fab")
		)
		(pad "1" smd custom
			(at 0 -0.4445 270)
			(size 0.1397 0.1397)
			(layers "F.Cu" "F.Mask" "F.Paste")
			(net "P5V_B_3_PGOOD")
			(options
				(clearance outline)
				(anchor circle)
			)
			(primitives
				(gr_poly
					(pts
						(arc
							(start -0.1778 -0.2794)
							(mid -0.249642 -0.249642)
							(end -0.2794 -0.1778)
						)
						(arc
							(start -0.2794 0.1778)
							(mid -0.249642 0.249642)
							(end -0.1778 0.2794)
						)
						(arc
							(start 0.1778 0.2794)
							(mid 0.249642 0.249642)
							(end 0.2794 0.1778)
						)
						(arc
							(start 0.2794 -0.1778)
							(mid 0.249642 -0.249642)
							(end 0.1778 -0.2794)
						)
					)
					(width 0)
					(fill yes)
				)
			)
		)
		(pad "2" smd custom
			(at 0 0.4445 270)
			(size 0.1397 0.1397)
			(layers "F.Cu" "F.Mask" "F.Paste")
			(net "GND")
			(options
				(clearance outline)
				(anchor circle)
			)
			(primitives
				(gr_poly
					(pts
						(arc
							(start -0.1778 -0.2794)
							(mid -0.249642 -0.249642)
							(end -0.2794 -0.1778)
						)
						(arc
							(start -0.2794 0.1778)
							(mid -0.249642 0.249642)
							(end -0.1778 0.2794)
						)
						(arc
							(start 0.1778 0.2794)
							(mid 0.249642 0.249642)
							(end 0.2794 0.1778)
						)
						(arc
							(start 0.2794 -0.1778)
							(mid 0.249642 -0.249642)
							(end 0.1778 -0.2794)
						)
					)
					(width 0)
					(fill yes)
				)
			)
		)
	)
	(footprint ""
		(layer "F.Cu")
		(at 401.828 -258.826 90)
		(property "Reference" "C143"
			(at 0 0 90)
			(layer "F.SilkS")
			(hide yes)
			(effects
				(font
					(size 1.27 1.27)
				)
			)
		)
		(property "Value" "SCD033U25V2KX-GP"
			(at 1.1811 -2.7051 90)
			(unlocked yes)
			(layer "F.Fab")
			(hide yes)
			(effects
				(font
					(size 1.016 1.016)
					(thickness 0.1524)
				)
			)
		)
		(property "Device Type" "C402H22"
			(at 1.1811 -4.2291 90)
			(unlocked yes)
			(layer "F.Fab")
			(hide yes)
			(effects
				(font
					(size 1.016 1.016)
					(thickness 0.1524)
				)
			)
		)
		(duplicate_pad_numbers_are_jumpers no)
		(fp_rect
			(start -0.4318 0.9525)
			(end 0.4318 -0.9525)
			(stroke
				(width 0)
				(type default)
			)
			(fill no)
			(layer "F.CrtYd")
		)
		(fp_rect
			(start -0.4318 0.9525)
			(end 0.4318 -0.9525)
			(stroke
				(width 0)
				(type default)
			)
			(fill no)
			(layer "F.Fab")
		)
		(pad "1" smd custom
			(at 0 -0.4445 90)
			(size 0.1524 0.1524)
			(layers "F.Cu" "F.Mask" "F.Paste")
			(net "P12V_B")
			(options
				(clearance outline)
				(anchor circle)
			)
			(primitives
				(gr_poly
					(pts
						(arc
							(start 0.3048 -0.2032)
							(mid 0.275042 -0.275042)
							(end 0.2032 -0.3048)
						)
						(arc
							(start -0.2032 -0.3048)
							(mid -0.275042 -0.275042)
							(end -0.3048 -0.2032)
						)
						(arc
							(start -0.3048 0.2032)
							(mid -0.275042 0.275042)
							(end -0.2032 0.3048)
						)
						(arc
							(start 0.2032 0.3048)
							(mid 0.275042 0.275042)
							(end 0.3048 0.2032)
						)
					)
					(width 0)
					(fill yes)
				)
			)
		)
		(pad "2" smd custom
			(at 0 0.4445 90)
			(size 0.1524 0.1524)
			(layers "F.Cu" "F.Mask" "F.Paste")
			(net "SW_HDD_N8")
			(options
				(clearance outline)
				(anchor circle)
			)
			(primitives
				(gr_poly
					(pts
						(arc
							(start 0.3048 -0.2032)
							(mid 0.275042 -0.275042)
							(end 0.2032 -0.3048)
						)
						(arc
							(start -0.2032 -0.3048)
							(mid -0.275042 -0.275042)
							(end -0.3048 -0.2032)
						)
						(arc
							(start -0.3048 0.2032)
							(mid -0.275042 0.275042)
							(end -0.2032 0.3048)
						)
						(arc
							(start 0.2032 0.3048)
							(mid 0.275042 0.275042)
							(end 0.3048 0.2032)
						)
					)
					(width 0)
					(fill yes)
				)
			)
		)
	)
	(footprint ""
		(layer "F.Cu")
		(at 320.465196 -377.1646 90)
		(property "Reference" "R181"
			(at 0 0 90)
			(layer "F.SilkS")
			(hide yes)
			(effects
				(font
					(size 1.27 1.27)
				)
			)
		)
		(property "Value" "4K7R2F-GP"
			(at 0.064008 -3.993896 90)
			(unlocked yes)
			(layer "F.Fab")
			(hide yes)
			(effects
				(font
					(size 1.016 1.016)
					(thickness 0.1524)
				)
			)
		)
		(property "Device Type" "R402H16"
			(at 0.064008 -5.517896 90)
			(unlocked yes)
			(layer "F.Fab")
			(hide yes)
			(effects
				(font
					(size 1.016 1.016)
					(thickness 0.1524)
				)
			)
		)
		(duplicate_pad_numbers_are_jumpers no)
		(fp_line
			(start 0.508 -0.9398)
			(end -0.508 -0.9398)
			(stroke
				(width 0.1524)
				(type default)
			)
			(layer "F.SilkS")
		)
		(fp_line
			(start -0.508 -0.9398)
			(end -0.508 0.9398)
			(stroke
				(width 0.1524)
				(type default)
			)
			(layer "F.SilkS")
		)
		(fp_rect
			(start -0.508 0.9398)
			(end 0.508 -0.9398)
			(stroke
				(width 0)
				(type default)
			)
			(fill no)
			(layer "F.CrtYd")
		)
		(fp_rect
			(start -0.508 0.9398)
			(end 0.508 -0.9398)
			(stroke
				(width 0)
				(type default)
			)
			(fill no)
			(layer "F.Fab")
		)
		(pad "1" smd custom
			(at 0 -0.4445 90)
			(size 0.1397 0.1397)
			(layers "F.Cu" "F.Mask" "F.Paste")
			(net "FAN_BLUE_LED2")
			(options
				(clearance outline)
				(anchor circle)
			)
			(primitives
				(gr_poly
					(pts
						(arc
							(start -0.1778 -0.2794)
							(mid -0.249642 -0.249642)
							(end -0.2794 -0.1778)
						)
						(arc
							(start -0.2794 0.1778)
							(mid -0.249642 0.249642)
							(end -0.1778 0.2794)
						)
						(arc
							(start 0.1778 0.2794)
							(mid 0.249642 0.249642)
							(end 0.2794 0.1778)
						)
						(arc
							(start 0.2794 -0.1778)
							(mid 0.249642 -0.249642)
							(end 0.1778 -0.2794)
						)
					)
					(width 0)
					(fill yes)
				)
			)
		)
		(pad "2" smd custom
			(at 0 0.4445 90)
			(size 0.1397 0.1397)
			(layers "F.Cu" "F.Mask" "F.Paste")
			(net "P12V_IN")
			(options
				(clearance outline)
				(anchor circle)
			)
			(primitives
				(gr_poly
					(pts
						(arc
							(start -0.1778 -0.2794)
							(mid -0.249642 -0.249642)
							(end -0.2794 -0.1778)
						)
						(arc
							(start -0.2794 0.1778)
							(mid -0.249642 0.249642)
							(end -0.1778 0.2794)
						)
						(arc
							(start 0.1778 0.2794)
							(mid 0.249642 0.249642)
							(end 0.2794 0.1778)
						)
						(arc
							(start 0.2794 -0.1778)
							(mid 0.249642 -0.249642)
							(end 0.1778 -0.2794)
						)
					)
					(width 0)
					(fill yes)
				)
			)
		)
	)
	(footprint ""
		(layer "F.Cu")
		(at 401.193 -135.509 90)
		(property "Reference" "R546"
			(at 0 0 90)
			(layer "F.SilkS")
			(hide yes)
			(effects
				(font
					(size 1.27 1.27)
				)
			)
		)
		(property "Value" "200KR2F-L-GP"
			(at 0.064008 -3.993896 90)
			(unlocked yes)
			(layer "F.Fab")
			(hide yes)
			(effects
				(font
					(size 1.016 1.016)
					(thickness 0.1524)
				)
			)
		)
		(property "Device Type" "R402H16"
			(at 0.064008 -5.517896 90)
			(unlocked yes)
			(layer "F.Fab")
			(hide yes)
			(effects
				(font
					(size 1.016 1.016)
					(thickness 0.1524)
				)
			)
		)
		(duplicate_pad_numbers_are_jumpers no)
		(fp_line
			(start 0.508 -0.9398)
			(end -0.508 -0.9398)
			(stroke
				(width 0.1524)
				(type default)
			)
			(layer "F.SilkS")
		)
		(fp_line
			(start -0.508 -0.9398)
			(end -0.508 0.9398)
			(stroke
				(width 0.1524)
				(type default)
			)
			(layer "F.SilkS")
		)
		(fp_rect
			(start -0.508 0.9398)
			(end 0.508 -0.9398)
			(stroke
				(width 0)
				(type default)
			)
			(fill no)
			(layer "F.CrtYd")
		)
		(fp_rect
			(start -0.508 0.9398)
			(end 0.508 -0.9398)
			(stroke
				(width 0)
				(type default)
			)
			(fill no)
			(layer "F.Fab")
		)
		(pad "1" smd custom
			(at 0 -0.4445 90)
			(size 0.1397 0.1397)
			(layers "F.Cu" "F.Mask" "F.Paste")
			(net "SW_HDD_R20")
			(options
				(clearance outline)
				(anchor circle)
			)
			(primitives
				(gr_poly
					(pts
						(arc
							(start -0.1778 -0.2794)
							(mid -0.249642 -0.249642)
							(end -0.2794 -0.1778)
						)
						(arc
							(start -0.2794 0.1778)
							(mid -0.249642 0.249642)
							(end -0.1778 0.2794)
						)
						(arc
							(start 0.1778 0.2794)
							(mid 0.249642 0.249642)
							(end 0.2794 0.1778)
						)
						(arc
							(start 0.2794 -0.1778)
							(mid 0.249642 -0.249642)
							(end 0.1778 -0.2794)
						)
					)
					(width 0)
					(fill yes)
				)
			)
		)
		(pad "2" smd custom
			(at 0 0.4445 90)
			(size 0.1397 0.1397)
			(layers "F.Cu" "F.Mask" "F.Paste")
			(net "SW_HDD_N20")
			(options
				(clearance outline)
				(anchor circle)
			)
			(primitives
				(gr_poly
					(pts
						(arc
							(start -0.1778 -0.2794)
							(mid -0.249642 -0.249642)
							(end -0.2794 -0.1778)
						)
						(arc
							(start -0.2794 0.1778)
							(mid -0.249642 0.249642)
							(end -0.1778 0.2794)
						)
						(arc
							(start 0.1778 0.2794)
							(mid 0.249642 0.249642)
							(end 0.2794 0.1778)
						)
						(arc
							(start 0.2794 -0.1778)
							(mid 0.249642 -0.249642)
							(end 0.1778 -0.2794)
						)
					)
					(width 0)
					(fill yes)
				)
			)
		)
	)
	(footprint ""
		(layer "F.Cu")
		(at 237.871 -199.0852 90)
		(property "Reference" "U9"
			(at 0 0 90)
			(layer "F.SilkS")
			(hide yes)
			(effects
				(font
					(size 1.27 1.27)
				)
			)
		)
		(property "Value" "TCA9555PWR-GP"
			(at 0 -6.9342 90)
			(unlocked yes)
			(layer "F.Fab")
			(hide yes)
			(effects
				(font
					(size 1.016 1.016)
					(thickness 0.1524)
				)
			)
		)
		(property "Device Type" "TSOIC24H48"
			(at 0 -8.5852 90)
			(unlocked yes)
			(layer "F.Fab")
			(hide yes)
			(effects
				(font
					(size 1.016 1.016)
					(thickness 0.1524)
				)
			)
		)
		(duplicate_pad_numbers_are_jumpers no)
		(fp_line
			(start 3.81 -1.397)
			(end 3.81 1.397)
			(stroke
				(width 0.1524)
				(type default)
			)
			(layer "F.SilkS")
		)
		(fp_line
			(start -4.2291 -1.397)
			(end 3.81 -1.397)
			(stroke
				(width 0.1524)
				(type default)
			)
			(layer "F.SilkS")
		)
		(fp_line
			(start -4.2291 -0.8001)
			(end -3.429 0)
			(stroke
				(width 0.1524)
				(type default)
			)
			(layer "F.SilkS")
		)
		(fp_line
			(start -3.429 0)
			(end -4.2291 0.8001)
			(stroke
				(width 0.1524)
				(type default)
			)
			(layer "F.SilkS")
		)
		(fp_line
			(start 3.81 1.397)
			(end -4.2291 1.397)
			(stroke
				(width 0.1524)
				(type default)
			)
			(layer "F.SilkS")
		)
		(fp_line
			(start -4.22656 3.81)
			(end -4.2291 1.397)
			(stroke
				(width 0.508)
				(type default)
			)
			(layer "F.SilkS")
		)
		(fp_line
			(start -4.2291 3.937)
			(end -4.2291 -1.397)
			(stroke
				(width 0.1524)
				(type default)
			)
			(layer "F.SilkS")
		)
		(fp_poly
			(pts
				(xy -3.90652 -1.8542) (xy 3.90652 -1.8542) (xy 3.90652 1.8542) (xy -3.90652 1.8542)
			)
			(stroke
				(width 0)
				(type default)
			)
			(fill yes)
			(layer "F.SilkS")
		)
		(fp_poly
			(pts
				(xy -4.2164 3.81) (xy 4.2164 3.81) (xy 4.22656 -3.81) (xy -4.2164 -3.81)
			)
			(stroke
				(width 0)
				(type default)
			)
			(fill no)
			(layer "F.CrtYd")
		)
		(fp_poly
			(pts
				(xy -4.22656 -3.81) (xy 4.22656 -3.81) (xy 4.22656 3.81) (xy -4.22656 3.81)
			)
			(stroke
				(width 0)
				(type default)
			)
			(fill no)
			(layer "F.Fab")
		)
		(pad "1" smd rect
			(at -3.57632 2.8194 90)
			(size 0.3556 1.524)
			(layers "F.Cu" "F.Mask" "F.Paste")
			(net "IO_EXP2_INT_N")
		)
		(pad "2" smd rect
			(at -2.92608 2.8194 90)
			(size 0.3556 1.524)
			(layers "F.Cu" "F.Mask" "F.Paste")
			(net "IO_EXP2_A1")
		)
		(pad "3" smd rect
			(at -2.27584 2.8194 90)
			(size 0.3556 1.524)
			(layers "F.Cu" "F.Mask" "F.Paste")
			(net "IO_EXP2_A2")
		)
		(pad "4" smd rect
			(at -1.6256 2.8194 90)
			(size 0.3556 1.524)
			(layers "F.Cu" "F.Mask" "F.Paste")
			(net "DRIVE_B_16_PWR")
		)
		(pad "5" smd rect
			(at -0.97536 2.8194 90)
			(size 0.3556 1.524)
			(layers "F.Cu" "F.Mask" "F.Paste")
			(net "DRIVE_B_17_PWR")
		)
		(pad "6" smd rect
			(at -0.32512 2.8194 90)
			(size 0.3556 1.524)
			(layers "F.Cu" "F.Mask" "F.Paste")
			(net "DRIVE_B_18_PWR")
		)
		(pad "7" smd rect
			(at 0.32512 2.8194 90)
			(size 0.3556 1.524)
			(layers "F.Cu" "F.Mask" "F.Paste")
			(net "DRIVE_B_19_PWR")
		)
		(pad "8" smd rect
			(at 0.97536 2.8194 90)
			(size 0.3556 1.524)
			(layers "F.Cu" "F.Mask" "F.Paste")
			(net "DRIVE_B_20_PWR")
		)
		(pad "9" smd rect
			(at 1.6256 2.8194 90)
			(size 0.3556 1.524)
			(layers "F.Cu" "F.Mask" "F.Paste")
			(net "DRIVE_B_21_PWR")
		)
		(pad "10" smd rect
			(at 2.27584 2.8194 90)
			(size 0.3556 1.524)
			(layers "F.Cu" "F.Mask" "F.Paste")
			(net "DRIVE_B_22_PWR")
		)
		(pad "11" smd rect
			(at 2.92608 2.8194 90)
			(size 0.3556 1.524)
			(layers "F.Cu" "F.Mask" "F.Paste")
			(net "DRIVE_B_23_PWR")
		)
		(pad "12" smd rect
			(at 3.57632 2.8194 90)
			(size 0.3556 1.524)
			(layers "F.Cu" "F.Mask" "F.Paste")
			(net "GND")
		)
		(pad "13" smd rect
			(at 3.57632 -2.8194 90)
			(size 0.3556 1.524)
			(layers "F.Cu" "F.Mask" "F.Paste")
			(net "DRIVE_B_24_PWR")
		)
		(pad "14" smd rect
			(at 2.92608 -2.8194 90)
			(size 0.3556 1.524)
			(layers "F.Cu" "F.Mask" "F.Paste")
			(net "DRIVE_B_25_PWR")
		)
		(pad "15" smd rect
			(at 2.27584 -2.8194 90)
			(size 0.3556 1.524)
			(layers "F.Cu" "F.Mask" "F.Paste")
			(net "DRIVE_B_26_PWR")
		)
		(pad "16" smd rect
			(at 1.6256 -2.8194 90)
			(size 0.3556 1.524)
			(layers "F.Cu" "F.Mask" "F.Paste")
			(net "DRIVE_B_27_PWR")
		)
		(pad "17" smd rect
			(at 0.97536 -2.8194 90)
			(size 0.3556 1.524)
			(layers "F.Cu" "F.Mask" "F.Paste")
			(net "DRIVE_B_28_PWR")
		)
		(pad "18" smd rect
			(at 0.32512 -2.8194 90)
			(size 0.3556 1.524)
			(layers "F.Cu" "F.Mask" "F.Paste")
			(net "DRIVE_B_29_PWR")
		)
		(pad "19" smd rect
			(at -0.32512 -2.8194 90)
			(size 0.3556 1.524)
			(layers "F.Cu" "F.Mask" "F.Paste")
			(net "DRIVE_B_30_PWR")
		)
		(pad "20" smd rect
			(at -0.97536 -2.8194 90)
			(size 0.3556 1.524)
			(layers "F.Cu" "F.Mask" "F.Paste")
			(net "DRIVE_B_31_PWR")
		)
		(pad "21" smd rect
			(at -1.6256 -2.8194 90)
			(size 0.3556 1.524)
			(layers "F.Cu" "F.Mask" "F.Paste")
			(net "IO_EXP2_A0")
		)
		(pad "22" smd rect
			(at -2.27584 -2.8194 90)
			(size 0.3556 1.524)
			(layers "F.Cu" "F.Mask" "F.Paste")
			(net "IO_EXP2_SCL")
		)
		(pad "23" smd rect
			(at -2.92608 -2.8194 90)
			(size 0.3556 1.524)
			(layers "F.Cu" "F.Mask" "F.Paste")
			(net "IO_EXP2_SDA")
		)
		(pad "24" smd rect
			(at -3.57632 -2.8194 90)
			(size 0.3556 1.524)
			(layers "F.Cu" "F.Mask" "F.Paste")
			(net "GPIO_VCC_U9")
		)
	)
	(footprint ""
		(layer "F.Cu")
		(at 247.762522 -358.876346)
		(property "Reference" "C559"
			(at 0 0 0)
			(layer "F.SilkS")
			(hide yes)
			(effects
				(font
					(size 1.27 1.27)
				)
			)
		)
		(property "Value" "SCD1U25V2KX-2-GP"
			(at 1.1811 -2.7051 0)
			(unlocked yes)
			(layer "F.Fab")
			(hide yes)
			(effects
				(font
					(size 1.016 1.016)
					(thickness 0.1524)
				)
			)
		)
		(property "Device Type" "C402H22"
			(at 1.1811 -4.2291 0)
			(unlocked yes)
			(layer "F.Fab")
			(hide yes)
			(effects
				(font
					(size 1.016 1.016)
					(thickness 0.1524)
				)
			)
		)
		(duplicate_pad_numbers_are_jumpers no)
		(fp_rect
			(start -0.4318 0.9525)
			(end 0.4318 -0.9525)
			(stroke
				(width 0)
				(type default)
			)
			(fill no)
			(layer "F.CrtYd")
		)
		(fp_rect
			(start -0.4318 0.9525)
			(end 0.4318 -0.9525)
			(stroke
				(width 0)
				(type default)
			)
			(fill no)
			(layer "F.Fab")
		)
		(pad "1" smd custom
			(at 0 -0.4445)
			(size 0.1524 0.1524)
			(layers "F.Cu" "F.Mask" "F.Paste")
			(net "MB3_PSET_R")
			(options
				(clearance outline)
				(anchor circle)
			)
			(primitives
				(gr_poly
					(pts
						(arc
							(start 0.3048 -0.2032)
							(mid 0.275042 -0.275042)
							(end 0.2032 -0.3048)
						)
						(arc
							(start -0.2032 -0.3048)
							(mid -0.275042 -0.275042)
							(end -0.3048 -0.2032)
						)
						(arc
							(start -0.3048 0.2032)
							(mid -0.275042 0.275042)
							(end -0.2032 0.3048)
						)
						(arc
							(start 0.2032 0.3048)
							(mid 0.275042 0.275042)
							(end 0.3048 0.2032)
						)
					)
					(width 0)
					(fill yes)
				)
			)
		)
		(pad "2" smd custom
			(at 0 0.4445)
			(size 0.1524 0.1524)
			(layers "F.Cu" "F.Mask" "F.Paste")
			(net "AGND_CURRENT_DPB")
			(options
				(clearance outline)
				(anchor circle)
			)
			(primitives
				(gr_poly
					(pts
						(arc
							(start 0.3048 -0.2032)
							(mid 0.275042 -0.275042)
							(end 0.2032 -0.3048)
						)
						(arc
							(start -0.2032 -0.3048)
							(mid -0.275042 -0.275042)
							(end -0.3048 -0.2032)
						)
						(arc
							(start -0.3048 0.2032)
							(mid -0.275042 0.275042)
							(end -0.2032 0.3048)
						)
						(arc
							(start 0.2032 0.3048)
							(mid 0.275042 0.275042)
							(end 0.3048 0.2032)
						)
					)
					(width 0)
					(fill yes)
				)
			)
		)
	)
	(footprint ""
		(layer "F.Cu")
		(at 172.974 -133.096 180)
		(property "Reference" "R477"
			(at 0 0 180)
			(layer "F.SilkS")
			(hide yes)
			(effects
				(font
					(size 1.27 1.27)
				)
			)
		)
		(property "Value" "200KR2F-L-GP"
			(at 0.064008 -3.993896 180)
			(unlocked yes)
			(layer "F.Fab")
			(hide yes)
			(effects
				(font
					(size 1.016 1.016)
					(thickness 0.1524)
				)
			)
		)
		(property "Device Type" "R402H16"
			(at 0.064008 -5.517896 180)
			(unlocked yes)
			(layer "F.Fab")
			(hide yes)
			(effects
				(font
					(size 1.016 1.016)
					(thickness 0.1524)
				)
			)
		)
		(duplicate_pad_numbers_are_jumpers no)
		(fp_line
			(start 0.508 -0.9398)
			(end -0.508 -0.9398)
			(stroke
				(width 0.1524)
				(type default)
			)
			(layer "F.SilkS")
		)
		(fp_line
			(start -0.508 -0.9398)
			(end -0.508 0.9398)
			(stroke
				(width 0.1524)
				(type default)
			)
			(layer "F.SilkS")
		)
		(fp_rect
			(start -0.508 0.9398)
			(end 0.508 -0.9398)
			(stroke
				(width 0)
				(type default)
			)
			(fill no)
			(layer "F.CrtYd")
		)
		(fp_rect
			(start -0.508 0.9398)
			(end 0.508 -0.9398)
			(stroke
				(width 0)
				(type default)
			)
			(fill no)
			(layer "F.Fab")
		)
		(pad "1" smd custom
			(at 0 -0.4445 180)
			(size 0.1397 0.1397)
			(layers "F.Cu" "F.Mask" "F.Paste")
			(net "SW_HDD_R17")
			(options
				(clearance outline)
				(anchor circle)
			)
			(primitives
				(gr_poly
					(pts
						(arc
							(start -0.1778 -0.2794)
							(mid -0.249642 -0.249642)
							(end -0.2794 -0.1778)
						)
						(arc
							(start -0.2794 0.1778)
							(mid -0.249642 0.249642)
							(end -0.1778 0.2794)
						)
						(arc
							(start 0.1778 0.2794)
							(mid 0.249642 0.249642)
							(end 0.2794 0.1778)
						)
						(arc
							(start 0.2794 -0.1778)
							(mid 0.249642 -0.249642)
							(end 0.1778 -0.2794)
						)
					)
					(width 0)
					(fill yes)
				)
			)
		)
		(pad "2" smd custom
			(at 0 0.4445 180)
			(size 0.1397 0.1397)
			(layers "F.Cu" "F.Mask" "F.Paste")
			(net "SW_HDD_N17")
			(options
				(clearance outline)
				(anchor circle)
			)
			(primitives
				(gr_poly
					(pts
						(arc
							(start -0.1778 -0.2794)
							(mid -0.249642 -0.249642)
							(end -0.2794 -0.1778)
						)
						(arc
							(start -0.2794 0.1778)
							(mid -0.249642 0.249642)
							(end -0.1778 0.2794)
						)
						(arc
							(start 0.1778 0.2794)
							(mid 0.249642 0.249642)
							(end 0.2794 0.1778)
						)
						(arc
							(start 0.2794 -0.1778)
							(mid 0.249642 -0.249642)
							(end 0.1778 -0.2794)
						)
					)
					(width 0)
					(fill yes)
				)
			)
		)
	)
	(footprint ""
		(layer "F.Cu")
		(at 463.1436 -23.9776 90)
		(property "Reference" "D34"
			(at 0 0 90)
			(layer "F.SilkS")
			(hide yes)
			(effects
				(font
					(size 1.27 1.27)
				)
			)
		)
		(property "Value" "RB551V30-GP"
			(at 0 -6.7818 90)
			(unlocked yes)
			(layer "F.Fab")
			(hide yes)
			(effects
				(font
					(size 1.016 1.016)
					(thickness 0.1524)
				)
			)
		)
		(property "Device Type" "SOD323AKH38"
			(at 0 -8.6868 90)
			(unlocked yes)
			(layer "F.Fab")
			(hide yes)
			(effects
				(font
					(size 1.016 1.016)
					(thickness 0.1524)
				)
			)
		)
		(duplicate_pad_numbers_are_jumpers no)
		(fp_line
			(start 0.889 -1.9304)
			(end 0.889 2.159)
			(stroke
				(width 0.1524)
				(type default)
			)
			(layer "F.SilkS")
		)
		(fp_line
			(start -0.889 -1.9304)
			(end 0.889 -1.9304)
			(stroke
				(width 0.1524)
				(type default)
			)
			(layer "F.SilkS")
		)
		(fp_line
			(start 0.762 2.0574)
			(end -0.762 2.0574)
			(stroke
				(width 0.508)
				(type default)
			)
			(layer "F.SilkS")
		)
		(fp_line
			(start 0.889 2.159)
			(end -0.889 2.159)
			(stroke
				(width 0.1524)
				(type default)
			)
			(layer "F.SilkS")
		)
		(fp_line
			(start -0.889 2.159)
			(end -0.889 -1.9304)
			(stroke
				(width 0.1524)
				(type default)
			)
			(layer "F.SilkS")
		)
		(fp_rect
			(start -1.016 2.3114)
			(end 1.016 -2.0066)
			(stroke
				(width 0)
				(type default)
			)
			(fill no)
			(layer "F.CrtYd")
		)
		(fp_poly
			(pts
				(xy -1.016 -2.0066) (xy 1.016 -2.0066) (xy 1.016 2.3114) (xy -1.016 2.3114)
			)
			(stroke
				(width 0)
				(type default)
			)
			(fill no)
			(layer "F.Fab")
		)
		(pad "A" smd rect
			(at 0 -1.143 90)
			(size 0.5588 1.016)
			(layers "F.Cu" "F.Mask" "F.Paste")
			(net "SW_HDD_R34")
		)
		(pad "K" smd rect
			(at 0 1.143 90)
			(size 0.5588 1.016)
			(layers "F.Cu" "F.Mask" "F.Paste")
			(net "SW_HDD_N34")
		)
	)
	(footprint ""
		(layer "F.Cu")
		(at 141.097 -131.572 90)
		(property "Reference" "R452"
			(at 0 0 90)
			(layer "F.SilkS")
			(hide yes)
			(effects
				(font
					(size 1.27 1.27)
				)
			)
		)
		(property "Value" "4K7R2J-2-GP"
			(at 0.064008 -3.993896 90)
			(unlocked yes)
			(layer "F.Fab")
			(hide yes)
			(effects
				(font
					(size 1.016 1.016)
					(thickness 0.1524)
				)
			)
		)
		(property "Device Type" "R402H16"
			(at 0.064008 -5.517896 90)
			(unlocked yes)
			(layer "F.Fab")
			(hide yes)
			(effects
				(font
					(size 1.016 1.016)
					(thickness 0.1524)
				)
			)
		)
		(duplicate_pad_numbers_are_jumpers no)
		(fp_line
			(start 0.508 -0.9398)
			(end -0.508 -0.9398)
			(stroke
				(width 0.1524)
				(type default)
			)
			(layer "F.SilkS")
		)
		(fp_line
			(start -0.508 -0.9398)
			(end -0.508 0.9398)
			(stroke
				(width 0.1524)
				(type default)
			)
			(layer "F.SilkS")
		)
		(fp_rect
			(start -0.508 0.9398)
			(end 0.508 -0.9398)
			(stroke
				(width 0)
				(type default)
			)
			(fill no)
			(layer "F.CrtYd")
		)
		(fp_rect
			(start -0.508 0.9398)
			(end 0.508 -0.9398)
			(stroke
				(width 0)
				(type default)
			)
			(fill no)
			(layer "F.Fab")
		)
		(pad "1" smd custom
			(at 0 -0.4445 90)
			(size 0.1397 0.1397)
			(layers "F.Cu" "F.Mask" "F.Paste")
			(net "P12V_B")
			(options
				(clearance outline)
				(anchor circle)
			)
			(primitives
				(gr_poly
					(pts
						(arc
							(start -0.1778 -0.2794)
							(mid -0.249642 -0.249642)
							(end -0.2794 -0.1778)
						)
						(arc
							(start -0.2794 0.1778)
							(mid -0.249642 0.249642)
							(end -0.1778 0.2794)
						)
						(arc
							(start 0.1778 0.2794)
							(mid 0.249642 0.249642)
							(end 0.2794 0.1778)
						)
						(arc
							(start 0.2794 -0.1778)
							(mid 0.249642 -0.249642)
							(end 0.1778 -0.2794)
						)
					)
					(width 0)
					(fill yes)
				)
			)
		)
		(pad "2" smd custom
			(at 0 0.4445 90)
			(size 0.1397 0.1397)
			(layers "F.Cu" "F.Mask" "F.Paste")
			(net "SW_HDD_R16")
			(options
				(clearance outline)
				(anchor circle)
			)
			(primitives
				(gr_poly
					(pts
						(arc
							(start -0.1778 -0.2794)
							(mid -0.249642 -0.249642)
							(end -0.2794 -0.1778)
						)
						(arc
							(start -0.2794 0.1778)
							(mid -0.249642 0.249642)
							(end -0.1778 0.2794)
						)
						(arc
							(start 0.1778 0.2794)
							(mid 0.249642 0.249642)
							(end 0.2794 0.1778)
						)
						(arc
							(start 0.2794 -0.1778)
							(mid 0.249642 -0.249642)
							(end 0.1778 -0.2794)
						)
					)
					(width 0)
					(fill yes)
				)
			)
		)
	)
	(footprint ""
		(layer "F.Cu")
		(at 115.316 -256.286 180)
		(property "Reference" "Q10"
			(at 0 0 180)
			(layer "F.SilkS")
			(hide yes)
			(effects
				(font
					(size 1.27 1.27)
				)
			)
		)
		(property "Value" "AO4406AL-GP"
			(at -3.707384 -1.5367 180)
			(unlocked yes)
			(layer "F.Fab")
			(hide yes)
			(effects
				(font
					(size 1.016 1.016)
					(thickness 0.1524)
				)
			)
		)
		(property "Device Type" "SOIC8H69"
			(at -3.707384 -3.0607 180)
			(unlocked yes)
			(layer "F.Fab")
			(hide yes)
			(effects
				(font
					(size 1.016 1.016)
					(thickness 0.1524)
				)
			)
		)
		(duplicate_pad_numbers_are_jumpers no)
		(fp_line
			(start 2.1336 1.4224)
			(end 2.1336 -1.4224)
			(stroke
				(width 0.1524)
				(type default)
			)
			(layer "F.SilkS")
		)
		(fp_line
			(start 2.1336 -1.4224)
			(end -2.7432 -1.4224)
			(stroke
				(width 0.1524)
				(type default)
			)
			(layer "F.SilkS")
		)
		(fp_line
			(start -2.1844 -0.0508)
			(end -2.7178 0.508)
			(stroke
				(width 0.1524)
				(type default)
			)
			(layer "F.SilkS")
		)
		(fp_line
			(start -2.6289 3.4417)
			(end -2.6289 1.4732)
			(stroke
				(width 0.381)
				(type default)
			)
			(layer "F.SilkS")
		)
		(fp_line
			(start -2.7178 -0.508)
			(end -2.1844 -0.0508)
			(stroke
				(width 0.1524)
				(type default)
			)
			(layer "F.SilkS")
		)
		(fp_line
			(start -2.7432 1.4224)
			(end 2.1336 1.4224)
			(stroke
				(width 0.1524)
				(type default)
			)
			(layer "F.SilkS")
		)
		(fp_line
			(start -2.7432 1.4224)
			(end -2.6416 1.4224)
			(stroke
				(width 0.1524)
				(type default)
			)
			(layer "F.SilkS")
		)
		(fp_line
			(start -2.7432 -1.4224)
			(end -2.7432 1.4224)
			(stroke
				(width 0.1524)
				(type default)
			)
			(layer "F.SilkS")
		)
		(fp_poly
			(pts
				(xy -2.2098 -1.4224) (xy -2.2098 1.4224) (xy 2.2098 1.4224) (xy 2.2098 -1.4224)
			)
			(stroke
				(width 0)
				(type default)
			)
			(fill yes)
			(layer "F.SilkS")
		)
		(fp_rect
			(start -2.450084 2.999994)
			(end 2.450084 -2.999994)
			(stroke
				(width 0)
				(type default)
			)
			(fill no)
			(layer "F.CrtYd")
		)
		(fp_poly
			(pts
				(xy -2.8194 3.6322) (xy -2.8194 -3.6322) (xy 2.8194 -3.6322) (xy 2.8194 1.18364) (xy 2.450084 1.18364)
				(xy 2.450084 -2.999994) (xy -2.450084 -2.999994) (xy -2.450084 2.999994) (xy 2.450084 2.999994)
				(xy 2.450084 1.18618) (xy 2.8194 1.18618) (xy 2.8194 3.6322)
			)
			(stroke
				(width 0)
				(type default)
			)
			(fill no)
			(layer "F.CrtYd")
		)
		(fp_rect
			(start -2.8194 3.6322)
			(end 2.8194 -3.6322)
			(stroke
				(width 0)
				(type default)
			)
			(fill no)
			(layer "F.Fab")
		)
		(pad "1" smd rect
			(at -1.905 2.54 180)
			(size 0.635 1.651)
			(layers "F.Cu" "F.Mask" "F.Paste")
			(net "P5V_HDD3")
		)
		(pad "2" smd rect
			(at -0.635 2.54 180)
			(size 0.635 1.651)
			(layers "F.Cu" "F.Mask" "F.Paste")
			(net "P5V_HDD3")
		)
		(pad "3" smd rect
			(at 0.635 2.54 180)
			(size 0.635 1.651)
			(layers "F.Cu" "F.Mask" "F.Paste")
			(net "P5V_HDD3")
		)
		(pad "4" smd rect
			(at 1.905 2.54 180)
			(size 0.635 1.651)
			(layers "F.Cu" "F.Mask" "F.Paste")
			(net "SW_HDD_P3")
		)
		(pad "5" smd rect
			(at 1.905 -2.54 180)
			(size 0.635 1.651)
			(layers "F.Cu" "F.Mask" "F.Paste")
			(net "P5V_B_1")
		)
		(pad "6" smd rect
			(at 0.635 -2.54 180)
			(size 0.635 1.651)
			(layers "F.Cu" "F.Mask" "F.Paste")
			(net "P5V_B_1")
		)
		(pad "7" smd rect
			(at -0.635 -2.54 180)
			(size 0.635 1.651)
			(layers "F.Cu" "F.Mask" "F.Paste")
			(net "P5V_B_1")
		)
		(pad "8" smd rect
			(at -1.905 -2.54 180)
			(size 0.635 1.651)
			(layers "F.Cu" "F.Mask" "F.Paste")
			(net "P5V_B_1")
		)
	)
	(footprint ""
		(layer "F.Cu")
		(at 207.3148 -199.517 -90)
		(property "Reference" "R29"
			(at 0 0 270)
			(layer "F.SilkS")
			(hide yes)
			(effects
				(font
					(size 1.27 1.27)
				)
			)
		)
		(property "Value" "4K7R2F-GP"
			(at 0.064008 -3.993896 270)
			(unlocked yes)
			(layer "F.Fab")
			(hide yes)
			(effects
				(font
					(size 1.016 1.016)
					(thickness 0.1524)
				)
			)
		)
		(property "Device Type" "R402H16"
			(at 0.064008 -5.517896 270)
			(unlocked yes)
			(layer "F.Fab")
			(hide yes)
			(effects
				(font
					(size 1.016 1.016)
					(thickness 0.1524)
				)
			)
		)
		(duplicate_pad_numbers_are_jumpers no)
		(fp_line
			(start -0.508 -0.9398)
			(end -0.508 0.9398)
			(stroke
				(width 0.1524)
				(type default)
			)
			(layer "F.SilkS")
		)
		(fp_line
			(start 0.508 -0.9398)
			(end -0.508 -0.9398)
			(stroke
				(width 0.1524)
				(type default)
			)
			(layer "F.SilkS")
		)
		(fp_rect
			(start -0.508 0.9398)
			(end 0.508 -0.9398)
			(stroke
				(width 0)
				(type default)
			)
			(fill no)
			(layer "F.CrtYd")
		)
		(fp_rect
			(start -0.508 0.9398)
			(end 0.508 -0.9398)
			(stroke
				(width 0)
				(type default)
			)
			(fill no)
			(layer "F.Fab")
		)
		(pad "1" smd custom
			(at 0 -0.4445 270)
			(size 0.1397 0.1397)
			(layers "F.Cu" "F.Mask" "F.Paste")
			(net "IO_EXP2_HDD_FAULT_INT_N")
			(options
				(clearance outline)
				(anchor circle)
			)
			(primitives
				(gr_poly
					(pts
						(arc
							(start -0.1778 -0.2794)
							(mid -0.249642 -0.249642)
							(end -0.2794 -0.1778)
						)
						(arc
							(start -0.2794 0.1778)
							(mid -0.249642 0.249642)
							(end -0.1778 0.2794)
						)
						(arc
							(start 0.1778 0.2794)
							(mid 0.249642 0.249642)
							(end 0.2794 0.1778)
						)
						(arc
							(start 0.2794 -0.1778)
							(mid 0.249642 -0.249642)
							(end 0.1778 -0.2794)
						)
					)
					(width 0)
					(fill yes)
				)
			)
		)
		(pad "2" smd custom
			(at 0 0.4445 270)
			(size 0.1397 0.1397)
			(layers "F.Cu" "F.Mask" "F.Paste")
			(net "P3V3_STBY_B")
			(options
				(clearance outline)
				(anchor circle)
			)
			(primitives
				(gr_poly
					(pts
						(arc
							(start -0.1778 -0.2794)
							(mid -0.249642 -0.249642)
							(end -0.2794 -0.1778)
						)
						(arc
							(start -0.2794 0.1778)
							(mid -0.249642 0.249642)
							(end -0.1778 0.2794)
						)
						(arc
							(start 0.1778 0.2794)
							(mid 0.249642 0.249642)
							(end 0.2794 0.1778)
						)
						(arc
							(start 0.2794 -0.1778)
							(mid 0.249642 -0.249642)
							(end 0.1778 -0.2794)
						)
					)
					(width 0)
					(fill yes)
				)
			)
		)
	)
	(footprint ""
		(layer "F.Cu")
		(at 66.802 -148.082 -90)
		(property "Reference" "R369"
			(at 0 0 270)
			(layer "F.SilkS")
			(hide yes)
			(effects
				(font
					(size 1.27 1.27)
				)
			)
		)
		(property "Value" "10KR2F-2-GP"
			(at 0.064008 -3.993896 270)
			(unlocked yes)
			(layer "F.Fab")
			(hide yes)
			(effects
				(font
					(size 1.016 1.016)
					(thickness 0.1524)
				)
			)
		)
		(property "Device Type" "R402H16"
			(at 0.064008 -5.517896 270)
			(unlocked yes)
			(layer "F.Fab")
			(hide yes)
			(effects
				(font
					(size 1.016 1.016)
					(thickness 0.1524)
				)
			)
		)
		(duplicate_pad_numbers_are_jumpers no)
		(fp_line
			(start -0.508 -0.9398)
			(end -0.508 0.9398)
			(stroke
				(width 0.1524)
				(type default)
			)
			(layer "F.SilkS")
		)
		(fp_line
			(start 0.508 -0.9398)
			(end -0.508 -0.9398)
			(stroke
				(width 0.1524)
				(type default)
			)
			(layer "F.SilkS")
		)
		(fp_rect
			(start -0.508 0.9398)
			(end 0.508 -0.9398)
			(stroke
				(width 0)
				(type default)
			)
			(fill no)
			(layer "F.CrtYd")
		)
		(fp_rect
			(start -0.508 0.9398)
			(end 0.508 -0.9398)
			(stroke
				(width 0)
				(type default)
			)
			(fill no)
			(layer "F.Fab")
		)
		(pad "1" smd custom
			(at 0 -0.4445 270)
			(size 0.1397 0.1397)
			(layers "F.Cu" "F.Mask" "F.Paste")
			(net "P3V3_STBY_B")
			(options
				(clearance outline)
				(anchor circle)
			)
			(primitives
				(gr_poly
					(pts
						(arc
							(start -0.1778 -0.2794)
							(mid -0.249642 -0.249642)
							(end -0.2794 -0.1778)
						)
						(arc
							(start -0.2794 0.1778)
							(mid -0.249642 0.249642)
							(end -0.1778 0.2794)
						)
						(arc
							(start 0.1778 0.2794)
							(mid 0.249642 0.249642)
							(end 0.2794 0.1778)
						)
						(arc
							(start 0.2794 -0.1778)
							(mid 0.249642 -0.249642)
							(end 0.1778 -0.2794)
						)
					)
					(width 0)
					(fill yes)
				)
			)
		)
		(pad "2" smd custom
			(at 0 0.4445 270)
			(size 0.1397 0.1397)
			(layers "F.Cu" "F.Mask" "F.Paste")
			(net "HDD_PRSNT_13")
			(options
				(clearance outline)
				(anchor circle)
			)
			(primitives
				(gr_poly
					(pts
						(arc
							(start -0.1778 -0.2794)
							(mid -0.249642 -0.249642)
							(end -0.2794 -0.1778)
						)
						(arc
							(start -0.2794 0.1778)
							(mid -0.249642 0.249642)
							(end -0.1778 0.2794)
						)
						(arc
							(start 0.1778 0.2794)
							(mid 0.249642 0.249642)
							(end 0.2794 0.1778)
						)
						(arc
							(start 0.2794 -0.1778)
							(mid 0.249642 -0.249642)
							(end 0.1778 -0.2794)
						)
					)
					(width 0)
					(fill yes)
				)
			)
		)
	)
	(footprint ""
		(layer "F.Cu")
		(at 428.117 -44.958 180)
		(property "Reference" "C465"
			(at 0 0 180)
			(layer "F.SilkS")
			(hide yes)
			(effects
				(font
					(size 1.27 1.27)
				)
			)
		)
		(property "Value" "SC4D7U25V5KX-1-GP"
			(at -0.0762 -6.1214 180)
			(unlocked yes)
			(layer "F.Fab")
			(hide yes)
			(effects
				(font
					(size 1.016 1.016)
					(thickness 0.1524)
				)
			)
		)
		(property "Device Type" "C805H58"
			(at -0.0762 -8.1534 180)
			(unlocked yes)
			(layer "F.Fab")
			(hide yes)
			(effects
				(font
					(size 1.016 1.016)
					(thickness 0.1524)
				)
			)
		)
		(duplicate_pad_numbers_are_jumpers no)
		(fp_line
			(start 0.635 0)
			(end -0.635 0)
			(stroke
				(width 0.508)
				(type default)
			)
			(layer "F.SilkS")
		)
		(fp_rect
			(start -0.9652 1.778)
			(end 0.9652 -1.778)
			(stroke
				(width 0)
				(type default)
			)
			(fill no)
			(layer "F.CrtYd")
		)
		(fp_poly
			(pts
				(xy -0.9652 -1.778) (xy 0.9652 -1.778) (xy 0.9652 1.778) (xy -0.9652 1.778)
			)
			(stroke
				(width 0)
				(type default)
			)
			(fill no)
			(layer "F.Fab")
		)
		(pad "1" smd rect
			(at 0 -0.9652 180)
			(size 1.397 1.143)
			(layers "F.Cu" "F.Mask" "F.Paste")
			(net "P12V_HDD33")
		)
		(pad "2" smd rect
			(at 0 0.9652 180)
			(size 1.397 1.143)
			(layers "F.Cu" "F.Mask" "F.Paste")
			(net "GND")
		)
	)
	(footprint ""
		(layer "F.Cu")
		(at 261.153148 -215.700356 -90)
		(property "Reference" "R164"
			(at 0 0 270)
			(layer "F.SilkS")
			(hide yes)
			(effects
				(font
					(size 1.27 1.27)
				)
			)
		)
		(property "Value" "4K7R2F-GP"
			(at 0.064008 -3.993896 270)
			(unlocked yes)
			(layer "F.Fab")
			(hide yes)
			(effects
				(font
					(size 1.016 1.016)
					(thickness 0.1524)
				)
			)
		)
		(property "Device Type" "R402H16"
			(at 0.064008 -5.517896 270)
			(unlocked yes)
			(layer "F.Fab")
			(hide yes)
			(effects
				(font
					(size 1.016 1.016)
					(thickness 0.1524)
				)
			)
		)
		(duplicate_pad_numbers_are_jumpers no)
		(fp_line
			(start -0.508 -0.9398)
			(end -0.508 0.9398)
			(stroke
				(width 0.1524)
				(type default)
			)
			(layer "F.SilkS")
		)
		(fp_line
			(start 0.508 -0.9398)
			(end -0.508 -0.9398)
			(stroke
				(width 0.1524)
				(type default)
			)
			(layer "F.SilkS")
		)
		(fp_rect
			(start -0.508 0.9398)
			(end 0.508 -0.9398)
			(stroke
				(width 0)
				(type default)
			)
			(fill no)
			(layer "F.CrtYd")
		)
		(fp_rect
			(start -0.508 0.9398)
			(end 0.508 -0.9398)
			(stroke
				(width 0)
				(type default)
			)
			(fill no)
			(layer "F.Fab")
		)
		(pad "1" smd custom
			(at 0 -0.4445 270)
			(size 0.1397 0.1397)
			(layers "F.Cu" "F.Mask" "F.Paste")
			(net "VOL_SEN_ADDR1")
			(options
				(clearance outline)
				(anchor circle)
			)
			(primitives
				(gr_poly
					(pts
						(arc
							(start -0.1778 -0.2794)
							(mid -0.249642 -0.249642)
							(end -0.2794 -0.1778)
						)
						(arc
							(start -0.2794 0.1778)
							(mid -0.249642 0.249642)
							(end -0.1778 0.2794)
						)
						(arc
							(start 0.1778 0.2794)
							(mid 0.249642 0.249642)
							(end 0.2794 0.1778)
						)
						(arc
							(start 0.2794 -0.1778)
							(mid 0.249642 -0.249642)
							(end 0.1778 -0.2794)
						)
					)
					(width 0)
					(fill yes)
				)
			)
		)
		(pad "2" smd custom
			(at 0 0.4445 270)
			(size 0.1397 0.1397)
			(layers "F.Cu" "F.Mask" "F.Paste")
			(net "GND")
			(options
				(clearance outline)
				(anchor circle)
			)
			(primitives
				(gr_poly
					(pts
						(arc
							(start -0.1778 -0.2794)
							(mid -0.249642 -0.249642)
							(end -0.2794 -0.1778)
						)
						(arc
							(start -0.2794 0.1778)
							(mid -0.249642 0.249642)
							(end -0.1778 0.2794)
						)
						(arc
							(start 0.1778 0.2794)
							(mid 0.249642 0.249642)
							(end 0.2794 0.1778)
						)
						(arc
							(start 0.2794 -0.1778)
							(mid 0.249642 -0.249642)
							(end 0.1778 -0.2794)
						)
					)
					(width 0)
					(fill yes)
				)
			)
		)
	)
	(footprint ""
		(layer "F.Cu")
		(at 95.563436 -244.660674 90)
		(property "Reference" "C55"
			(at 0 0 90)
			(layer "F.SilkS")
			(hide yes)
			(effects
				(font
					(size 1.27 1.27)
				)
			)
		)
		(property "Value" "SCD01U16V1KX-GP"
			(at -2.8321 -1.7399 90)
			(unlocked yes)
			(layer "F.Fab")
			(hide yes)
			(effects
				(font
					(size 1.016 1.016)
					(thickness 0.1524)
				)
			)
		)
		(property "Device Type" "C0201H13"
			(at -2.8321 -3.2639 90)
			(unlocked yes)
			(layer "F.Fab")
			(hide yes)
			(effects
				(font
					(size 1.016 1.016)
					(thickness 0.1524)
				)
			)
		)
		(duplicate_pad_numbers_are_jumpers no)
		(fp_rect
			(start -0.2794 0.6477)
			(end 0.2794 -0.6477)
			(stroke
				(width 0)
				(type default)
			)
			(fill no)
			(layer "F.CrtYd")
		)
		(fp_rect
			(start -0.2794 0.6477)
			(end 0.2794 -0.6477)
			(stroke
				(width 0)
				(type default)
			)
			(fill no)
			(layer "F.Fab")
		)
		(pad "1" smd custom
			(at 0 -0.2794 90)
			(size 0.0762 0.0762)
			(layers "F.Cu" "F.Mask" "F.Paste")
			(net "SAS_HDD_RX_P2")
			(options
				(clearance outline)
				(anchor circle)
			)
			(primitives
				(gr_poly
					(pts
						(arc
							(start 0.1524 -0.127)
							(mid 0.137521 -0.162921)
							(end 0.1016 -0.1778)
						)
						(arc
							(start -0.1016 -0.1778)
							(mid -0.137521 -0.162921)
							(end -0.1524 -0.127)
						)
						(arc
							(start -0.1524 0.127)
							(mid -0.137521 0.162921)
							(end -0.1016 0.1778)
						)
						(arc
							(start 0.1016 0.1778)
							(mid 0.137521 0.162921)
							(end 0.1524 0.127)
						)
					)
					(width 0)
					(fill yes)
				)
			)
		)
		(pad "2" smd custom
			(at 0 0.2794 90)
			(size 0.0762 0.0762)
			(layers "F.Cu" "F.Mask" "F.Paste")
			(net "PHY_SCC_B_TO_DRV_B_2_DP")
			(options
				(clearance outline)
				(anchor circle)
			)
			(primitives
				(gr_poly
					(pts
						(arc
							(start 0.1524 -0.127)
							(mid 0.137521 -0.162921)
							(end 0.1016 -0.1778)
						)
						(arc
							(start -0.1016 -0.1778)
							(mid -0.137521 -0.162921)
							(end -0.1524 -0.127)
						)
						(arc
							(start -0.1524 0.127)
							(mid -0.137521 0.162921)
							(end -0.1016 0.1778)
						)
						(arc
							(start 0.1016 0.1778)
							(mid 0.137521 0.162921)
							(end 0.1524 0.127)
						)
					)
					(width 0)
					(fill yes)
				)
			)
		)
	)
	(footprint ""
		(layer "F.Cu")
		(at 47.173896 -117.74551 -90)
		(property "Reference" "R1126"
			(at 0 0 270)
			(layer "F.SilkS")
			(hide yes)
			(effects
				(font
					(size 1.27 1.27)
				)
			)
		)
		(property "Value" "200KR2F-L-GP"
			(at 0.064008 -3.993896 270)
			(unlocked yes)
			(layer "F.Fab")
			(hide yes)
			(effects
				(font
					(size 1.016 1.016)
					(thickness 0.1524)
				)
			)
		)
		(property "Device Type" "R402H16"
			(at 0.064008 -5.517896 270)
			(unlocked yes)
			(layer "F.Fab")
			(hide yes)
			(effects
				(font
					(size 1.016 1.016)
					(thickness 0.1524)
				)
			)
		)
		(duplicate_pad_numbers_are_jumpers no)
		(fp_line
			(start -0.508 -0.9398)
			(end -0.508 0.9398)
			(stroke
				(width 0.1524)
				(type default)
			)
			(layer "F.SilkS")
		)
		(fp_line
			(start 0.508 -0.9398)
			(end -0.508 -0.9398)
			(stroke
				(width 0.1524)
				(type default)
			)
			(layer "F.SilkS")
		)
		(fp_rect
			(start -0.508 0.9398)
			(end 0.508 -0.9398)
			(stroke
				(width 0)
				(type default)
			)
			(fill no)
			(layer "F.CrtYd")
		)
		(fp_rect
			(start -0.508 0.9398)
			(end 0.508 -0.9398)
			(stroke
				(width 0)
				(type default)
			)
			(fill no)
			(layer "F.Fab")
		)
		(pad "1" smd custom
			(at 0 -0.4445 270)
			(size 0.1397 0.1397)
			(layers "F.Cu" "F.Mask" "F.Paste")
			(net "P5V_B_2_MODE")
			(options
				(clearance outline)
				(anchor circle)
			)
			(primitives
				(gr_poly
					(pts
						(arc
							(start -0.1778 -0.2794)
							(mid -0.249642 -0.249642)
							(end -0.2794 -0.1778)
						)
						(arc
							(start -0.2794 0.1778)
							(mid -0.249642 0.249642)
							(end -0.1778 0.2794)
						)
						(arc
							(start 0.1778 0.2794)
							(mid 0.249642 0.249642)
							(end 0.2794 0.1778)
						)
						(arc
							(start 0.2794 -0.1778)
							(mid 0.249642 -0.249642)
							(end 0.1778 -0.2794)
						)
					)
					(width 0)
					(fill yes)
				)
			)
		)
		(pad "2" smd custom
			(at 0 0.4445 270)
			(size 0.1397 0.1397)
			(layers "F.Cu" "F.Mask" "F.Paste")
			(net "P5V_B_2_PGOOD")
			(options
				(clearance outline)
				(anchor circle)
			)
			(primitives
				(gr_poly
					(pts
						(arc
							(start -0.1778 -0.2794)
							(mid -0.249642 -0.249642)
							(end -0.2794 -0.1778)
						)
						(arc
							(start -0.2794 0.1778)
							(mid -0.249642 0.249642)
							(end -0.1778 0.2794)
						)
						(arc
							(start 0.1778 0.2794)
							(mid 0.249642 0.249642)
							(end 0.2794 0.1778)
						)
						(arc
							(start 0.2794 -0.1778)
							(mid 0.249642 -0.249642)
							(end 0.1778 -0.2794)
						)
					)
					(width 0)
					(fill yes)
				)
			)
		)
	)
	(footprint ""
		(layer "F.Cu")
		(at 181.991 -160.401 180)
		(property "Reference" "C256"
			(at 0 0 180)
			(layer "F.SilkS")
			(hide yes)
			(effects
				(font
					(size 1.27 1.27)
				)
			)
		)
		(property "Value" "SC1U25V3KX-GP"
			(at 0 -2.8194 180)
			(unlocked yes)
			(layer "F.Fab")
			(hide yes)
			(effects
				(font
					(size 1.016 1.016)
					(thickness 0.1524)
				)
			)
		)
		(property "Device Type" "C603H36"
			(at 0 -4.3434 180)
			(unlocked yes)
			(layer "F.Fab")
			(hide yes)
			(effects
				(font
					(size 1.016 1.016)
					(thickness 0.1524)
				)
			)
		)
		(duplicate_pad_numbers_are_jumpers no)
		(fp_line
			(start 0.508 0)
			(end -0.508 0)
			(stroke
				(width 0.2032)
				(type default)
			)
			(layer "F.SilkS")
		)
		(fp_rect
			(start -0.5842 1.3335)
			(end 0.5842 -1.3335)
			(stroke
				(width 0)
				(type default)
			)
			(fill no)
			(layer "F.CrtYd")
		)
		(fp_rect
			(start -0.5842 1.3335)
			(end 0.5842 -1.3335)
			(stroke
				(width 0)
				(type default)
			)
			(fill no)
			(layer "F.Fab")
		)
		(pad "1" smd custom
			(at 0 -0.762 180)
			(size 0.2159 0.2159)
			(layers "F.Cu" "F.Mask" "F.Paste")
			(net "P12V_HDD17")
			(options
				(clearance outline)
				(anchor circle)
			)
			(primitives
				(gr_poly
					(pts
						(arc
							(start -0.3302 -0.4318)
							(mid -0.402042 -0.402042)
							(end -0.4318 -0.3302)
						)
						(arc
							(start -0.4318 0.3302)
							(mid -0.402042 0.402042)
							(end -0.3302 0.4318)
						)
						(arc
							(start 0.3302 0.4318)
							(mid 0.402042 0.402042)
							(end 0.4318 0.3302)
						)
						(arc
							(start 0.4318 -0.3302)
							(mid 0.402042 -0.402042)
							(end 0.3302 -0.4318)
						)
					)
					(width 0)
					(fill yes)
				)
			)
		)
		(pad "2" smd custom
			(at 0 0.762 180)
			(size 0.2159 0.2159)
			(layers "F.Cu" "F.Mask" "F.Paste")
			(net "GND")
			(options
				(clearance outline)
				(anchor circle)
			)
			(primitives
				(gr_poly
					(pts
						(arc
							(start -0.3302 -0.4318)
							(mid -0.402042 -0.402042)
							(end -0.4318 -0.3302)
						)
						(arc
							(start -0.4318 0.3302)
							(mid -0.402042 0.402042)
							(end -0.3302 0.4318)
						)
						(arc
							(start 0.3302 0.4318)
							(mid 0.402042 0.402042)
							(end 0.4318 0.3302)
						)
						(arc
							(start 0.4318 -0.3302)
							(mid 0.402042 -0.402042)
							(end 0.3302 -0.4318)
						)
					)
					(width 0)
					(fill yes)
				)
			)
		)
	)
	(footprint ""
		(layer "F.Cu")
		(at 453.837802 -226.57435 -90)
		(property "Reference" "R1151"
			(at 0 0 270)
			(layer "F.SilkS")
			(hide yes)
			(effects
				(font
					(size 1.27 1.27)
				)
			)
		)
		(property "Value" "309KR2F-GP"
			(at 0.064008 -3.993896 270)
			(unlocked yes)
			(layer "F.Fab")
			(hide yes)
			(effects
				(font
					(size 1.016 1.016)
					(thickness 0.1524)
				)
			)
		)
		(property "Device Type" "R402H16"
			(at 0.064008 -5.517896 270)
			(unlocked yes)
			(layer "F.Fab")
			(hide yes)
			(effects
				(font
					(size 1.016 1.016)
					(thickness 0.1524)
				)
			)
		)
		(duplicate_pad_numbers_are_jumpers no)
		(fp_line
			(start -0.508 -0.9398)
			(end -0.508 0.9398)
			(stroke
				(width 0.1524)
				(type default)
			)
			(layer "F.SilkS")
		)
		(fp_line
			(start 0.508 -0.9398)
			(end -0.508 -0.9398)
			(stroke
				(width 0.1524)
				(type default)
			)
			(layer "F.SilkS")
		)
		(fp_rect
			(start -0.508 0.9398)
			(end 0.508 -0.9398)
			(stroke
				(width 0)
				(type default)
			)
			(fill no)
			(layer "F.CrtYd")
		)
		(fp_rect
			(start -0.508 0.9398)
			(end 0.508 -0.9398)
			(stroke
				(width 0)
				(type default)
			)
			(fill no)
			(layer "F.Fab")
		)
		(pad "1" smd custom
			(at 0 -0.4445 270)
			(size 0.1397 0.1397)
			(layers "F.Cu" "F.Mask" "F.Paste")
			(net "P5V_B_3_RF")
			(options
				(clearance outline)
				(anchor circle)
			)
			(primitives
				(gr_poly
					(pts
						(arc
							(start -0.1778 -0.2794)
							(mid -0.249642 -0.249642)
							(end -0.2794 -0.1778)
						)
						(arc
							(start -0.2794 0.1778)
							(mid -0.249642 0.249642)
							(end -0.1778 0.2794)
						)
						(arc
							(start 0.1778 0.2794)
							(mid 0.249642 0.249642)
							(end 0.2794 0.1778)
						)
						(arc
							(start 0.2794 -0.1778)
							(mid 0.249642 -0.249642)
							(end 0.1778 -0.2794)
						)
					)
					(width 0)
					(fill yes)
				)
			)
		)
		(pad "2" smd custom
			(at 0 0.4445 270)
			(size 0.1397 0.1397)
			(layers "F.Cu" "F.Mask" "F.Paste")
			(net "P5V_B_3_VREG")
			(options
				(clearance outline)
				(anchor circle)
			)
			(primitives
				(gr_poly
					(pts
						(arc
							(start -0.1778 -0.2794)
							(mid -0.249642 -0.249642)
							(end -0.2794 -0.1778)
						)
						(arc
							(start -0.2794 0.1778)
							(mid -0.249642 0.249642)
							(end -0.1778 0.2794)
						)
						(arc
							(start 0.1778 0.2794)
							(mid 0.249642 0.249642)
							(end 0.2794 0.1778)
						)
						(arc
							(start 0.2794 -0.1778)
							(mid 0.249642 -0.249642)
							(end 0.1778 -0.2794)
						)
					)
					(width 0)
					(fill yes)
				)
			)
		)
	)
	(footprint ""
		(layer "F.Cu")
		(at 19.37766 -222.048324 90)
		(property "Reference" "C622"
			(at 0 0 90)
			(layer "F.SilkS")
			(hide yes)
			(effects
				(font
					(size 1.27 1.27)
				)
			)
		)
		(property "Value" "SC10U16V5KX-7-GP-U"
			(at -0.0762 -6.1214 90)
			(unlocked yes)
			(layer "F.Fab")
			(hide yes)
			(effects
				(font
					(size 1.016 1.016)
					(thickness 0.1524)
				)
			)
		)
		(property "Device Type" "C805H58"
			(at -0.0762 -8.1534 90)
			(unlocked yes)
			(layer "F.Fab")
			(hide yes)
			(effects
				(font
					(size 1.016 1.016)
					(thickness 0.1524)
				)
			)
		)
		(duplicate_pad_numbers_are_jumpers no)
		(fp_line
			(start 0.635 0)
			(end -0.635 0)
			(stroke
				(width 0.508)
				(type default)
			)
			(layer "F.SilkS")
		)
		(fp_rect
			(start -0.9652 1.778)
			(end 0.9652 -1.778)
			(stroke
				(width 0)
				(type default)
			)
			(fill no)
			(layer "F.CrtYd")
		)
		(fp_poly
			(pts
				(xy -0.9652 -1.778) (xy 0.9652 -1.778) (xy 0.9652 1.778) (xy -0.9652 1.778)
			)
			(stroke
				(width 0)
				(type default)
			)
			(fill no)
			(layer "F.Fab")
		)
		(pad "1" smd rect
			(at 0 -0.9652 90)
			(size 1.397 1.143)
			(layers "F.Cu" "F.Mask" "F.Paste")
			(net "P12V_B_1_VIN_U31")
		)
		(pad "2" smd rect
			(at 0 0.9652 90)
			(size 1.397 1.143)
			(layers "F.Cu" "F.Mask" "F.Paste")
			(net "GND")
		)
	)
	(footprint ""
		(layer "F.Cu")
		(at 247.000522 -364.845346 -90)
		(property "Reference" "C555"
			(at 0 0 270)
			(layer "F.SilkS")
			(hide yes)
			(effects
				(font
					(size 1.27 1.27)
				)
			)
		)
		(property "Value" "SC1U25V3KX-GP"
			(at 0 -2.8194 270)
			(unlocked yes)
			(layer "F.Fab")
			(hide yes)
			(effects
				(font
					(size 1.016 1.016)
					(thickness 0.1524)
				)
			)
		)
		(property "Device Type" "C603H36"
			(at 0 -4.3434 270)
			(unlocked yes)
			(layer "F.Fab")
			(hide yes)
			(effects
				(font
					(size 1.016 1.016)
					(thickness 0.1524)
				)
			)
		)
		(duplicate_pad_numbers_are_jumpers no)
		(fp_line
			(start 0.508 0)
			(end -0.508 0)
			(stroke
				(width 0.2032)
				(type default)
			)
			(layer "F.SilkS")
		)
		(fp_rect
			(start -0.5842 1.3335)
			(end 0.5842 -1.3335)
			(stroke
				(width 0)
				(type default)
			)
			(fill no)
			(layer "F.CrtYd")
		)
		(fp_rect
			(start -0.5842 1.3335)
			(end 0.5842 -1.3335)
			(stroke
				(width 0)
				(type default)
			)
			(fill no)
			(layer "F.Fab")
		)
		(pad "1" smd custom
			(at 0 -0.762 270)
			(size 0.2159 0.2159)
			(layers "F.Cu" "F.Mask" "F.Paste")
			(net "MB3_P12V_HS")
			(options
				(clearance outline)
				(anchor circle)
			)
			(primitives
				(gr_poly
					(pts
						(arc
							(start -0.3302 -0.4318)
							(mid -0.402042 -0.402042)
							(end -0.4318 -0.3302)
						)
						(arc
							(start -0.4318 0.3302)
							(mid -0.402042 0.402042)
							(end -0.3302 0.4318)
						)
						(arc
							(start 0.3302 0.4318)
							(mid 0.402042 0.402042)
							(end 0.4318 0.3302)
						)
						(arc
							(start 0.4318 -0.3302)
							(mid 0.402042 -0.402042)
							(end 0.3302 -0.4318)
						)
					)
					(width 0)
					(fill yes)
				)
			)
		)
		(pad "2" smd custom
			(at 0 0.762 270)
			(size 0.2159 0.2159)
			(layers "F.Cu" "F.Mask" "F.Paste")
			(net "AGND_CURRENT_DPB")
			(options
				(clearance outline)
				(anchor circle)
			)
			(primitives
				(gr_poly
					(pts
						(arc
							(start -0.3302 -0.4318)
							(mid -0.402042 -0.402042)
							(end -0.4318 -0.3302)
						)
						(arc
							(start -0.4318 0.3302)
							(mid -0.402042 0.402042)
							(end -0.3302 0.4318)
						)
						(arc
							(start 0.3302 0.4318)
							(mid 0.402042 0.402042)
							(end 0.4318 0.3302)
						)
						(arc
							(start 0.4318 -0.3302)
							(mid 0.402042 -0.402042)
							(end 0.3302 -0.4318)
						)
					)
					(width 0)
					(fill yes)
				)
			)
		)
	)
	(footprint ""
		(layer "F.Cu")
		(at 208.90738 -235.18622 180)
		(property "Reference" "R36"
			(at 0 0 180)
			(layer "F.SilkS")
			(hide yes)
			(effects
				(font
					(size 1.27 1.27)
				)
			)
		)
		(property "Value" "4K7R2F-GP"
			(at 0.064008 -3.993896 180)
			(unlocked yes)
			(layer "F.Fab")
			(hide yes)
			(effects
				(font
					(size 1.016 1.016)
					(thickness 0.1524)
				)
			)
		)
		(property "Device Type" "R402H16"
			(at 0.064008 -5.517896 180)
			(unlocked yes)
			(layer "F.Fab")
			(hide yes)
			(effects
				(font
					(size 1.016 1.016)
					(thickness 0.1524)
				)
			)
		)
		(duplicate_pad_numbers_are_jumpers no)
		(fp_line
			(start 0.508 -0.9398)
			(end -0.508 -0.9398)
			(stroke
				(width 0.1524)
				(type default)
			)
			(layer "F.SilkS")
		)
		(fp_line
			(start -0.508 -0.9398)
			(end -0.508 0.9398)
			(stroke
				(width 0.1524)
				(type default)
			)
			(layer "F.SilkS")
		)
		(fp_rect
			(start -0.508 0.9398)
			(end 0.508 -0.9398)
			(stroke
				(width 0)
				(type default)
			)
			(fill no)
			(layer "F.CrtYd")
		)
		(fp_rect
			(start -0.508 0.9398)
			(end 0.508 -0.9398)
			(stroke
				(width 0)
				(type default)
			)
			(fill no)
			(layer "F.Fab")
		)
		(pad "1" smd custom
			(at 0 -0.4445 180)
			(size 0.1397 0.1397)
			(layers "F.Cu" "F.Mask" "F.Paste")
			(net "P3V3_STBY_B")
			(options
				(clearance outline)
				(anchor circle)
			)
			(primitives
				(gr_poly
					(pts
						(arc
							(start -0.1778 -0.2794)
							(mid -0.249642 -0.249642)
							(end -0.2794 -0.1778)
						)
						(arc
							(start -0.2794 0.1778)
							(mid -0.249642 0.249642)
							(end -0.1778 0.2794)
						)
						(arc
							(start 0.1778 0.2794)
							(mid 0.249642 0.249642)
							(end 0.2794 0.1778)
						)
						(arc
							(start 0.2794 -0.1778)
							(mid 0.249642 -0.249642)
							(end 0.1778 -0.2794)
						)
					)
					(width 0)
					(fill yes)
				)
			)
		)
		(pad "2" smd custom
			(at 0 0.4445 180)
			(size 0.1397 0.1397)
			(layers "F.Cu" "F.Mask" "F.Paste")
			(net "IO_EXP4_A0")
			(options
				(clearance outline)
				(anchor circle)
			)
			(primitives
				(gr_poly
					(pts
						(arc
							(start -0.1778 -0.2794)
							(mid -0.249642 -0.249642)
							(end -0.2794 -0.1778)
						)
						(arc
							(start -0.2794 0.1778)
							(mid -0.249642 0.249642)
							(end -0.1778 0.2794)
						)
						(arc
							(start 0.1778 0.2794)
							(mid 0.249642 0.249642)
							(end 0.2794 0.1778)
						)
						(arc
							(start 0.2794 -0.1778)
							(mid 0.249642 -0.249642)
							(end 0.1778 -0.2794)
						)
					)
					(width 0)
					(fill yes)
				)
			)
		)
	)
	(footprint ""
		(layer "F.Cu")
		(at 433.737004 -360.299)
		(property "Reference" "R971"
			(at 0 0 0)
			(layer "F.SilkS")
			(hide yes)
			(effects
				(font
					(size 1.27 1.27)
				)
			)
		)
		(property "Value" "4K7R2J-2-GP"
			(at 0.064008 -3.993896 0)
			(unlocked yes)
			(layer "F.Fab")
			(hide yes)
			(effects
				(font
					(size 1.016 1.016)
					(thickness 0.1524)
				)
			)
		)
		(property "Device Type" "R402H16"
			(at 0.064008 -5.517896 0)
			(unlocked yes)
			(layer "F.Fab")
			(hide yes)
			(effects
				(font
					(size 1.016 1.016)
					(thickness 0.1524)
				)
			)
		)
		(duplicate_pad_numbers_are_jumpers no)
		(fp_line
			(start -0.508 -0.9398)
			(end -0.508 0.9398)
			(stroke
				(width 0.1524)
				(type default)
			)
			(layer "F.SilkS")
		)
		(fp_line
			(start 0.508 -0.9398)
			(end -0.508 -0.9398)
			(stroke
				(width 0.1524)
				(type default)
			)
			(layer "F.SilkS")
		)
		(fp_rect
			(start -0.508 0.9398)
			(end 0.508 -0.9398)
			(stroke
				(width 0)
				(type default)
			)
			(fill no)
			(layer "F.CrtYd")
		)
		(fp_rect
			(start -0.508 0.9398)
			(end 0.508 -0.9398)
			(stroke
				(width 0)
				(type default)
			)
			(fill no)
			(layer "F.Fab")
		)
		(pad "1" smd custom
			(at 0 -0.4445)
			(size 0.1397 0.1397)
			(layers "F.Cu" "F.Mask" "F.Paste")
			(net "P12V_IN")
			(options
				(clearance outline)
				(anchor circle)
			)
			(primitives
				(gr_poly
					(pts
						(arc
							(start -0.1778 -0.2794)
							(mid -0.249642 -0.249642)
							(end -0.2794 -0.1778)
						)
						(arc
							(start -0.2794 0.1778)
							(mid -0.249642 0.249642)
							(end -0.1778 0.2794)
						)
						(arc
							(start 0.1778 0.2794)
							(mid 0.249642 0.249642)
							(end 0.2794 0.1778)
						)
						(arc
							(start 0.2794 -0.1778)
							(mid 0.249642 -0.249642)
							(end 0.1778 -0.2794)
						)
					)
					(width 0)
					(fill yes)
				)
			)
		)
		(pad "2" smd custom
			(at 0 0.4445)
			(size 0.1397 0.1397)
			(layers "F.Cu" "F.Mask" "F.Paste")
			(net "GATE_FAN3")
			(options
				(clearance outline)
				(anchor circle)
			)
			(primitives
				(gr_poly
					(pts
						(arc
							(start -0.1778 -0.2794)
							(mid -0.249642 -0.249642)
							(end -0.2794 -0.1778)
						)
						(arc
							(start -0.2794 0.1778)
							(mid -0.249642 0.249642)
							(end -0.1778 0.2794)
						)
						(arc
							(start 0.1778 0.2794)
							(mid 0.249642 0.249642)
							(end 0.2794 0.1778)
						)
						(arc
							(start 0.2794 -0.1778)
							(mid 0.249642 -0.249642)
							(end 0.1778 -0.2794)
						)
					)
					(width 0)
					(fill yes)
				)
			)
		)
	)
	(footprint ""
		(layer "F.Cu")
		(at 122.849894 -143.91005 -90)
		(property "Reference" "HDDSAS15"
			(at 0 0 270)
			(layer "F.SilkS")
			(hide yes)
			(effects
				(font
					(size 1.27 1.27)
				)
			)
		)
		(property "Value" "SKT-SAS15P-14P-45-GP"
			(at -20.7645 -8.9789 270)
			(unlocked yes)
			(layer "F.Fab")
			(hide yes)
			(effects
				(font
					(size 1.016 1.016)
					(thickness 0.1524)
				)
			)
		)
		(property "Device Type" "10120818-001C-TRLF"
			(at -20.7645 -10.5029 270)
			(unlocked yes)
			(layer "F.Fab")
			(hide yes)
			(effects
				(font
					(size 1.016 1.016)
					(thickness 0.1524)
				)
			)
		)
		(duplicate_pad_numbers_are_jumpers no)
		(fp_line
			(start 1.651 4.2926)
			(end 1.651 3.0099)
			(stroke
				(width 0.1524)
				(type default)
			)
			(layer "F.SilkS")
		)
		(fp_line
			(start 8.509 4.2926)
			(end 1.651 4.2926)
			(stroke
				(width 0.1524)
				(type default)
			)
			(layer "F.SilkS")
		)
		(fp_line
			(start -23.4188 3.0099)
			(end -23.4188 -3.2512)
			(stroke
				(width 0.1524)
				(type default)
			)
			(layer "F.SilkS")
		)
		(fp_line
			(start 1.651 3.0099)
			(end -23.4188 3.0099)
			(stroke
				(width 0.1524)
				(type default)
			)
			(layer "F.SilkS")
		)
		(fp_line
			(start 8.509 3.0099)
			(end 8.509 4.2926)
			(stroke
				(width 0.1524)
				(type default)
			)
			(layer "F.SilkS")
		)
		(fp_line
			(start 23.4188 3.0099)
			(end 8.509 3.0099)
			(stroke
				(width 0.1524)
				(type default)
			)
			(layer "F.SilkS")
		)
		(fp_line
			(start -23.4188 -3.2512)
			(end 23.4188 -3.2512)
			(stroke
				(width 0.1524)
				(type default)
			)
			(layer "F.SilkS")
		)
		(fp_line
			(start 23.4188 -3.2512)
			(end 23.4188 3.0099)
			(stroke
				(width 0.1524)
				(type default)
			)
			(layer "F.SilkS")
		)
		(fp_line
			(start 15.5067 -3.3401)
			(end 16.2687 -3.3401)
			(stroke
				(width 0.3302)
				(type default)
			)
			(layer "F.SilkS")
		)
		(fp_poly
			(pts
				(xy 15.868904 -3.230372) (xy 16.503904 -3.865372) (xy 15.233904 -3.865372)
			)
			(stroke
				(width 0)
				(type default)
			)
			(fill yes)
			(layer "F.SilkS")
		)
		(fp_poly
			(pts
				(xy -22.8727 -2.7559) (xy 22.8727 -2.7559) (xy 22.8727 2.7559) (xy 8.255 2.7559) (xy 8.255 3.5179)
				(xy 1.905 3.5179) (xy 1.905 2.7559) (xy -22.8727 2.7559)
			)
			(stroke
				(width 0)
				(type default)
			)
			(fill no)
			(layer "F.CrtYd")
		)
		(fp_poly
			(pts
				(xy 1.397 4.5466) (xy 1.397 3.2639) (xy -23.6728 3.2639) (xy -23.6728 -3.5052) (xy 23.6728 -3.5052)
				(xy 23.6728 -0.00635) (xy 22.8727 -0.00635) (xy 22.8727 -2.7559) (xy -22.8727 -2.7559) (xy -22.8727 2.7559)
				(xy 1.905 2.7559) (xy 1.905 3.5179) (xy 8.255 3.5179) (xy 8.255 2.7559) (xy 22.8727 2.7559) (xy 22.8727 0.00635)
				(xy 23.6728 0.00635) (xy 23.6728 3.2639) (xy 8.763 3.2639) (xy 8.763 4.5466)
			)
			(stroke
				(width 0)
				(type default)
			)
			(fill no)
			(layer "F.CrtYd")
		)
		(fp_poly
			(pts
				(xy 1.397 4.5466) (xy 1.397 3.2639) (xy -23.6728 3.2639) (xy -23.6728 -3.5052) (xy 23.6728 -3.5052)
				(xy 23.6728 3.2639) (xy 8.763 3.2639) (xy 8.763 4.5466)
			)
			(stroke
				(width 0)
				(type default)
			)
			(fill no)
			(layer "F.Fab")
		)
		(pad "" np_thru_hole circle
			(at -18.874994 0 270)
			(size 0.254 0.254)
			(drill 1.3462)
			(layers "*.Cu" "*.Mask")
			(clearance 0.9017)
			(thermal_gap 0.9017)
		)
		(pad "" np_thru_hole circle
			(at 18.874994 0 270)
			(size 0.254 0.254)
			(drill 0.9398)
			(layers "*.Cu" "*.Mask")
			(clearance 0.6985)
			(thermal_gap 0.6985)
		)
		(pad "G1" smd rect
			(at 21.874988 0 270)
			(size 2.5908 2.5908)
			(layers "F.Cu" "F.Mask" "F.Paste")
			(net "GND")
		)
		(pad "G2" smd rect
			(at -21.874988 0 270)
			(size 2.5908 2.5908)
			(layers "F.Cu" "F.Mask" "F.Paste")
			(net "GND")
		)
		(pad "P1" smd rect
			(at 1.905 -1.82499 270)
			(size 0.6096 2.3622)
			(layers "F.Cu" "F.Mask" "F.Paste")
			(net "Net_1729")
		)
		(pad "P2" smd rect
			(at 0.635 -1.82499 270)
			(size 0.6096 2.3622)
			(layers "F.Cu" "F.Mask" "F.Paste")
			(net "Net_1730")
		)
		(pad "P3" smd rect
			(at -0.635 -1.82499 270)
			(size 0.6096 2.3622)
			(layers "F.Cu" "F.Mask" "F.Paste")
			(net "Net_1731")
		)
		(pad "P4" smd rect
			(at -1.905 -1.82499 270)
			(size 0.6096 2.3622)
			(layers "F.Cu" "F.Mask" "F.Paste")
			(net "GND")
		)
		(pad "P5" smd rect
			(at -3.175 -1.82499 270)
			(size 0.6096 2.3622)
			(layers "F.Cu" "F.Mask" "F.Paste")
			(net "HDD_PRSNT_15")
		)
		(pad "P6" smd rect
			(at -4.445 -1.82499 270)
			(size 0.6096 2.3622)
			(layers "F.Cu" "F.Mask" "F.Paste")
			(net "GND")
		)
		(pad "P7" smd rect
			(at -5.715 -1.82499 270)
			(size 0.6096 2.3622)
			(layers "F.Cu" "F.Mask" "F.Paste")
			(net "5V_PRE_15")
		)
		(pad "P8" smd rect
			(at -6.985 -1.82499 270)
			(size 0.6096 2.3622)
			(layers "F.Cu" "F.Mask" "F.Paste")
			(net "P5V_HDD15")
		)
		(pad "P9" smd rect
			(at -8.255 -1.82499 270)
			(size 0.6096 2.3622)
			(layers "F.Cu" "F.Mask" "F.Paste")
			(net "P5V_HDD15")
		)
		(pad "P10" smd rect
			(at -9.525 -1.82499 270)
			(size 0.6096 2.3622)
			(layers "F.Cu" "F.Mask" "F.Paste")
			(net "GND")
		)
		(pad "P11" smd rect
			(at -10.795 -1.82499 270)
			(size 0.6096 2.3622)
			(layers "F.Cu" "F.Mask" "F.Paste")
			(net "ACT_HDD_15")
		)
		(pad "P12" smd rect
			(at -12.065 -1.82499 270)
			(size 0.6096 2.3622)
			(layers "F.Cu" "F.Mask" "F.Paste")
			(net "GND")
		)
		(pad "P13" smd rect
			(at -13.335 -1.82499 270)
			(size 0.6096 2.3622)
			(layers "F.Cu" "F.Mask" "F.Paste")
			(net "12V_PRE_15")
		)
		(pad "P14" smd rect
			(at -14.605 -1.82499 270)
			(size 0.6096 2.3622)
			(layers "F.Cu" "F.Mask" "F.Paste")
			(net "P12V_HDD15")
		)
		(pad "P15" smd rect
			(at -15.875 -1.82499 270)
			(size 0.6096 2.3622)
			(layers "F.Cu" "F.Mask" "F.Paste")
			(net "P12V_HDD15")
		)
		(pad "S1" smd rect
			(at 15.875 -1.82499 270)
			(size 0.6096 2.3622)
			(layers "F.Cu" "F.Mask" "F.Paste")
			(net "GND")
		)
		(pad "S2" smd rect
			(at 14.605 -1.82499 270)
			(size 0.6096 2.3622)
			(layers "F.Cu" "F.Mask" "F.Paste")
			(net "SAS_HDD_RX_P15")
		)
		(pad "S3" smd rect
			(at 13.335 -1.82499 270)
			(size 0.6096 2.3622)
			(layers "F.Cu" "F.Mask" "F.Paste")
			(net "SAS_HDD_RX_N15")
		)
		(pad "S4" smd rect
			(at 12.065 -1.82499 270)
			(size 0.6096 2.3622)
			(layers "F.Cu" "F.Mask" "F.Paste")
			(net "GND")
		)
		(pad "S5" smd rect
			(at 10.795 -1.82499 270)
			(size 0.6096 2.3622)
			(layers "F.Cu" "F.Mask" "F.Paste")
			(net "PHY_DRV_B_TO_SCC_B_15_DN")
		)
		(pad "S6" smd rect
			(at 9.525 -1.82499 270)
			(size 0.6096 2.3622)
			(layers "F.Cu" "F.Mask" "F.Paste")
			(net "PHY_DRV_B_TO_SCC_B_15_DP")
		)
		(pad "S7" smd rect
			(at 8.255 -1.82499 270)
			(size 0.6096 2.3622)
			(layers "F.Cu" "F.Mask" "F.Paste")
			(net "GND")
		)
		(pad "S8" smd rect
			(at 7.480046 2.845054 270)
			(size 0.508 2.3622)
			(layers "F.Cu" "F.Mask" "F.Paste")
			(net "GND")
		)
		(pad "S9" smd rect
			(at 6.679946 2.845054 270)
			(size 0.508 2.3622)
			(layers "F.Cu" "F.Mask" "F.Paste")
			(net "Net_438")
		)
		(pad "S10" smd rect
			(at 5.8801 2.845054 270)
			(size 0.508 2.3622)
			(layers "F.Cu" "F.Mask" "F.Paste")
			(net "Net_330")
		)
		(pad "S11" smd rect
			(at 5.08 2.845054 270)
			(size 0.508 2.3622)
			(layers "F.Cu" "F.Mask" "F.Paste")
			(net "GND")
		)
		(pad "S12" smd rect
			(at 4.2799 2.845054 270)
			(size 0.508 2.3622)
			(layers "F.Cu" "F.Mask" "F.Paste")
			(net "Net_366")
		)
		(pad "S13" smd rect
			(at 3.480054 2.845054 270)
			(size 0.508 2.3622)
			(layers "F.Cu" "F.Mask" "F.Paste")
			(net "Net_402")
		)
		(pad "S14" smd rect
			(at 2.679954 2.845054 270)
			(size 0.508 2.3622)
			(layers "F.Cu" "F.Mask" "F.Paste")
			(net "GND")
		)
		(zone
			(layer "F.Cu")
			(hatch none 0.5)
			(connect_pads
				(clearance 0)
			)
			(min_thickness 0.25)
			(keepout
				(tracks allowed)
				(vias not_allowed)
				(pads allowed)
				(copperpour not_allowed)
				(footprints allowed)
			)
			(placement
				(enabled no)
				(sheetname "")
			)
			(fill
				(thermal_gap 0.5)
				(thermal_bridge_width 0.5)
				(island_removal_mode 0)
			)
			(polygon
				(pts
					(xy 126.507494 -160.64865) (xy 119.433594 -160.64865) (xy 119.433594 -167.58285) (xy 120.538494 -167.58285)
					(xy 120.538494 -163.46805) (xy 125.161294 -163.46805) (xy 125.161294 -167.58285) (xy 126.507494 -167.58285)
				)
			)
		)
		(zone
			(layer "F.Cu")
			(hatch none 0.5)
			(connect_pads
				(clearance 0)
			)
			(min_thickness 0.25)
			(keepout
				(tracks not_allowed)
				(vias allowed)
				(pads allowed)
				(copperpour not_allowed)
				(footprints allowed)
			)
			(placement
				(enabled no)
				(sheetname "")
			)
			(fill
				(thermal_gap 0.5)
				(thermal_bridge_width 0.5)
				(island_removal_mode 0)
			)
			(polygon
				(pts
					(xy 126.507494 -160.64865) (xy 119.433594 -160.64865) (xy 119.433594 -167.58285) (xy 120.538494 -167.58285)
					(xy 120.538494 -163.46805) (xy 125.161294 -163.46805) (xy 125.161294 -167.58285) (xy 126.507494 -167.58285)
				)
			)
		)
		(zone
			(layer "F.Cu")
			(hatch none 0.5)
			(connect_pads
				(clearance 0)
			)
			(min_thickness 0.25)
			(keepout
				(tracks allowed)
				(vias not_allowed)
				(pads allowed)
				(copperpour not_allowed)
				(footprints allowed)
			)
			(placement
				(enabled no)
				(sheetname "")
			)
			(fill
				(thermal_gap 0.5)
				(thermal_bridge_width 0.5)
				(island_removal_mode 0)
			)
			(polygon
				(pts
					(xy 126.507494 -127.17145) (xy 119.433594 -127.17145) (xy 119.433594 -120.23725) (xy 120.538494 -120.23725)
					(xy 120.538494 -124.35205) (xy 125.161294 -124.35205) (xy 125.161294 -120.23725) (xy 126.507494 -120.23725)
				)
			)
		)
		(zone
			(layer "F.Cu")
			(hatch none 0.5)
			(connect_pads
				(clearance 0)
			)
			(min_thickness 0.25)
			(keepout
				(tracks not_allowed)
				(vias allowed)
				(pads allowed)
				(copperpour not_allowed)
				(footprints allowed)
			)
			(placement
				(enabled no)
				(sheetname "")
			)
			(fill
				(thermal_gap 0.5)
				(thermal_bridge_width 0.5)
				(island_removal_mode 0)
			)
			(polygon
				(pts
					(xy 126.507494 -127.17145) (xy 119.433594 -127.17145) (xy 119.433594 -120.23725) (xy 120.538494 -120.23725)
					(xy 120.538494 -124.35205) (xy 125.161294 -124.35205) (xy 125.161294 -120.23725) (xy 126.507494 -120.23725)
				)
			)
		)
		(zone
			(layers "F.Cu" "B.Cu" "In1.Cu" "In2.Cu" "In3.Cu" "In4.Cu" "In5.Cu" "In6.Cu")
			(hatch none 0.5)
			(connect_pads
				(clearance 0)
			)
			(min_thickness 0.25)
			(keepout
				(tracks not_allowed)
				(vias allowed)
				(pads allowed)
				(copperpour not_allowed)
				(footprints allowed)
			)
			(placement
				(enabled no)
				(sheetname "")
			)
			(fill
				(thermal_gap 0.5)
				(thermal_bridge_width 0.5)
				(island_removal_mode 0)
			)
			(polygon
				(pts
					(arc
						(start 123.624594 -125.035056)
						(mid 122.075194 -125.035056)
						(end 123.624594 -125.035056)
					)
				)
			)
		)
		(zone
			(layers "F.Cu" "B.Cu" "In1.Cu" "In2.Cu" "In3.Cu" "In4.Cu" "In5.Cu" "In6.Cu")
			(hatch none 0.5)
			(connect_pads
				(clearance 0)
			)
			(min_thickness 0.25)
			(keepout
				(tracks not_allowed)
				(vias allowed)
				(pads allowed)
				(copperpour not_allowed)
				(footprints allowed)
			)
			(placement
				(enabled no)
				(sheetname "")
			)
			(fill
				(thermal_gap 0.5)
				(thermal_bridge_width 0.5)
				(island_removal_mode 0)
			)
			(polygon
				(pts
					(arc
						(start 123.827794 -162.785044)
						(mid 121.871994 -162.785044)
						(end 123.827794 -162.785044)
					)
				)
			)
		)
	)
	(footprint ""
		(layer "F.Cu")
		(at 86.106 -133.4262 -90)
		(property "Reference" "R400"
			(at 0 0 270)
			(layer "F.SilkS")
			(hide yes)
			(effects
				(font
					(size 1.27 1.27)
				)
			)
		)
		(property "Value" "1KR2F-3-GP"
			(at 0.064008 -3.993896 270)
			(unlocked yes)
			(layer "F.Fab")
			(hide yes)
			(effects
				(font
					(size 1.016 1.016)
					(thickness 0.1524)
				)
			)
		)
		(property "Device Type" "R402H16"
			(at 0.064008 -5.517896 270)
			(unlocked yes)
			(layer "F.Fab")
			(hide yes)
			(effects
				(font
					(size 1.016 1.016)
					(thickness 0.1524)
				)
			)
		)
		(duplicate_pad_numbers_are_jumpers no)
		(fp_line
			(start -0.508 -0.9398)
			(end -0.508 0.9398)
			(stroke
				(width 0.1524)
				(type default)
			)
			(layer "F.SilkS")
		)
		(fp_line
			(start 0.508 -0.9398)
			(end -0.508 -0.9398)
			(stroke
				(width 0.1524)
				(type default)
			)
			(layer "F.SilkS")
		)
		(fp_rect
			(start -0.508 0.9398)
			(end 0.508 -0.9398)
			(stroke
				(width 0)
				(type default)
			)
			(fill no)
			(layer "F.CrtYd")
		)
		(fp_rect
			(start -0.508 0.9398)
			(end 0.508 -0.9398)
			(stroke
				(width 0)
				(type default)
			)
			(fill no)
			(layer "F.Fab")
		)
		(pad "1" smd custom
			(at 0 -0.4445 270)
			(size 0.1397 0.1397)
			(layers "F.Cu" "F.Mask" "F.Paste")
			(net "P3V3_STBY_B")
			(options
				(clearance outline)
				(anchor circle)
			)
			(primitives
				(gr_poly
					(pts
						(arc
							(start -0.1778 -0.2794)
							(mid -0.249642 -0.249642)
							(end -0.2794 -0.1778)
						)
						(arc
							(start -0.2794 0.1778)
							(mid -0.249642 0.249642)
							(end -0.1778 0.2794)
						)
						(arc
							(start 0.1778 0.2794)
							(mid 0.249642 0.249642)
							(end 0.2794 0.1778)
						)
						(arc
							(start 0.2794 -0.1778)
							(mid 0.249642 -0.249642)
							(end 0.1778 -0.2794)
						)
					)
					(width 0)
					(fill yes)
				)
			)
		)
		(pad "2" smd custom
			(at 0 0.4445 270)
			(size 0.1397 0.1397)
			(layers "F.Cu" "F.Mask" "F.Paste")
			(net "SW_PWR_R_HDD14")
			(options
				(clearance outline)
				(anchor circle)
			)
			(primitives
				(gr_poly
					(pts
						(arc
							(start -0.1778 -0.2794)
							(mid -0.249642 -0.249642)
							(end -0.2794 -0.1778)
						)
						(arc
							(start -0.2794 0.1778)
							(mid -0.249642 0.249642)
							(end -0.1778 0.2794)
						)
						(arc
							(start 0.1778 0.2794)
							(mid 0.249642 0.249642)
							(end 0.2794 0.1778)
						)
						(arc
							(start 0.2794 -0.1778)
							(mid 0.249642 -0.249642)
							(end 0.1778 -0.2794)
						)
					)
					(width 0)
					(fill yes)
				)
			)
		)
	)
	(footprint ""
		(layer "F.Cu")
		(at 363.601 -13.589)
		(property "Reference" "R795"
			(at 0 0 0)
			(layer "F.SilkS")
			(hide yes)
			(effects
				(font
					(size 1.27 1.27)
				)
			)
		)
		(property "Value" "4K7R2F-GP"
			(at 0.064008 -3.993896 0)
			(unlocked yes)
			(layer "F.Fab")
			(hide yes)
			(effects
				(font
					(size 1.016 1.016)
					(thickness 0.1524)
				)
			)
		)
		(property "Device Type" "R402H16"
			(at 0.064008 -5.517896 0)
			(unlocked yes)
			(layer "F.Fab")
			(hide yes)
			(effects
				(font
					(size 1.016 1.016)
					(thickness 0.1524)
				)
			)
		)
		(duplicate_pad_numbers_are_jumpers no)
		(fp_line
			(start -0.508 -0.9398)
			(end -0.508 0.9398)
			(stroke
				(width 0.1524)
				(type default)
			)
			(layer "F.SilkS")
		)
		(fp_line
			(start 0.508 -0.9398)
			(end -0.508 -0.9398)
			(stroke
				(width 0.1524)
				(type default)
			)
			(layer "F.SilkS")
		)
		(fp_rect
			(start -0.508 0.9398)
			(end 0.508 -0.9398)
			(stroke
				(width 0)
				(type default)
			)
			(fill no)
			(layer "F.CrtYd")
		)
		(fp_rect
			(start -0.508 0.9398)
			(end 0.508 -0.9398)
			(stroke
				(width 0)
				(type default)
			)
			(fill no)
			(layer "F.Fab")
		)
		(pad "1" smd custom
			(at 0 -0.4445)
			(size 0.1397 0.1397)
			(layers "F.Cu" "F.Mask" "F.Paste")
			(net "SW_PWR_R_HDD31")
			(options
				(clearance outline)
				(anchor circle)
			)
			(primitives
				(gr_poly
					(pts
						(arc
							(start -0.1778 -0.2794)
							(mid -0.249642 -0.249642)
							(end -0.2794 -0.1778)
						)
						(arc
							(start -0.2794 0.1778)
							(mid -0.249642 0.249642)
							(end -0.1778 0.2794)
						)
						(arc
							(start 0.1778 0.2794)
							(mid 0.249642 0.249642)
							(end 0.2794 0.1778)
						)
						(arc
							(start 0.2794 -0.1778)
							(mid 0.249642 -0.249642)
							(end 0.1778 -0.2794)
						)
					)
					(width 0)
					(fill yes)
				)
			)
		)
		(pad "2" smd custom
			(at 0 0.4445)
			(size 0.1397 0.1397)
			(layers "F.Cu" "F.Mask" "F.Paste")
			(net "GND")
			(options
				(clearance outline)
				(anchor circle)
			)
			(primitives
				(gr_poly
					(pts
						(arc
							(start -0.1778 -0.2794)
							(mid -0.249642 -0.249642)
							(end -0.2794 -0.1778)
						)
						(arc
							(start -0.2794 0.1778)
							(mid -0.249642 0.249642)
							(end -0.1778 0.2794)
						)
						(arc
							(start 0.1778 0.2794)
							(mid 0.249642 0.249642)
							(end 0.2794 0.1778)
						)
						(arc
							(start 0.2794 -0.1778)
							(mid 0.249642 -0.249642)
							(end 0.1778 -0.2794)
						)
					)
					(width 0)
					(fill yes)
				)
			)
		)
	)
	(footprint ""
		(layer "F.Cu")
		(at 333.502 -160.02 180)
		(property "Reference" "C270"
			(at 0 0 180)
			(layer "F.SilkS")
			(hide yes)
			(effects
				(font
					(size 1.27 1.27)
				)
			)
		)
		(property "Value" "SC4D7U25V5KX-1-GP"
			(at -0.0762 -6.1214 180)
			(unlocked yes)
			(layer "F.Fab")
			(hide yes)
			(effects
				(font
					(size 1.016 1.016)
					(thickness 0.1524)
				)
			)
		)
		(property "Device Type" "C805H58"
			(at -0.0762 -8.1534 180)
			(unlocked yes)
			(layer "F.Fab")
			(hide yes)
			(effects
				(font
					(size 1.016 1.016)
					(thickness 0.1524)
				)
			)
		)
		(duplicate_pad_numbers_are_jumpers no)
		(fp_line
			(start 0.635 0)
			(end -0.635 0)
			(stroke
				(width 0.508)
				(type default)
			)
			(layer "F.SilkS")
		)
		(fp_rect
			(start -0.9652 1.778)
			(end 0.9652 -1.778)
			(stroke
				(width 0)
				(type default)
			)
			(fill no)
			(layer "F.CrtYd")
		)
		(fp_poly
			(pts
				(xy -0.9652 -1.778) (xy 0.9652 -1.778) (xy 0.9652 1.778) (xy -0.9652 1.778)
			)
			(stroke
				(width 0)
				(type default)
			)
			(fill no)
			(layer "F.Fab")
		)
		(pad "1" smd rect
			(at 0 -0.9652 180)
			(size 1.397 1.143)
			(layers "F.Cu" "F.Mask" "F.Paste")
			(net "P12V_HDD18")
		)
		(pad "2" smd rect
			(at 0 0.9652 180)
			(size 1.397 1.143)
			(layers "F.Cu" "F.Mask" "F.Paste")
			(net "GND")
		)
	)
	(footprint ""
		(layer "F.Cu")
		(at 477.152462 -244.884194 90)
		(property "Reference" "VIA23"
			(at 0 0 90)
			(layer "F.SilkS")
			(hide yes)
			(effects
				(font
					(size 1.27 1.27)
				)
			)
		)
		(property "Value" "100OHM-8L-2D36MM-L18-GP"
			(at 3.8989 0.5715 90)
			(unlocked yes)
			(layer "F.Fab")
			(hide yes)
			(effects
				(font
					(size 1.016 1.016)
					(thickness 0.1524)
				)
			)
		)
		(property "Device Type" "VIA-PCIE-4P-414097"
			(at 3.8989 -0.9525 90)
			(unlocked yes)
			(layer "F.Fab")
			(hide yes)
			(effects
				(font
					(size 1.016 1.016)
					(thickness 0.1524)
				)
			)
		)
		(duplicate_pad_numbers_are_jumpers no)
		(fp_rect
			(start -2.0701 0.4826)
			(end 2.0701 -0.4826)
			(stroke
				(width 0)
				(type default)
			)
			(fill no)
			(layer "F.CrtYd")
		)
		(fp_rect
			(start -2.0701 0.4826)
			(end 2.0701 -0.4826)
			(stroke
				(width 0)
				(type default)
			)
			(fill no)
			(layer "F.Fab")
		)
		(pad "1" thru_hole circle
			(at -1.5875 0 90)
			(size 0.508 0.508)
			(drill 0.254)
			(layers "*.Cu" "*.Mask")
			(remove_unused_layers no)
			(net "GND")
			(clearance 0.2286)
			(thermal_gap 0.2286)
		)
		(pad "2" thru_hole circle
			(at -0.5715 0 90)
			(size 0.508 0.508)
			(drill 0.254)
			(layers "*.Cu" "*.Mask")
			(remove_unused_layers no)
			(net "PHY_SCC_B_TO_DRV_B_11_DP")
			(clearance 0.2286)
			(thermal_gap 0.2286)
		)
		(pad "3" thru_hole circle
			(at 0.5715 0 90)
			(size 0.508 0.508)
			(drill 0.254)
			(layers "*.Cu" "*.Mask")
			(remove_unused_layers no)
			(net "PHY_SCC_B_TO_DRV_B_11_DN")
			(clearance 0.2286)
			(thermal_gap 0.2286)
		)
		(pad "4" thru_hole circle
			(at 1.5875 0 90)
			(size 0.508 0.508)
			(drill 0.254)
			(layers "*.Cu" "*.Mask")
			(remove_unused_layers no)
			(net "GND")
			(clearance 0.2286)
			(thermal_gap 0.2286)
		)
	)
	(footprint ""
		(layer "F.Cu")
		(at 141.478 -248.158 180)
		(property "Reference" "R234"
			(at 0 0 180)
			(layer "F.SilkS")
			(hide yes)
			(effects
				(font
					(size 1.27 1.27)
				)
			)
		)
		(property "Value" "200KR2F-L-GP"
			(at 0.064008 -3.993896 180)
			(unlocked yes)
			(layer "F.Fab")
			(hide yes)
			(effects
				(font
					(size 1.016 1.016)
					(thickness 0.1524)
				)
			)
		)
		(property "Device Type" "R402H16"
			(at 0.064008 -5.517896 180)
			(unlocked yes)
			(layer "F.Fab")
			(hide yes)
			(effects
				(font
					(size 1.016 1.016)
					(thickness 0.1524)
				)
			)
		)
		(duplicate_pad_numbers_are_jumpers no)
		(fp_line
			(start 0.508 -0.9398)
			(end -0.508 -0.9398)
			(stroke
				(width 0.1524)
				(type default)
			)
			(layer "F.SilkS")
		)
		(fp_line
			(start -0.508 -0.9398)
			(end -0.508 0.9398)
			(stroke
				(width 0.1524)
				(type default)
			)
			(layer "F.SilkS")
		)
		(fp_rect
			(start -0.508 0.9398)
			(end 0.508 -0.9398)
			(stroke
				(width 0)
				(type default)
			)
			(fill no)
			(layer "F.CrtYd")
		)
		(fp_rect
			(start -0.508 0.9398)
			(end 0.508 -0.9398)
			(stroke
				(width 0)
				(type default)
			)
			(fill no)
			(layer "F.Fab")
		)
		(pad "1" smd custom
			(at 0 -0.4445 180)
			(size 0.1397 0.1397)
			(layers "F.Cu" "F.Mask" "F.Paste")
			(net "SW_HDD_R4")
			(options
				(clearance outline)
				(anchor circle)
			)
			(primitives
				(gr_poly
					(pts
						(arc
							(start -0.1778 -0.2794)
							(mid -0.249642 -0.249642)
							(end -0.2794 -0.1778)
						)
						(arc
							(start -0.2794 0.1778)
							(mid -0.249642 0.249642)
							(end -0.1778 0.2794)
						)
						(arc
							(start 0.1778 0.2794)
							(mid 0.249642 0.249642)
							(end 0.2794 0.1778)
						)
						(arc
							(start 0.2794 -0.1778)
							(mid 0.249642 -0.249642)
							(end 0.1778 -0.2794)
						)
					)
					(width 0)
					(fill yes)
				)
			)
		)
		(pad "2" smd custom
			(at 0 0.4445 180)
			(size 0.1397 0.1397)
			(layers "F.Cu" "F.Mask" "F.Paste")
			(net "SW_HDD_N4")
			(options
				(clearance outline)
				(anchor circle)
			)
			(primitives
				(gr_poly
					(pts
						(arc
							(start -0.1778 -0.2794)
							(mid -0.249642 -0.249642)
							(end -0.2794 -0.1778)
						)
						(arc
							(start -0.2794 0.1778)
							(mid -0.249642 0.249642)
							(end -0.1778 0.2794)
						)
						(arc
							(start 0.1778 0.2794)
							(mid 0.249642 0.249642)
							(end 0.2794 0.1778)
						)
						(arc
							(start 0.2794 -0.1778)
							(mid 0.249642 -0.249642)
							(end 0.1778 -0.2794)
						)
					)
					(width 0)
					(fill yes)
				)
			)
		)
	)
	(footprint ""
		(layer "F.Cu")
		(at 146.304 -32.004 -90)
		(property "Reference" "C395"
			(at 0 0 270)
			(layer "F.SilkS")
			(hide yes)
			(effects
				(font
					(size 1.27 1.27)
				)
			)
		)
		(property "Value" "SC10U16V6KX-2GP"
			(at -0.0762 -5.1308 270)
			(unlocked yes)
			(layer "F.Fab")
			(hide yes)
			(effects
				(font
					(size 1.016 1.016)
					(thickness 0.1524)
				)
			)
		)
		(property "Device Type" "C1206H71"
			(at -0.127 -6.6548 270)
			(unlocked yes)
			(layer "F.Fab")
			(hide yes)
			(effects
				(font
					(size 1.016 1.016)
					(thickness 0.1524)
				)
			)
		)
		(duplicate_pad_numbers_are_jumpers no)
		(fp_line
			(start -1.016 2.2352)
			(end -1.016 0.8382)
			(stroke
				(width 0.1524)
				(type default)
			)
			(layer "F.SilkS")
		)
		(fp_line
			(start 1.016 2.2352)
			(end -1.016 2.2352)
			(stroke
				(width 0.1524)
				(type default)
			)
			(layer "F.SilkS")
		)
		(fp_line
			(start 1.016 0.8382)
			(end 1.016 2.2352)
			(stroke
				(width 0.1524)
				(type default)
			)
			(layer "F.SilkS")
		)
		(fp_line
			(start -1.016 -0.8382)
			(end -1.016 -2.2352)
			(stroke
				(width 0.1524)
				(type default)
			)
			(layer "F.SilkS")
		)
		(fp_line
			(start -1.016 -2.2352)
			(end 1.016 -2.2352)
			(stroke
				(width 0.1524)
				(type default)
			)
			(layer "F.SilkS")
		)
		(fp_line
			(start 1.016 -2.2352)
			(end 1.016 -0.8382)
			(stroke
				(width 0.1524)
				(type default)
			)
			(layer "F.SilkS")
		)
		(fp_rect
			(start -1.0922 2.3114)
			(end 1.0922 -2.3114)
			(stroke
				(width 0)
				(type default)
			)
			(fill no)
			(layer "F.CrtYd")
		)
		(fp_poly
			(pts
				(xy 1.0922 -2.3114) (xy 1.0922 2.3114) (xy -1.0922 2.3114) (xy -1.0922 -2.3114)
			)
			(stroke
				(width 0)
				(type default)
			)
			(fill no)
			(layer "F.Fab")
		)
		(pad "1" smd rect
			(at 0 -1.397 270)
			(size 1.651 1.27)
			(layers "F.Cu" "F.Mask" "F.Paste")
			(net "P5V_HDD28")
		)
		(pad "2" smd rect
			(at 0 1.397 270)
			(size 1.651 1.27)
			(layers "F.Cu" "F.Mask" "F.Paste")
			(net "GND")
		)
	)
	(footprint ""
		(layer "F.Cu")
		(at 462.159604 -373.6086 90)
		(property "Reference" "R1300"
			(at 0 0 90)
			(layer "F.SilkS")
			(hide yes)
			(effects
				(font
					(size 1.27 1.27)
				)
			)
		)
		(property "Value" "4K7R2F-GP"
			(at 0.064008 -3.993896 90)
			(unlocked yes)
			(layer "F.Fab")
			(hide yes)
			(effects
				(font
					(size 1.016 1.016)
					(thickness 0.1524)
				)
			)
		)
		(property "Device Type" "R402H16"
			(at 0.064008 -5.517896 90)
			(unlocked yes)
			(layer "F.Fab")
			(hide yes)
			(effects
				(font
					(size 1.016 1.016)
					(thickness 0.1524)
				)
			)
		)
		(duplicate_pad_numbers_are_jumpers no)
		(fp_line
			(start 0.508 -0.9398)
			(end -0.508 -0.9398)
			(stroke
				(width 0.1524)
				(type default)
			)
			(layer "F.SilkS")
		)
		(fp_line
			(start -0.508 -0.9398)
			(end -0.508 0.9398)
			(stroke
				(width 0.1524)
				(type default)
			)
			(layer "F.SilkS")
		)
		(fp_rect
			(start -0.508 0.9398)
			(end 0.508 -0.9398)
			(stroke
				(width 0)
				(type default)
			)
			(fill no)
			(layer "F.CrtYd")
		)
		(fp_rect
			(start -0.508 0.9398)
			(end 0.508 -0.9398)
			(stroke
				(width 0)
				(type default)
			)
			(fill no)
			(layer "F.Fab")
		)
		(pad "1" smd custom
			(at 0 -0.4445 90)
			(size 0.1397 0.1397)
			(layers "F.Cu" "F.Mask" "F.Paste")
			(net "FAN_YELLOW_LED3")
			(options
				(clearance outline)
				(anchor circle)
			)
			(primitives
				(gr_poly
					(pts
						(arc
							(start -0.1778 -0.2794)
							(mid -0.249642 -0.249642)
							(end -0.2794 -0.1778)
						)
						(arc
							(start -0.2794 0.1778)
							(mid -0.249642 0.249642)
							(end -0.1778 0.2794)
						)
						(arc
							(start 0.1778 0.2794)
							(mid 0.249642 0.249642)
							(end 0.2794 0.1778)
						)
						(arc
							(start 0.2794 -0.1778)
							(mid 0.249642 -0.249642)
							(end 0.1778 -0.2794)
						)
					)
					(width 0)
					(fill yes)
				)
			)
		)
		(pad "2" smd custom
			(at 0 0.4445 90)
			(size 0.1397 0.1397)
			(layers "F.Cu" "F.Mask" "F.Paste")
			(net "P12V_IN")
			(options
				(clearance outline)
				(anchor circle)
			)
			(primitives
				(gr_poly
					(pts
						(arc
							(start -0.1778 -0.2794)
							(mid -0.249642 -0.249642)
							(end -0.2794 -0.1778)
						)
						(arc
							(start -0.2794 0.1778)
							(mid -0.249642 0.249642)
							(end -0.1778 0.2794)
						)
						(arc
							(start 0.1778 0.2794)
							(mid 0.249642 0.249642)
							(end 0.2794 0.1778)
						)
						(arc
							(start 0.2794 -0.1778)
							(mid 0.249642 -0.249642)
							(end 0.1778 -0.2794)
						)
					)
					(width 0)
					(fill yes)
				)
			)
		)
	)
	(footprint ""
		(layer "F.Cu")
		(at 394.6398 -135.5852 -90)
		(property "Reference" "C298"
			(at 0 0 270)
			(layer "F.SilkS")
			(hide yes)
			(effects
				(font
					(size 1.27 1.27)
				)
			)
		)
		(property "Value" "SCD033U25V2KX-GP"
			(at 1.1811 -2.7051 270)
			(unlocked yes)
			(layer "F.Fab")
			(hide yes)
			(effects
				(font
					(size 1.016 1.016)
					(thickness 0.1524)
				)
			)
		)
		(property "Device Type" "C402H22"
			(at 1.1811 -4.2291 270)
			(unlocked yes)
			(layer "F.Fab")
			(hide yes)
			(effects
				(font
					(size 1.016 1.016)
					(thickness 0.1524)
				)
			)
		)
		(duplicate_pad_numbers_are_jumpers no)
		(fp_rect
			(start -0.4318 0.9525)
			(end 0.4318 -0.9525)
			(stroke
				(width 0)
				(type default)
			)
			(fill no)
			(layer "F.CrtYd")
		)
		(fp_rect
			(start -0.4318 0.9525)
			(end 0.4318 -0.9525)
			(stroke
				(width 0)
				(type default)
			)
			(fill no)
			(layer "F.Fab")
		)
		(pad "1" smd custom
			(at 0 -0.4445 270)
			(size 0.1524 0.1524)
			(layers "F.Cu" "F.Mask" "F.Paste")
			(net "SW_HDD_P20")
			(options
				(clearance outline)
				(anchor circle)
			)
			(primitives
				(gr_poly
					(pts
						(arc
							(start 0.3048 -0.2032)
							(mid 0.275042 -0.275042)
							(end 0.2032 -0.3048)
						)
						(arc
							(start -0.2032 -0.3048)
							(mid -0.275042 -0.275042)
							(end -0.3048 -0.2032)
						)
						(arc
							(start -0.3048 0.2032)
							(mid -0.275042 0.275042)
							(end -0.2032 0.3048)
						)
						(arc
							(start 0.2032 0.3048)
							(mid 0.275042 0.275042)
							(end 0.3048 0.2032)
						)
					)
					(width 0)
					(fill yes)
				)
			)
		)
		(pad "2" smd custom
			(at 0 0.4445 270)
			(size 0.1524 0.1524)
			(layers "F.Cu" "F.Mask" "F.Paste")
			(net "GND")
			(options
				(clearance outline)
				(anchor circle)
			)
			(primitives
				(gr_poly
					(pts
						(arc
							(start 0.3048 -0.2032)
							(mid 0.275042 -0.275042)
							(end 0.2032 -0.3048)
						)
						(arc
							(start -0.2032 -0.3048)
							(mid -0.275042 -0.275042)
							(end -0.3048 -0.2032)
						)
						(arc
							(start -0.3048 0.2032)
							(mid -0.275042 0.275042)
							(end -0.2032 0.3048)
						)
						(arc
							(start 0.2032 0.3048)
							(mid 0.275042 0.275042)
							(end 0.3048 0.2032)
						)
					)
					(width 0)
					(fill yes)
				)
			)
		)
	)
	(footprint ""
		(layer "F.Cu")
		(at 130.302 -266.065 90)
		(property "Reference" "R209"
			(at 0 0 90)
			(layer "F.SilkS")
			(hide yes)
			(effects
				(font
					(size 1.27 1.27)
				)
			)
		)
		(property "Value" "220R3F-1-GP"
			(at -0.0254 -2.5146 90)
			(unlocked yes)
			(layer "F.Fab")
			(hide yes)
			(effects
				(font
					(size 1.016 1.016)
					(thickness 0.1524)
				)
			)
		)
		(property "Device Type" "R603H22"
			(at -0.0254 -4.0386 90)
			(unlocked yes)
			(layer "F.Fab")
			(hide yes)
			(effects
				(font
					(size 1.016 1.016)
					(thickness 0.1524)
				)
			)
		)
		(duplicate_pad_numbers_are_jumpers no)
		(fp_line
			(start 0.2032 0)
			(end 0.4826 0)
			(stroke
				(width 0.2032)
				(type default)
			)
			(layer "F.SilkS")
		)
		(fp_line
			(start -0.4826 0)
			(end -0.2032 0)
			(stroke
				(width 0.2032)
				(type default)
			)
			(layer "F.SilkS")
		)
		(fp_rect
			(start -0.5842 1.3335)
			(end 0.5842 -1.3335)
			(stroke
				(width 0)
				(type default)
			)
			(fill no)
			(layer "F.CrtYd")
		)
		(fp_rect
			(start -0.5842 1.3335)
			(end 0.5842 -1.3335)
			(stroke
				(width 0)
				(type default)
			)
			(fill no)
			(layer "F.Fab")
		)
		(pad "1" smd custom
			(at 0 -0.762 90)
			(size 0.2159 0.2159)
			(layers "F.Cu" "F.Mask" "F.Paste")
			(net "HDD_PRSNT_3")
			(options
				(clearance outline)
				(anchor circle)
			)
			(primitives
				(gr_poly
					(pts
						(arc
							(start -0.3302 -0.4318)
							(mid -0.402042 -0.402042)
							(end -0.4318 -0.3302)
						)
						(arc
							(start -0.4318 0.3302)
							(mid -0.402042 0.402042)
							(end -0.3302 0.4318)
						)
						(arc
							(start 0.3302 0.4318)
							(mid 0.402042 0.402042)
							(end 0.4318 0.3302)
						)
						(arc
							(start 0.4318 -0.3302)
							(mid 0.402042 -0.402042)
							(end 0.3302 -0.4318)
						)
					)
					(width 0)
					(fill yes)
				)
			)
		)
		(pad "2" smd custom
			(at 0 0.762 90)
			(size 0.2159 0.2159)
			(layers "F.Cu" "F.Mask" "F.Paste")
			(net "DRIVE_B_3_INS")
			(options
				(clearance outline)
				(anchor circle)
			)
			(primitives
				(gr_poly
					(pts
						(arc
							(start -0.3302 -0.4318)
							(mid -0.402042 -0.402042)
							(end -0.4318 -0.3302)
						)
						(arc
							(start -0.4318 0.3302)
							(mid -0.402042 0.402042)
							(end -0.3302 0.4318)
						)
						(arc
							(start 0.3302 0.4318)
							(mid 0.402042 0.402042)
							(end 0.4318 0.3302)
						)
						(arc
							(start 0.4318 -0.3302)
							(mid 0.402042 -0.402042)
							(end 0.3302 -0.4318)
						)
					)
					(width 0)
					(fill yes)
				)
			)
		)
	)
	(footprint ""
		(layer "F.Cu")
		(at 141.478 -18.161 180)
		(property "Reference" "R730"
			(at 0 0 180)
			(layer "F.SilkS")
			(hide yes)
			(effects
				(font
					(size 1.27 1.27)
				)
			)
		)
		(property "Value" "200KR2F-L-GP"
			(at 0.064008 -3.993896 180)
			(unlocked yes)
			(layer "F.Fab")
			(hide yes)
			(effects
				(font
					(size 1.016 1.016)
					(thickness 0.1524)
				)
			)
		)
		(property "Device Type" "R402H16"
			(at 0.064008 -5.517896 180)
			(unlocked yes)
			(layer "F.Fab")
			(hide yes)
			(effects
				(font
					(size 1.016 1.016)
					(thickness 0.1524)
				)
			)
		)
		(duplicate_pad_numbers_are_jumpers no)
		(fp_line
			(start 0.508 -0.9398)
			(end -0.508 -0.9398)
			(stroke
				(width 0.1524)
				(type default)
			)
			(layer "F.SilkS")
		)
		(fp_line
			(start -0.508 -0.9398)
			(end -0.508 0.9398)
			(stroke
				(width 0.1524)
				(type default)
			)
			(layer "F.SilkS")
		)
		(fp_rect
			(start -0.508 0.9398)
			(end 0.508 -0.9398)
			(stroke
				(width 0)
				(type default)
			)
			(fill no)
			(layer "F.CrtYd")
		)
		(fp_rect
			(start -0.508 0.9398)
			(end 0.508 -0.9398)
			(stroke
				(width 0)
				(type default)
			)
			(fill no)
			(layer "F.Fab")
		)
		(pad "1" smd custom
			(at 0 -0.4445 180)
			(size 0.1397 0.1397)
			(layers "F.Cu" "F.Mask" "F.Paste")
			(net "SW_HDD_R28")
			(options
				(clearance outline)
				(anchor circle)
			)
			(primitives
				(gr_poly
					(pts
						(arc
							(start -0.1778 -0.2794)
							(mid -0.249642 -0.249642)
							(end -0.2794 -0.1778)
						)
						(arc
							(start -0.2794 0.1778)
							(mid -0.249642 0.249642)
							(end -0.1778 0.2794)
						)
						(arc
							(start 0.1778 0.2794)
							(mid 0.249642 0.249642)
							(end 0.2794 0.1778)
						)
						(arc
							(start 0.2794 -0.1778)
							(mid 0.249642 -0.249642)
							(end 0.1778 -0.2794)
						)
					)
					(width 0)
					(fill yes)
				)
			)
		)
		(pad "2" smd custom
			(at 0 0.4445 180)
			(size 0.1397 0.1397)
			(layers "F.Cu" "F.Mask" "F.Paste")
			(net "SW_HDD_N28")
			(options
				(clearance outline)
				(anchor circle)
			)
			(primitives
				(gr_poly
					(pts
						(arc
							(start -0.1778 -0.2794)
							(mid -0.249642 -0.249642)
							(end -0.2794 -0.1778)
						)
						(arc
							(start -0.2794 0.1778)
							(mid -0.249642 0.249642)
							(end -0.1778 0.2794)
						)
						(arc
							(start 0.1778 0.2794)
							(mid 0.249642 0.249642)
							(end 0.2794 0.1778)
						)
						(arc
							(start 0.2794 -0.1778)
							(mid 0.249642 -0.249642)
							(end 0.1778 -0.2794)
						)
					)
					(width 0)
					(fill yes)
				)
			)
		)
	)
	(footprint ""
		(layer "F.Cu")
		(at 181.6862 -42.291)
		(property "Reference" "C412"
			(at 0 0 0)
			(layer "F.SilkS")
			(hide yes)
			(effects
				(font
					(size 1.27 1.27)
				)
			)
		)
		(property "Value" "SC4D7U25V5KX-1-GP"
			(at -0.0762 -6.1214 0)
			(unlocked yes)
			(layer "F.Fab")
			(hide yes)
			(effects
				(font
					(size 1.016 1.016)
					(thickness 0.1524)
				)
			)
		)
		(property "Device Type" "C805H58"
			(at -0.0762 -8.1534 0)
			(unlocked yes)
			(layer "F.Fab")
			(hide yes)
			(effects
				(font
					(size 1.016 1.016)
					(thickness 0.1524)
				)
			)
		)
		(duplicate_pad_numbers_are_jumpers no)
		(fp_line
			(start 0.635 0)
			(end -0.635 0)
			(stroke
				(width 0.508)
				(type default)
			)
			(layer "F.SilkS")
		)
		(fp_rect
			(start -0.9652 1.778)
			(end 0.9652 -1.778)
			(stroke
				(width 0)
				(type default)
			)
			(fill no)
			(layer "F.CrtYd")
		)
		(fp_poly
			(pts
				(xy -0.9652 -1.778) (xy 0.9652 -1.778) (xy 0.9652 1.778) (xy -0.9652 1.778)
			)
			(stroke
				(width 0)
				(type default)
			)
			(fill no)
			(layer "F.Fab")
		)
		(pad "1" smd rect
			(at 0 -0.9652)
			(size 1.397 1.143)
			(layers "F.Cu" "F.Mask" "F.Paste")
			(net "P12V_HDD29")
		)
		(pad "2" smd rect
			(at 0 0.9652)
			(size 1.397 1.143)
			(layers "F.Cu" "F.Mask" "F.Paste")
			(net "GND")
		)
	)
	(footprint ""
		(layer "F.Cu")
		(at 20.066 -146.939 -90)
		(property "Reference" "C187"
			(at 0 0 270)
			(layer "F.SilkS")
			(hide yes)
			(effects
				(font
					(size 1.27 1.27)
				)
			)
		)
		(property "Value" "SC10U16V6KX-2GP"
			(at -0.0762 -5.1308 270)
			(unlocked yes)
			(layer "F.Fab")
			(hide yes)
			(effects
				(font
					(size 1.016 1.016)
					(thickness 0.1524)
				)
			)
		)
		(property "Device Type" "C1206H71"
			(at -0.127 -6.6548 270)
			(unlocked yes)
			(layer "F.Fab")
			(hide yes)
			(effects
				(font
					(size 1.016 1.016)
					(thickness 0.1524)
				)
			)
		)
		(duplicate_pad_numbers_are_jumpers no)
		(fp_line
			(start -1.016 2.2352)
			(end -1.016 0.8382)
			(stroke
				(width 0.1524)
				(type default)
			)
			(layer "F.SilkS")
		)
		(fp_line
			(start 1.016 2.2352)
			(end -1.016 2.2352)
			(stroke
				(width 0.1524)
				(type default)
			)
			(layer "F.SilkS")
		)
		(fp_line
			(start 1.016 0.8382)
			(end 1.016 2.2352)
			(stroke
				(width 0.1524)
				(type default)
			)
			(layer "F.SilkS")
		)
		(fp_line
			(start -1.016 -0.8382)
			(end -1.016 -2.2352)
			(stroke
				(width 0.1524)
				(type default)
			)
			(layer "F.SilkS")
		)
		(fp_line
			(start -1.016 -2.2352)
			(end 1.016 -2.2352)
			(stroke
				(width 0.1524)
				(type default)
			)
			(layer "F.SilkS")
		)
		(fp_line
			(start 1.016 -2.2352)
			(end 1.016 -0.8382)
			(stroke
				(width 0.1524)
				(type default)
			)
			(layer "F.SilkS")
		)
		(fp_rect
			(start -1.0922 2.3114)
			(end 1.0922 -2.3114)
			(stroke
				(width 0)
				(type default)
			)
			(fill no)
			(layer "F.CrtYd")
		)
		(fp_poly
			(pts
				(xy 1.0922 -2.3114) (xy 1.0922 2.3114) (xy -1.0922 2.3114) (xy -1.0922 -2.3114)
			)
			(stroke
				(width 0)
				(type default)
			)
			(fill no)
			(layer "F.Fab")
		)
		(pad "1" smd rect
			(at 0 -1.397 270)
			(size 1.651 1.27)
			(layers "F.Cu" "F.Mask" "F.Paste")
			(net "P5V_HDD12")
		)
		(pad "2" smd rect
			(at 0 1.397 270)
			(size 1.651 1.27)
			(layers "F.Cu" "F.Mask" "F.Paste")
			(net "GND")
		)
	)
	(footprint ""
		(layer "F.Cu")
		(at 23.749 -148.209)
		(property "Reference" "R350"
			(at 0 0 0)
			(layer "F.SilkS")
			(hide yes)
			(effects
				(font
					(size 1.27 1.27)
				)
			)
		)
		(property "Value" "2R6F-GP"
			(at -0.0508 -4.8514 0)
			(unlocked yes)
			(layer "F.Fab")
			(hide yes)
			(effects
				(font
					(size 1.016 1.016)
					(thickness 0.1524)
				)
			)
		)
		(property "Device Type" "R1206H26"
			(at 0 -6.3754 0)
			(unlocked yes)
			(layer "F.Fab")
			(hide yes)
			(effects
				(font
					(size 1.016 1.016)
					(thickness 0.1524)
				)
			)
		)
		(duplicate_pad_numbers_are_jumpers no)
		(fp_line
			(start -1.016 -2.2352)
			(end 1.016 -2.2352)
			(stroke
				(width 0.1524)
				(type default)
			)
			(layer "F.SilkS")
		)
		(fp_line
			(start -1.016 2.2352)
			(end -1.016 -2.2352)
			(stroke
				(width 0.1524)
				(type default)
			)
			(layer "F.SilkS")
		)
		(fp_line
			(start 1.016 -2.2352)
			(end 1.016 2.2352)
			(stroke
				(width 0.1524)
				(type default)
			)
			(layer "F.SilkS")
		)
		(fp_line
			(start 1.016 2.2352)
			(end -1.016 2.2352)
			(stroke
				(width 0.1524)
				(type default)
			)
			(layer "F.SilkS")
		)
		(fp_rect
			(start -1.0922 2.3114)
			(end 1.0922 -2.3114)
			(stroke
				(width 0)
				(type default)
			)
			(fill no)
			(layer "F.CrtYd")
		)
		(fp_poly
			(pts
				(xy -1.0922 -2.3114) (xy 1.0922 -2.3114) (xy 1.0922 2.3114) (xy -1.0922 2.3114)
			)
			(stroke
				(width 0)
				(type default)
			)
			(fill no)
			(layer "F.Fab")
		)
		(pad "1" smd rect
			(at 0 -1.397)
			(size 1.651 1.27)
			(layers "F.Cu" "F.Mask" "F.Paste")
			(net "P5V_HDD12")
		)
		(pad "2" smd rect
			(at 0 1.397)
			(size 1.651 1.27)
			(layers "F.Cu" "F.Mask" "F.Paste")
			(net "5V_PRE_12")
		)
	)
	(footprint ""
		(layer "F.Cu")
		(at 232.22204 -233.01198 180)
		(property "Reference" "R70"
			(at 0 0 180)
			(layer "F.SilkS")
			(hide yes)
			(effects
				(font
					(size 1.27 1.27)
				)
			)
		)
		(property "Value" "4K7R2F-GP"
			(at 0.064008 -3.993896 180)
			(unlocked yes)
			(layer "F.Fab")
			(hide yes)
			(effects
				(font
					(size 1.016 1.016)
					(thickness 0.1524)
				)
			)
		)
		(property "Device Type" "R402H16"
			(at 0.064008 -5.517896 180)
			(unlocked yes)
			(layer "F.Fab")
			(hide yes)
			(effects
				(font
					(size 1.016 1.016)
					(thickness 0.1524)
				)
			)
		)
		(duplicate_pad_numbers_are_jumpers no)
		(fp_line
			(start 0.508 -0.9398)
			(end -0.508 -0.9398)
			(stroke
				(width 0.1524)
				(type default)
			)
			(layer "F.SilkS")
		)
		(fp_line
			(start -0.508 -0.9398)
			(end -0.508 0.9398)
			(stroke
				(width 0.1524)
				(type default)
			)
			(layer "F.SilkS")
		)
		(fp_rect
			(start -0.508 0.9398)
			(end 0.508 -0.9398)
			(stroke
				(width 0)
				(type default)
			)
			(fill no)
			(layer "F.CrtYd")
		)
		(fp_rect
			(start -0.508 0.9398)
			(end 0.508 -0.9398)
			(stroke
				(width 0)
				(type default)
			)
			(fill no)
			(layer "F.Fab")
		)
		(pad "1" smd custom
			(at 0 -0.4445 180)
			(size 0.1397 0.1397)
			(layers "F.Cu" "F.Mask" "F.Paste")
			(net "IO_EXP1_A2")
			(options
				(clearance outline)
				(anchor circle)
			)
			(primitives
				(gr_poly
					(pts
						(arc
							(start -0.1778 -0.2794)
							(mid -0.249642 -0.249642)
							(end -0.2794 -0.1778)
						)
						(arc
							(start -0.2794 0.1778)
							(mid -0.249642 0.249642)
							(end -0.1778 0.2794)
						)
						(arc
							(start 0.1778 0.2794)
							(mid 0.249642 0.249642)
							(end 0.2794 0.1778)
						)
						(arc
							(start 0.2794 -0.1778)
							(mid 0.249642 -0.249642)
							(end 0.1778 -0.2794)
						)
					)
					(width 0)
					(fill yes)
				)
			)
		)
		(pad "2" smd custom
			(at 0 0.4445 180)
			(size 0.1397 0.1397)
			(layers "F.Cu" "F.Mask" "F.Paste")
			(net "GND")
			(options
				(clearance outline)
				(anchor circle)
			)
			(primitives
				(gr_poly
					(pts
						(arc
							(start -0.1778 -0.2794)
							(mid -0.249642 -0.249642)
							(end -0.2794 -0.1778)
						)
						(arc
							(start -0.2794 0.1778)
							(mid -0.249642 0.249642)
							(end -0.1778 0.2794)
						)
						(arc
							(start 0.1778 0.2794)
							(mid 0.249642 0.249642)
							(end 0.2794 0.1778)
						)
						(arc
							(start 0.2794 -0.1778)
							(mid 0.249642 -0.249642)
							(end 0.1778 -0.2794)
						)
					)
					(width 0)
					(fill yes)
				)
			)
		)
	)
	(footprint ""
		(layer "F.Cu")
		(at 182.372 -371.602 90)
		(property "Reference" "R987"
			(at 0 0 90)
			(layer "F.SilkS")
			(hide yes)
			(effects
				(font
					(size 1.27 1.27)
				)
			)
		)
		(property "Value" "0R2J-2-GP"
			(at 0.064008 -3.993896 90)
			(unlocked yes)
			(layer "F.Fab")
			(hide yes)
			(effects
				(font
					(size 1.016 1.016)
					(thickness 0.1524)
				)
			)
		)
		(property "Device Type" "R402H16"
			(at 0.064008 -5.517896 90)
			(unlocked yes)
			(layer "F.Fab")
			(hide yes)
			(effects
				(font
					(size 1.016 1.016)
					(thickness 0.1524)
				)
			)
		)
		(duplicate_pad_numbers_are_jumpers no)
		(fp_line
			(start 0.508 -0.9398)
			(end -0.508 -0.9398)
			(stroke
				(width 0.1524)
				(type default)
			)
			(layer "F.SilkS")
		)
		(fp_line
			(start -0.508 -0.9398)
			(end -0.508 0.9398)
			(stroke
				(width 0.1524)
				(type default)
			)
			(layer "F.SilkS")
		)
		(fp_rect
			(start -0.508 0.9398)
			(end 0.508 -0.9398)
			(stroke
				(width 0)
				(type default)
			)
			(fill no)
			(layer "F.CrtYd")
		)
		(fp_rect
			(start -0.508 0.9398)
			(end 0.508 -0.9398)
			(stroke
				(width 0)
				(type default)
			)
			(fill no)
			(layer "F.Fab")
		)
		(pad "1" smd custom
			(at 0 -0.4445 90)
			(size 0.1397 0.1397)
			(layers "F.Cu" "F.Mask" "F.Paste")
			(net "MB0_SCL_R")
			(options
				(clearance outline)
				(anchor circle)
			)
			(primitives
				(gr_poly
					(pts
						(arc
							(start -0.1778 -0.2794)
							(mid -0.249642 -0.249642)
							(end -0.2794 -0.1778)
						)
						(arc
							(start -0.2794 0.1778)
							(mid -0.249642 0.249642)
							(end -0.1778 0.2794)
						)
						(arc
							(start 0.1778 0.2794)
							(mid 0.249642 0.249642)
							(end 0.2794 0.1778)
						)
						(arc
							(start 0.2794 -0.1778)
							(mid 0.249642 -0.249642)
							(end 0.1778 -0.2794)
						)
					)
					(width 0)
					(fill yes)
				)
			)
		)
		(pad "2" smd custom
			(at 0 0.4445 90)
			(size 0.1397 0.1397)
			(layers "F.Cu" "F.Mask" "F.Paste")
			(net "I2C_CLIP_B_SCL")
			(options
				(clearance outline)
				(anchor circle)
			)
			(primitives
				(gr_poly
					(pts
						(arc
							(start -0.1778 -0.2794)
							(mid -0.249642 -0.249642)
							(end -0.2794 -0.1778)
						)
						(arc
							(start -0.2794 0.1778)
							(mid -0.249642 0.249642)
							(end -0.1778 0.2794)
						)
						(arc
							(start 0.1778 0.2794)
							(mid 0.249642 0.249642)
							(end 0.2794 0.1778)
						)
						(arc
							(start 0.2794 -0.1778)
							(mid 0.249642 -0.249642)
							(end 0.1778 -0.2794)
						)
					)
					(width 0)
					(fill yes)
				)
			)
		)
	)
	(footprint ""
		(layer "F.Cu")
		(at 248.778522 -358.876346)
		(property "Reference" "R1042"
			(at 0 0 0)
			(layer "F.SilkS")
			(hide yes)
			(effects
				(font
					(size 1.27 1.27)
				)
			)
		)
		(property "Value" "21KR2F-GP"
			(at 0.064008 -3.993896 0)
			(unlocked yes)
			(layer "F.Fab")
			(hide yes)
			(effects
				(font
					(size 1.016 1.016)
					(thickness 0.1524)
				)
			)
		)
		(property "Device Type" "R402H16"
			(at 0.064008 -5.517896 0)
			(unlocked yes)
			(layer "F.Fab")
			(hide yes)
			(effects
				(font
					(size 1.016 1.016)
					(thickness 0.1524)
				)
			)
		)
		(duplicate_pad_numbers_are_jumpers no)
		(fp_line
			(start -0.508 -0.9398)
			(end -0.508 0.9398)
			(stroke
				(width 0.1524)
				(type default)
			)
			(layer "F.SilkS")
		)
		(fp_line
			(start 0.508 -0.9398)
			(end -0.508 -0.9398)
			(stroke
				(width 0.1524)
				(type default)
			)
			(layer "F.SilkS")
		)
		(fp_rect
			(start -0.508 0.9398)
			(end 0.508 -0.9398)
			(stroke
				(width 0)
				(type default)
			)
			(fill no)
			(layer "F.CrtYd")
		)
		(fp_rect
			(start -0.508 0.9398)
			(end 0.508 -0.9398)
			(stroke
				(width 0)
				(type default)
			)
			(fill no)
			(layer "F.Fab")
		)
		(pad "1" smd custom
			(at 0 -0.4445)
			(size 0.1397 0.1397)
			(layers "F.Cu" "F.Mask" "F.Paste")
			(net "MB3_PSET_R")
			(options
				(clearance outline)
				(anchor circle)
			)
			(primitives
				(gr_poly
					(pts
						(arc
							(start -0.1778 -0.2794)
							(mid -0.249642 -0.249642)
							(end -0.2794 -0.1778)
						)
						(arc
							(start -0.2794 0.1778)
							(mid -0.249642 0.249642)
							(end -0.1778 0.2794)
						)
						(arc
							(start 0.1778 0.2794)
							(mid 0.249642 0.249642)
							(end 0.2794 0.1778)
						)
						(arc
							(start 0.2794 -0.1778)
							(mid 0.249642 -0.249642)
							(end 0.1778 -0.2794)
						)
					)
					(width 0)
					(fill yes)
				)
			)
		)
		(pad "2" smd custom
			(at 0 0.4445)
			(size 0.1397 0.1397)
			(layers "F.Cu" "F.Mask" "F.Paste")
			(net "AGND_CURRENT_DPB")
			(options
				(clearance outline)
				(anchor circle)
			)
			(primitives
				(gr_poly
					(pts
						(arc
							(start -0.1778 -0.2794)
							(mid -0.249642 -0.249642)
							(end -0.2794 -0.1778)
						)
						(arc
							(start -0.2794 0.1778)
							(mid -0.249642 0.249642)
							(end -0.1778 0.2794)
						)
						(arc
							(start 0.1778 0.2794)
							(mid 0.249642 0.249642)
							(end 0.2794 0.1778)
						)
						(arc
							(start 0.2794 -0.1778)
							(mid 0.249642 -0.249642)
							(end 0.1778 -0.2794)
						)
					)
					(width 0)
					(fill yes)
				)
			)
		)
	)
	(footprint ""
		(layer "F.Cu")
		(at 457.581 -147.066 -90)
		(property "Reference" "R575"
			(at 0 0 270)
			(layer "F.SilkS")
			(hide yes)
			(effects
				(font
					(size 1.27 1.27)
				)
			)
		)
		(property "Value" "2R6F-GP"
			(at -0.0508 -4.8514 270)
			(unlocked yes)
			(layer "F.Fab")
			(hide yes)
			(effects
				(font
					(size 1.016 1.016)
					(thickness 0.1524)
				)
			)
		)
		(property "Device Type" "R1206H26"
			(at 0 -6.3754 270)
			(unlocked yes)
			(layer "F.Fab")
			(hide yes)
			(effects
				(font
					(size 1.016 1.016)
					(thickness 0.1524)
				)
			)
		)
		(duplicate_pad_numbers_are_jumpers no)
		(fp_line
			(start -1.016 2.2352)
			(end -1.016 -2.2352)
			(stroke
				(width 0.1524)
				(type default)
			)
			(layer "F.SilkS")
		)
		(fp_line
			(start 1.016 2.2352)
			(end -1.016 2.2352)
			(stroke
				(width 0.1524)
				(type default)
			)
			(layer "F.SilkS")
		)
		(fp_line
			(start -1.016 -2.2352)
			(end 1.016 -2.2352)
			(stroke
				(width 0.1524)
				(type default)
			)
			(layer "F.SilkS")
		)
		(fp_line
			(start 1.016 -2.2352)
			(end 1.016 2.2352)
			(stroke
				(width 0.1524)
				(type default)
			)
			(layer "F.SilkS")
		)
		(fp_rect
			(start -1.0922 2.3114)
			(end 1.0922 -2.3114)
			(stroke
				(width 0)
				(type default)
			)
			(fill no)
			(layer "F.CrtYd")
		)
		(fp_poly
			(pts
				(xy -1.0922 -2.3114) (xy 1.0922 -2.3114) (xy 1.0922 2.3114) (xy -1.0922 2.3114)
			)
			(stroke
				(width 0)
				(type default)
			)
			(fill no)
			(layer "F.Fab")
		)
		(pad "1" smd rect
			(at 0 -1.397 270)
			(size 1.651 1.27)
			(layers "F.Cu" "F.Mask" "F.Paste")
			(net "P5V_HDD22")
		)
		(pad "2" smd rect
			(at 0 1.397 270)
			(size 1.651 1.27)
			(layers "F.Cu" "F.Mask" "F.Paste")
			(net "5V_PRE_22")
		)
	)
	(footprint ""
		(layer "F.Cu")
		(at 118.872 -45.466 180)
		(property "Reference" "C387"
			(at 0 0 180)
			(layer "F.SilkS")
			(hide yes)
			(effects
				(font
					(size 1.27 1.27)
				)
			)
		)
		(property "Value" "SC1U25V3KX-GP"
			(at 0 -2.8194 180)
			(unlocked yes)
			(layer "F.Fab")
			(hide yes)
			(effects
				(font
					(size 1.016 1.016)
					(thickness 0.1524)
				)
			)
		)
		(property "Device Type" "C603H36"
			(at 0 -4.3434 180)
			(unlocked yes)
			(layer "F.Fab")
			(hide yes)
			(effects
				(font
					(size 1.016 1.016)
					(thickness 0.1524)
				)
			)
		)
		(duplicate_pad_numbers_are_jumpers no)
		(fp_line
			(start 0.508 0)
			(end -0.508 0)
			(stroke
				(width 0.2032)
				(type default)
			)
			(layer "F.SilkS")
		)
		(fp_rect
			(start -0.5842 1.3335)
			(end 0.5842 -1.3335)
			(stroke
				(width 0)
				(type default)
			)
			(fill no)
			(layer "F.CrtYd")
		)
		(fp_rect
			(start -0.5842 1.3335)
			(end 0.5842 -1.3335)
			(stroke
				(width 0)
				(type default)
			)
			(fill no)
			(layer "F.Fab")
		)
		(pad "1" smd custom
			(at 0 -0.762 180)
			(size 0.2159 0.2159)
			(layers "F.Cu" "F.Mask" "F.Paste")
			(net "P12V_HDD27")
			(options
				(clearance outline)
				(anchor circle)
			)
			(primitives
				(gr_poly
					(pts
						(arc
							(start -0.3302 -0.4318)
							(mid -0.402042 -0.402042)
							(end -0.4318 -0.3302)
						)
						(arc
							(start -0.4318 0.3302)
							(mid -0.402042 0.402042)
							(end -0.3302 0.4318)
						)
						(arc
							(start 0.3302 0.4318)
							(mid 0.402042 0.402042)
							(end 0.4318 0.3302)
						)
						(arc
							(start 0.4318 -0.3302)
							(mid 0.402042 -0.402042)
							(end 0.3302 -0.4318)
						)
					)
					(width 0)
					(fill yes)
				)
			)
		)
		(pad "2" smd custom
			(at 0 0.762 180)
			(size 0.2159 0.2159)
			(layers "F.Cu" "F.Mask" "F.Paste")
			(net "GND")
			(options
				(clearance outline)
				(anchor circle)
			)
			(primitives
				(gr_poly
					(pts
						(arc
							(start -0.3302 -0.4318)
							(mid -0.402042 -0.402042)
							(end -0.4318 -0.3302)
						)
						(arc
							(start -0.4318 0.3302)
							(mid -0.402042 0.402042)
							(end -0.3302 0.4318)
						)
						(arc
							(start 0.3302 0.4318)
							(mid 0.402042 0.402042)
							(end 0.4318 0.3302)
						)
						(arc
							(start 0.4318 -0.3302)
							(mid 0.402042 -0.402042)
							(end 0.3302 -0.4318)
						)
					)
					(width 0)
					(fill yes)
				)
			)
		)
	)
	(footprint ""
		(layer "F.Cu")
		(at 392.938 -45.339 180)
		(property "Reference" "C452"
			(at 0 0 180)
			(layer "F.SilkS")
			(hide yes)
			(effects
				(font
					(size 1.27 1.27)
				)
			)
		)
		(property "Value" "SC1U25V3KX-GP"
			(at 0 -2.8194 180)
			(unlocked yes)
			(layer "F.Fab")
			(hide yes)
			(effects
				(font
					(size 1.016 1.016)
					(thickness 0.1524)
				)
			)
		)
		(property "Device Type" "C603H36"
			(at 0 -4.3434 180)
			(unlocked yes)
			(layer "F.Fab")
			(hide yes)
			(effects
				(font
					(size 1.016 1.016)
					(thickness 0.1524)
				)
			)
		)
		(duplicate_pad_numbers_are_jumpers no)
		(fp_line
			(start 0.508 0)
			(end -0.508 0)
			(stroke
				(width 0.2032)
				(type default)
			)
			(layer "F.SilkS")
		)
		(fp_rect
			(start -0.5842 1.3335)
			(end 0.5842 -1.3335)
			(stroke
				(width 0)
				(type default)
			)
			(fill no)
			(layer "F.CrtYd")
		)
		(fp_rect
			(start -0.5842 1.3335)
			(end 0.5842 -1.3335)
			(stroke
				(width 0)
				(type default)
			)
			(fill no)
			(layer "F.Fab")
		)
		(pad "1" smd custom
			(at 0 -0.762 180)
			(size 0.2159 0.2159)
			(layers "F.Cu" "F.Mask" "F.Paste")
			(net "P12V_HDD32")
			(options
				(clearance outline)
				(anchor circle)
			)
			(primitives
				(gr_poly
					(pts
						(arc
							(start -0.3302 -0.4318)
							(mid -0.402042 -0.402042)
							(end -0.4318 -0.3302)
						)
						(arc
							(start -0.4318 0.3302)
							(mid -0.402042 0.402042)
							(end -0.3302 0.4318)
						)
						(arc
							(start 0.3302 0.4318)
							(mid 0.402042 0.402042)
							(end 0.4318 0.3302)
						)
						(arc
							(start 0.4318 -0.3302)
							(mid 0.402042 -0.402042)
							(end 0.3302 -0.4318)
						)
					)
					(width 0)
					(fill yes)
				)
			)
		)
		(pad "2" smd custom
			(at 0 0.762 180)
			(size 0.2159 0.2159)
			(layers "F.Cu" "F.Mask" "F.Paste")
			(net "GND")
			(options
				(clearance outline)
				(anchor circle)
			)
			(primitives
				(gr_poly
					(pts
						(arc
							(start -0.3302 -0.4318)
							(mid -0.402042 -0.402042)
							(end -0.4318 -0.3302)
						)
						(arc
							(start -0.4318 0.3302)
							(mid -0.402042 0.402042)
							(end -0.3302 0.4318)
						)
						(arc
							(start 0.3302 0.4318)
							(mid 0.402042 0.402042)
							(end 0.4318 0.3302)
						)
						(arc
							(start 0.4318 -0.3302)
							(mid 0.402042 -0.402042)
							(end 0.3302 -0.4318)
						)
					)
					(width 0)
					(fill yes)
				)
			)
		)
	)
	(footprint ""
		(layer "F.Cu")
		(at 209.423 -207.01 90)
		(property "Reference" "R50"
			(at 0 0 90)
			(layer "F.SilkS")
			(hide yes)
			(effects
				(font
					(size 1.27 1.27)
				)
			)
		)
		(property "Value" "4K7R2F-GP"
			(at 0.064008 -3.993896 90)
			(unlocked yes)
			(layer "F.Fab")
			(hide yes)
			(effects
				(font
					(size 1.016 1.016)
					(thickness 0.1524)
				)
			)
		)
		(property "Device Type" "R402H16"
			(at 0.064008 -5.517896 90)
			(unlocked yes)
			(layer "F.Fab")
			(hide yes)
			(effects
				(font
					(size 1.016 1.016)
					(thickness 0.1524)
				)
			)
		)
		(duplicate_pad_numbers_are_jumpers no)
		(fp_line
			(start 0.508 -0.9398)
			(end -0.508 -0.9398)
			(stroke
				(width 0.1524)
				(type default)
			)
			(layer "F.SilkS")
		)
		(fp_line
			(start -0.508 -0.9398)
			(end -0.508 0.9398)
			(stroke
				(width 0.1524)
				(type default)
			)
			(layer "F.SilkS")
		)
		(fp_rect
			(start -0.508 0.9398)
			(end 0.508 -0.9398)
			(stroke
				(width 0)
				(type default)
			)
			(fill no)
			(layer "F.CrtYd")
		)
		(fp_rect
			(start -0.508 0.9398)
			(end 0.508 -0.9398)
			(stroke
				(width 0)
				(type default)
			)
			(fill no)
			(layer "F.Fab")
		)
		(pad "1" smd custom
			(at 0 -0.4445 90)
			(size 0.1397 0.1397)
			(layers "F.Cu" "F.Mask" "F.Paste")
			(net "P3V3_STBY_B")
			(options
				(clearance outline)
				(anchor circle)
			)
			(primitives
				(gr_poly
					(pts
						(arc
							(start -0.1778 -0.2794)
							(mid -0.249642 -0.249642)
							(end -0.2794 -0.1778)
						)
						(arc
							(start -0.2794 0.1778)
							(mid -0.249642 0.249642)
							(end -0.1778 0.2794)
						)
						(arc
							(start 0.1778 0.2794)
							(mid 0.249642 0.249642)
							(end 0.2794 0.1778)
						)
						(arc
							(start 0.2794 -0.1778)
							(mid 0.249642 -0.249642)
							(end 0.1778 -0.2794)
						)
					)
					(width 0)
					(fill yes)
				)
			)
		)
		(pad "2" smd custom
			(at 0 0.4445 90)
			(size 0.1397 0.1397)
			(layers "F.Cu" "F.Mask" "F.Paste")
			(net "IO_EXP5_A0")
			(options
				(clearance outline)
				(anchor circle)
			)
			(primitives
				(gr_poly
					(pts
						(arc
							(start -0.1778 -0.2794)
							(mid -0.249642 -0.249642)
							(end -0.2794 -0.1778)
						)
						(arc
							(start -0.2794 0.1778)
							(mid -0.249642 0.249642)
							(end -0.1778 0.2794)
						)
						(arc
							(start 0.1778 0.2794)
							(mid 0.249642 0.249642)
							(end 0.2794 0.1778)
						)
						(arc
							(start 0.2794 -0.1778)
							(mid 0.249642 -0.249642)
							(end 0.1778 -0.2794)
						)
					)
					(width 0)
					(fill yes)
				)
			)
		)
	)
	(footprint ""
		(layer "F.Cu")
		(at 332.359 -151.892 180)
		(property "Reference" "C265"
			(at 0 0 180)
			(layer "F.SilkS")
			(hide yes)
			(effects
				(font
					(size 1.27 1.27)
				)
			)
		)
		(property "Value" "SC10U16V6KX-2GP"
			(at -0.0762 -5.1308 180)
			(unlocked yes)
			(layer "F.Fab")
			(hide yes)
			(effects
				(font
					(size 1.016 1.016)
					(thickness 0.1524)
				)
			)
		)
		(property "Device Type" "C1206H71"
			(at -0.127 -6.6548 180)
			(unlocked yes)
			(layer "F.Fab")
			(hide yes)
			(effects
				(font
					(size 1.016 1.016)
					(thickness 0.1524)
				)
			)
		)
		(duplicate_pad_numbers_are_jumpers no)
		(fp_line
			(start 1.016 2.2352)
			(end -1.016 2.2352)
			(stroke
				(width 0.1524)
				(type default)
			)
			(layer "F.SilkS")
		)
		(fp_line
			(start 1.016 0.8382)
			(end 1.016 2.2352)
			(stroke
				(width 0.1524)
				(type default)
			)
			(layer "F.SilkS")
		)
		(fp_line
			(start 1.016 -2.2352)
			(end 1.016 -0.8382)
			(stroke
				(width 0.1524)
				(type default)
			)
			(layer "F.SilkS")
		)
		(fp_line
			(start -1.016 2.2352)
			(end -1.016 0.8382)
			(stroke
				(width 0.1524)
				(type default)
			)
			(layer "F.SilkS")
		)
		(fp_line
			(start -1.016 -0.8382)
			(end -1.016 -2.2352)
			(stroke
				(width 0.1524)
				(type default)
			)
			(layer "F.SilkS")
		)
		(fp_line
			(start -1.016 -2.2352)
			(end 1.016 -2.2352)
			(stroke
				(width 0.1524)
				(type default)
			)
			(layer "F.SilkS")
		)
		(fp_rect
			(start -1.0922 2.3114)
			(end 1.0922 -2.3114)
			(stroke
				(width 0)
				(type default)
			)
			(fill no)
			(layer "F.CrtYd")
		)
		(fp_poly
			(pts
				(xy 1.0922 -2.3114) (xy 1.0922 2.3114) (xy -1.0922 2.3114) (xy -1.0922 -2.3114)
			)
			(stroke
				(width 0)
				(type default)
			)
			(fill no)
			(layer "F.Fab")
		)
		(pad "1" smd rect
			(at 0 -1.397 180)
			(size 1.651 1.27)
			(layers "F.Cu" "F.Mask" "F.Paste")
			(net "P5V_HDD18")
		)
		(pad "2" smd rect
			(at 0 1.397 180)
			(size 1.651 1.27)
			(layers "F.Cu" "F.Mask" "F.Paste")
			(net "GND")
		)
	)
	(footprint ""
		(layer "F.Cu")
		(at 396.621 -274.955 180)
		(property "Reference" "C139"
			(at 0 0 180)
			(layer "F.SilkS")
			(hide yes)
			(effects
				(font
					(size 1.27 1.27)
				)
			)
		)
		(property "Value" "SC4D7U25V5KX-1-GP"
			(at -0.0762 -6.1214 180)
			(unlocked yes)
			(layer "F.Fab")
			(hide yes)
			(effects
				(font
					(size 1.016 1.016)
					(thickness 0.1524)
				)
			)
		)
		(property "Device Type" "C805H58"
			(at -0.0762 -8.1534 180)
			(unlocked yes)
			(layer "F.Fab")
			(hide yes)
			(effects
				(font
					(size 1.016 1.016)
					(thickness 0.1524)
				)
			)
		)
		(duplicate_pad_numbers_are_jumpers no)
		(fp_line
			(start 0.635 0)
			(end -0.635 0)
			(stroke
				(width 0.508)
				(type default)
			)
			(layer "F.SilkS")
		)
		(fp_rect
			(start -0.9652 1.778)
			(end 0.9652 -1.778)
			(stroke
				(width 0)
				(type default)
			)
			(fill no)
			(layer "F.CrtYd")
		)
		(fp_poly
			(pts
				(xy -0.9652 -1.778) (xy 0.9652 -1.778) (xy 0.9652 1.778) (xy -0.9652 1.778)
			)
			(stroke
				(width 0)
				(type default)
			)
			(fill no)
			(layer "F.Fab")
		)
		(pad "1" smd rect
			(at 0 -0.9652 180)
			(size 1.397 1.143)
			(layers "F.Cu" "F.Mask" "F.Paste")
			(net "P12V_HDD8")
		)
		(pad "2" smd rect
			(at 0 0.9652 180)
			(size 1.397 1.143)
			(layers "F.Cu" "F.Mask" "F.Paste")
			(net "GND")
		)
	)
	(footprint ""
		(layer "F.Cu")
		(at 364.998 -44.958 180)
		(property "Reference" "C438"
			(at 0 0 180)
			(layer "F.SilkS")
			(hide yes)
			(effects
				(font
					(size 1.27 1.27)
				)
			)
		)
		(property "Value" "SC4D7U25V5KX-1-GP"
			(at -0.0762 -6.1214 180)
			(unlocked yes)
			(layer "F.Fab")
			(hide yes)
			(effects
				(font
					(size 1.016 1.016)
					(thickness 0.1524)
				)
			)
		)
		(property "Device Type" "C805H58"
			(at -0.0762 -8.1534 180)
			(unlocked yes)
			(layer "F.Fab")
			(hide yes)
			(effects
				(font
					(size 1.016 1.016)
					(thickness 0.1524)
				)
			)
		)
		(duplicate_pad_numbers_are_jumpers no)
		(fp_line
			(start 0.635 0)
			(end -0.635 0)
			(stroke
				(width 0.508)
				(type default)
			)
			(layer "F.SilkS")
		)
		(fp_rect
			(start -0.9652 1.778)
			(end 0.9652 -1.778)
			(stroke
				(width 0)
				(type default)
			)
			(fill no)
			(layer "F.CrtYd")
		)
		(fp_poly
			(pts
				(xy -0.9652 -1.778) (xy 0.9652 -1.778) (xy 0.9652 1.778) (xy -0.9652 1.778)
			)
			(stroke
				(width 0)
				(type default)
			)
			(fill no)
			(layer "F.Fab")
		)
		(pad "1" smd rect
			(at 0 -0.9652 180)
			(size 1.397 1.143)
			(layers "F.Cu" "F.Mask" "F.Paste")
			(net "P12V_HDD31")
		)
		(pad "2" smd rect
			(at 0 0.9652 180)
			(size 1.397 1.143)
			(layers "F.Cu" "F.Mask" "F.Paste")
			(net "GND")
		)
	)
	(footprint ""
		(layer "F.Cu")
		(at 172.847 -375.412)
		(property "Reference" "R995"
			(at 0 0 0)
			(layer "F.SilkS")
			(hide yes)
			(effects
				(font
					(size 1.27 1.27)
				)
			)
		)
		(property "Value" "100KR2F-L1-GP"
			(at 0.064008 -3.993896 0)
			(unlocked yes)
			(layer "F.Fab")
			(hide yes)
			(effects
				(font
					(size 1.016 1.016)
					(thickness 0.1524)
				)
			)
		)
		(property "Device Type" "R402H16"
			(at 0.064008 -5.517896 0)
			(unlocked yes)
			(layer "F.Fab")
			(hide yes)
			(effects
				(font
					(size 1.016 1.016)
					(thickness 0.1524)
				)
			)
		)
		(duplicate_pad_numbers_are_jumpers no)
		(fp_line
			(start -0.508 -0.9398)
			(end -0.508 0.9398)
			(stroke
				(width 0.1524)
				(type default)
			)
			(layer "F.SilkS")
		)
		(fp_line
			(start 0.508 -0.9398)
			(end -0.508 -0.9398)
			(stroke
				(width 0.1524)
				(type default)
			)
			(layer "F.SilkS")
		)
		(fp_rect
			(start -0.508 0.9398)
			(end 0.508 -0.9398)
			(stroke
				(width 0)
				(type default)
			)
			(fill no)
			(layer "F.CrtYd")
		)
		(fp_rect
			(start -0.508 0.9398)
			(end 0.508 -0.9398)
			(stroke
				(width 0)
				(type default)
			)
			(fill no)
			(layer "F.Fab")
		)
		(pad "1" smd custom
			(at 0 -0.4445)
			(size 0.1397 0.1397)
			(layers "F.Cu" "F.Mask" "F.Paste")
			(net "P12V_IN")
			(options
				(clearance outline)
				(anchor circle)
			)
			(primitives
				(gr_poly
					(pts
						(arc
							(start -0.1778 -0.2794)
							(mid -0.249642 -0.249642)
							(end -0.2794 -0.1778)
						)
						(arc
							(start -0.2794 0.1778)
							(mid -0.249642 0.249642)
							(end -0.1778 0.2794)
						)
						(arc
							(start 0.1778 0.2794)
							(mid 0.249642 0.249642)
							(end 0.2794 0.1778)
						)
						(arc
							(start 0.2794 -0.1778)
							(mid 0.249642 -0.249642)
							(end 0.1778 -0.2794)
						)
					)
					(width 0)
					(fill yes)
				)
			)
		)
		(pad "2" smd custom
			(at 0 0.4445)
			(size 0.1397 0.1397)
			(layers "F.Cu" "F.Mask" "F.Paste")
			(net "MB0_P12V_PWGIN_R")
			(options
				(clearance outline)
				(anchor circle)
			)
			(primitives
				(gr_poly
					(pts
						(arc
							(start -0.1778 -0.2794)
							(mid -0.249642 -0.249642)
							(end -0.2794 -0.1778)
						)
						(arc
							(start -0.2794 0.1778)
							(mid -0.249642 0.249642)
							(end -0.1778 0.2794)
						)
						(arc
							(start 0.1778 0.2794)
							(mid 0.249642 0.249642)
							(end 0.2794 0.1778)
						)
						(arc
							(start 0.2794 -0.1778)
							(mid 0.249642 -0.249642)
							(end 0.1778 -0.2794)
						)
					)
					(width 0)
					(fill yes)
				)
			)
		)
	)
	(footprint ""
		(layer "F.Cu")
		(at 150.495 -45.466 180)
		(property "Reference" "C401"
			(at 0 0 180)
			(layer "F.SilkS")
			(hide yes)
			(effects
				(font
					(size 1.27 1.27)
				)
			)
		)
		(property "Value" "SC1U25V3KX-GP"
			(at 0 -2.8194 180)
			(unlocked yes)
			(layer "F.Fab")
			(hide yes)
			(effects
				(font
					(size 1.016 1.016)
					(thickness 0.1524)
				)
			)
		)
		(property "Device Type" "C603H36"
			(at 0 -4.3434 180)
			(unlocked yes)
			(layer "F.Fab")
			(hide yes)
			(effects
				(font
					(size 1.016 1.016)
					(thickness 0.1524)
				)
			)
		)
		(duplicate_pad_numbers_are_jumpers no)
		(fp_line
			(start 0.508 0)
			(end -0.508 0)
			(stroke
				(width 0.2032)
				(type default)
			)
			(layer "F.SilkS")
		)
		(fp_rect
			(start -0.5842 1.3335)
			(end 0.5842 -1.3335)
			(stroke
				(width 0)
				(type default)
			)
			(fill no)
			(layer "F.CrtYd")
		)
		(fp_rect
			(start -0.5842 1.3335)
			(end 0.5842 -1.3335)
			(stroke
				(width 0)
				(type default)
			)
			(fill no)
			(layer "F.Fab")
		)
		(pad "1" smd custom
			(at 0 -0.762 180)
			(size 0.2159 0.2159)
			(layers "F.Cu" "F.Mask" "F.Paste")
			(net "P12V_HDD28")
			(options
				(clearance outline)
				(anchor circle)
			)
			(primitives
				(gr_poly
					(pts
						(arc
							(start -0.3302 -0.4318)
							(mid -0.402042 -0.402042)
							(end -0.4318 -0.3302)
						)
						(arc
							(start -0.4318 0.3302)
							(mid -0.402042 0.402042)
							(end -0.3302 0.4318)
						)
						(arc
							(start 0.3302 0.4318)
							(mid 0.402042 0.402042)
							(end 0.4318 0.3302)
						)
						(arc
							(start 0.4318 -0.3302)
							(mid 0.402042 -0.402042)
							(end 0.3302 -0.4318)
						)
					)
					(width 0)
					(fill yes)
				)
			)
		)
		(pad "2" smd custom
			(at 0 0.762 180)
			(size 0.2159 0.2159)
			(layers "F.Cu" "F.Mask" "F.Paste")
			(net "GND")
			(options
				(clearance outline)
				(anchor circle)
			)
			(primitives
				(gr_poly
					(pts
						(arc
							(start -0.3302 -0.4318)
							(mid -0.402042 -0.402042)
							(end -0.4318 -0.3302)
						)
						(arc
							(start -0.4318 0.3302)
							(mid -0.402042 0.402042)
							(end -0.3302 0.4318)
						)
						(arc
							(start 0.3302 0.4318)
							(mid 0.402042 0.402042)
							(end 0.4318 0.3302)
						)
						(arc
							(start 0.4318 -0.3302)
							(mid 0.402042 -0.402042)
							(end 0.3302 -0.4318)
						)
					)
					(width 0)
					(fill yes)
				)
			)
		)
	)
	(footprint ""
		(layer "F.Cu")
		(at 433.324 -27.813 -90)
		(property "Reference" "R843"
			(at 0 0 270)
			(layer "F.SilkS")
			(hide yes)
			(effects
				(font
					(size 1.27 1.27)
				)
			)
		)
		(property "Value" "300KR2F-GP"
			(at 0.064008 -3.993896 270)
			(unlocked yes)
			(layer "F.Fab")
			(hide yes)
			(effects
				(font
					(size 1.016 1.016)
					(thickness 0.1524)
				)
			)
		)
		(property "Device Type" "R402H16"
			(at 0.064008 -5.517896 270)
			(unlocked yes)
			(layer "F.Fab")
			(hide yes)
			(effects
				(font
					(size 1.016 1.016)
					(thickness 0.1524)
				)
			)
		)
		(duplicate_pad_numbers_are_jumpers no)
		(fp_line
			(start -0.508 -0.9398)
			(end -0.508 0.9398)
			(stroke
				(width 0.1524)
				(type default)
			)
			(layer "F.SilkS")
		)
		(fp_line
			(start 0.508 -0.9398)
			(end -0.508 -0.9398)
			(stroke
				(width 0.1524)
				(type default)
			)
			(layer "F.SilkS")
		)
		(fp_rect
			(start -0.508 0.9398)
			(end 0.508 -0.9398)
			(stroke
				(width 0)
				(type default)
			)
			(fill no)
			(layer "F.CrtYd")
		)
		(fp_rect
			(start -0.508 0.9398)
			(end 0.508 -0.9398)
			(stroke
				(width 0)
				(type default)
			)
			(fill no)
			(layer "F.Fab")
		)
		(pad "1" smd custom
			(at 0 -0.4445 270)
			(size 0.1397 0.1397)
			(layers "F.Cu" "F.Mask" "F.Paste")
			(net "SW_HDD_N33")
			(options
				(clearance outline)
				(anchor circle)
			)
			(primitives
				(gr_poly
					(pts
						(arc
							(start -0.1778 -0.2794)
							(mid -0.249642 -0.249642)
							(end -0.2794 -0.1778)
						)
						(arc
							(start -0.2794 0.1778)
							(mid -0.249642 0.249642)
							(end -0.1778 0.2794)
						)
						(arc
							(start 0.1778 0.2794)
							(mid 0.249642 0.249642)
							(end 0.2794 0.1778)
						)
						(arc
							(start 0.2794 -0.1778)
							(mid 0.249642 -0.249642)
							(end 0.1778 -0.2794)
						)
					)
					(width 0)
					(fill yes)
				)
			)
		)
		(pad "2" smd custom
			(at 0 0.4445 270)
			(size 0.1397 0.1397)
			(layers "F.Cu" "F.Mask" "F.Paste")
			(net "P12V_B")
			(options
				(clearance outline)
				(anchor circle)
			)
			(primitives
				(gr_poly
					(pts
						(arc
							(start -0.1778 -0.2794)
							(mid -0.249642 -0.249642)
							(end -0.2794 -0.1778)
						)
						(arc
							(start -0.2794 0.1778)
							(mid -0.249642 0.249642)
							(end -0.1778 0.2794)
						)
						(arc
							(start 0.1778 0.2794)
							(mid 0.249642 0.249642)
							(end 0.2794 0.1778)
						)
						(arc
							(start 0.2794 -0.1778)
							(mid 0.249642 -0.249642)
							(end 0.1778 -0.2794)
						)
					)
					(width 0)
					(fill yes)
				)
			)
		)
	)
	(footprint ""
		(layer "F.Cu")
		(at 444.407036 -99.705922 180)
		(property "Reference" "Q263"
			(at 0 0 180)
			(layer "F.SilkS")
			(hide yes)
			(effects
				(font
					(size 1.27 1.27)
				)
			)
		)
		(property "Value" "SSM3K324R-GP"
			(at 0.127 -8.9662 180)
			(unlocked yes)
			(layer "F.Fab")
			(hide yes)
			(effects
				(font
					(size 1.016 1.016)
					(thickness 0.1524)
				)
			)
		)
		(property "Device Type" "SOT23DGS2D4H35"
			(at 0.127 -10.4902 180)
			(unlocked yes)
			(layer "F.Fab")
			(hide yes)
			(effects
				(font
					(size 1.016 1.016)
					(thickness 0.1524)
				)
			)
		)
		(duplicate_pad_numbers_are_jumpers no)
		(fp_line
			(start 1.651 1.778)
			(end 1.651 -1.778)
			(stroke
				(width 0.1524)
				(type default)
			)
			(layer "F.SilkS")
		)
		(fp_line
			(start 1.651 -1.778)
			(end -1.651 -1.778)
			(stroke
				(width 0.1524)
				(type default)
			)
			(layer "F.SilkS")
		)
		(fp_line
			(start -1.651 1.778)
			(end 1.651 1.778)
			(stroke
				(width 0.1524)
				(type default)
			)
			(layer "F.SilkS")
		)
		(fp_line
			(start -1.651 -1.778)
			(end -1.651 1.778)
			(stroke
				(width 0.1524)
				(type default)
			)
			(layer "F.SilkS")
		)
		(fp_poly
			(pts
				(xy -1.778 1.8796) (xy -1.778 -1.8796) (xy 1.778 -1.8796) (xy 1.778 1.8796)
			)
			(stroke
				(width 0)
				(type default)
			)
			(fill no)
			(layer "F.CrtYd")
		)
		(fp_poly
			(pts
				(xy -1.778 1.8796) (xy -1.778 -1.8796) (xy 1.778 -1.8796) (xy 1.778 1.8796)
			)
			(stroke
				(width 0)
				(type default)
			)
			(fill no)
			(layer "F.Fab")
		)
		(pad "D" smd custom
			(at 0 -0.9525 180)
			(size 0.1905 0.1905)
			(layers "F.Cu" "F.Mask" "F.Paste")
			(net "DRV_ACT_22_N")
			(options
				(clearance outline)
				(anchor circle)
			)
			(primitives
				(gr_poly
					(pts
						(arc
							(start -0.1778 0.5715)
							(mid -0.321484 0.511984)
							(end -0.381 0.3683)
						)
						(arc
							(start -0.381 -0.3683)
							(mid -0.321484 -0.511984)
							(end -0.1778 -0.5715)
						)
						(arc
							(start 0.1778 -0.5715)
							(mid 0.321484 -0.511984)
							(end 0.381 -0.3683)
						)
						(arc
							(start 0.381 0.3683)
							(mid 0.321484 0.511984)
							(end 0.1778 0.5715)
						)
					)
					(width 0)
					(fill yes)
				)
			)
		)
		(pad "G" smd custom
			(at -0.98425 0.9525 180)
			(size 0.1905 0.1905)
			(layers "F.Cu" "F.Mask" "F.Paste")
			(net "DRIVE_B_22_ACT")
			(options
				(clearance outline)
				(anchor circle)
			)
			(primitives
				(gr_poly
					(pts
						(arc
							(start -0.1778 0.5715)
							(mid -0.321484 0.511984)
							(end -0.381 0.3683)
						)
						(arc
							(start -0.381 -0.3683)
							(mid -0.321484 -0.511984)
							(end -0.1778 -0.5715)
						)
						(arc
							(start 0.1778 -0.5715)
							(mid 0.321484 -0.511984)
							(end 0.381 -0.3683)
						)
						(arc
							(start 0.381 0.3683)
							(mid 0.321484 0.511984)
							(end 0.1778 0.5715)
						)
					)
					(width 0)
					(fill yes)
				)
			)
		)
		(pad "S" smd custom
			(at 0.98425 0.9525 180)
			(size 0.1905 0.1905)
			(layers "F.Cu" "F.Mask" "F.Paste")
			(net "GND")
			(options
				(clearance outline)
				(anchor circle)
			)
			(primitives
				(gr_poly
					(pts
						(arc
							(start -0.1778 0.5715)
							(mid -0.321484 0.511984)
							(end -0.381 0.3683)
						)
						(arc
							(start -0.381 -0.3683)
							(mid -0.321484 -0.511984)
							(end -0.1778 -0.5715)
						)
						(arc
							(start 0.1778 -0.5715)
							(mid 0.321484 -0.511984)
							(end 0.381 -0.3683)
						)
						(arc
							(start 0.381 0.3683)
							(mid 0.321484 0.511984)
							(end 0.1778 0.5715)
						)
					)
					(width 0)
					(fill yes)
				)
			)
		)
	)
	(footprint ""
		(layer "F.Cu")
		(at 439.121804 -360.8324)
		(property "Reference" "Q133"
			(at 0 0 0)
			(layer "F.SilkS")
			(hide yes)
			(effects
				(font
					(size 1.27 1.27)
				)
			)
		)
		(property "Value" "AO4407AL-GP"
			(at -3.707384 -1.5367 0)
			(unlocked yes)
			(layer "F.Fab")
			(hide yes)
			(effects
				(font
					(size 1.016 1.016)
					(thickness 0.1524)
				)
			)
		)
		(property "Device Type" "SOIC8H69"
			(at -3.707384 -3.0607 0)
			(unlocked yes)
			(layer "F.Fab")
			(hide yes)
			(effects
				(font
					(size 1.016 1.016)
					(thickness 0.1524)
				)
			)
		)
		(duplicate_pad_numbers_are_jumpers no)
		(fp_line
			(start -2.7432 -1.4224)
			(end -2.7432 1.4224)
			(stroke
				(width 0.1524)
				(type default)
			)
			(layer "F.SilkS")
		)
		(fp_line
			(start -2.7432 1.4224)
			(end -2.6416 1.4224)
			(stroke
				(width 0.1524)
				(type default)
			)
			(layer "F.SilkS")
		)
		(fp_line
			(start -2.7432 1.4224)
			(end 2.1336 1.4224)
			(stroke
				(width 0.1524)
				(type default)
			)
			(layer "F.SilkS")
		)
		(fp_line
			(start -2.7178 -0.508)
			(end -2.1844 -0.0508)
			(stroke
				(width 0.1524)
				(type default)
			)
			(layer "F.SilkS")
		)
		(fp_line
			(start -2.6289 3.4417)
			(end -2.6289 1.4732)
			(stroke
				(width 0.381)
				(type default)
			)
			(layer "F.SilkS")
		)
		(fp_line
			(start -2.1844 -0.0508)
			(end -2.7178 0.508)
			(stroke
				(width 0.1524)
				(type default)
			)
			(layer "F.SilkS")
		)
		(fp_line
			(start 2.1336 -1.4224)
			(end -2.7432 -1.4224)
			(stroke
				(width 0.1524)
				(type default)
			)
			(layer "F.SilkS")
		)
		(fp_line
			(start 2.1336 1.4224)
			(end 2.1336 -1.4224)
			(stroke
				(width 0.1524)
				(type default)
			)
			(layer "F.SilkS")
		)
		(fp_poly
			(pts
				(xy -2.2098 -1.4224) (xy -2.2098 1.4224) (xy 2.2098 1.4224) (xy 2.2098 -1.4224)
			)
			(stroke
				(width 0)
				(type default)
			)
			(fill yes)
			(layer "F.SilkS")
		)
		(fp_rect
			(start -2.450084 2.999994)
			(end 2.450084 -2.999994)
			(stroke
				(width 0)
				(type default)
			)
			(fill no)
			(layer "F.CrtYd")
		)
		(fp_poly
			(pts
				(xy -2.8194 3.6322) (xy -2.8194 -3.6322) (xy 2.8194 -3.6322) (xy 2.8194 1.18364) (xy 2.450084 1.18364)
				(xy 2.450084 -2.999994) (xy -2.450084 -2.999994) (xy -2.450084 2.999994) (xy 2.450084 2.999994)
				(xy 2.450084 1.18618) (xy 2.8194 1.18618) (xy 2.8194 3.6322)
			)
			(stroke
				(width 0)
				(type default)
			)
			(fill no)
			(layer "F.CrtYd")
		)
		(fp_rect
			(start -2.8194 3.6322)
			(end 2.8194 -3.6322)
			(stroke
				(width 0)
				(type default)
			)
			(fill no)
			(layer "F.Fab")
		)
		(pad "1" smd rect
			(at -1.905 2.54)
			(size 0.635 1.651)
			(layers "F.Cu" "F.Mask" "F.Paste")
			(net "P12V_IN")
		)
		(pad "2" smd rect
			(at -0.635 2.54)
			(size 0.635 1.651)
			(layers "F.Cu" "F.Mask" "F.Paste")
			(net "P12V_IN")
		)
		(pad "3" smd rect
			(at 0.635 2.54)
			(size 0.635 1.651)
			(layers "F.Cu" "F.Mask" "F.Paste")
			(net "P12V_IN")
		)
		(pad "4" smd rect
			(at 1.905 2.54)
			(size 0.635 1.651)
			(layers "F.Cu" "F.Mask" "F.Paste")
			(net "GATE_FAN3_R")
		)
		(pad "5" smd rect
			(at 1.905 -2.54)
			(size 0.635 1.651)
			(layers "F.Cu" "F.Mask" "F.Paste")
			(net "P12V_FAN3")
		)
		(pad "6" smd rect
			(at 0.635 -2.54)
			(size 0.635 1.651)
			(layers "F.Cu" "F.Mask" "F.Paste")
			(net "P12V_FAN3")
		)
		(pad "7" smd rect
			(at -0.635 -2.54)
			(size 0.635 1.651)
			(layers "F.Cu" "F.Mask" "F.Paste")
			(net "P12V_FAN3")
		)
		(pad "8" smd rect
			(at -1.905 -2.54)
			(size 0.635 1.651)
			(layers "F.Cu" "F.Mask" "F.Paste")
			(net "P12V_FAN3")
		)
	)
	(footprint ""
		(layer "F.Cu")
		(at 483.300024 -143.91005 -90)
		(property "Reference" "HDDSAS23"
			(at 0 0 270)
			(layer "F.SilkS")
			(hide yes)
			(effects
				(font
					(size 1.27 1.27)
				)
			)
		)
		(property "Value" "SKT-SAS15P-14P-45-GP"
			(at -20.7645 -8.9789 270)
			(unlocked yes)
			(layer "F.Fab")
			(hide yes)
			(effects
				(font
					(size 1.016 1.016)
					(thickness 0.1524)
				)
			)
		)
		(property "Device Type" "10120818-001C-TRLF"
			(at -20.7645 -10.5029 270)
			(unlocked yes)
			(layer "F.Fab")
			(hide yes)
			(effects
				(font
					(size 1.016 1.016)
					(thickness 0.1524)
				)
			)
		)
		(duplicate_pad_numbers_are_jumpers no)
		(fp_line
			(start 1.651 4.2926)
			(end 1.651 3.0099)
			(stroke
				(width 0.1524)
				(type default)
			)
			(layer "F.SilkS")
		)
		(fp_line
			(start 8.509 4.2926)
			(end 1.651 4.2926)
			(stroke
				(width 0.1524)
				(type default)
			)
			(layer "F.SilkS")
		)
		(fp_line
			(start -23.4188 3.0099)
			(end -23.4188 -3.2512)
			(stroke
				(width 0.1524)
				(type default)
			)
			(layer "F.SilkS")
		)
		(fp_line
			(start 1.651 3.0099)
			(end -23.4188 3.0099)
			(stroke
				(width 0.1524)
				(type default)
			)
			(layer "F.SilkS")
		)
		(fp_line
			(start 8.509 3.0099)
			(end 8.509 4.2926)
			(stroke
				(width 0.1524)
				(type default)
			)
			(layer "F.SilkS")
		)
		(fp_line
			(start 23.4188 3.0099)
			(end 8.509 3.0099)
			(stroke
				(width 0.1524)
				(type default)
			)
			(layer "F.SilkS")
		)
		(fp_line
			(start -23.4188 -3.2512)
			(end 23.4188 -3.2512)
			(stroke
				(width 0.1524)
				(type default)
			)
			(layer "F.SilkS")
		)
		(fp_line
			(start 23.4188 -3.2512)
			(end 23.4188 3.0099)
			(stroke
				(width 0.1524)
				(type default)
			)
			(layer "F.SilkS")
		)
		(fp_line
			(start 15.5067 -3.3401)
			(end 16.2687 -3.3401)
			(stroke
				(width 0.3302)
				(type default)
			)
			(layer "F.SilkS")
		)
		(fp_poly
			(pts
				(xy 15.868904 -3.230372) (xy 16.503904 -3.865372) (xy 15.233904 -3.865372)
			)
			(stroke
				(width 0)
				(type default)
			)
			(fill yes)
			(layer "F.SilkS")
		)
		(fp_poly
			(pts
				(xy -22.8727 -2.7559) (xy 22.8727 -2.7559) (xy 22.8727 2.7559) (xy 8.255 2.7559) (xy 8.255 3.5179)
				(xy 1.905 3.5179) (xy 1.905 2.7559) (xy -22.8727 2.7559)
			)
			(stroke
				(width 0)
				(type default)
			)
			(fill no)
			(layer "F.CrtYd")
		)
		(fp_poly
			(pts
				(xy 1.397 4.5466) (xy 1.397 3.2639) (xy -23.6728 3.2639) (xy -23.6728 -3.5052) (xy 23.6728 -3.5052)
				(xy 23.6728 -0.00635) (xy 22.8727 -0.00635) (xy 22.8727 -2.7559) (xy -22.8727 -2.7559) (xy -22.8727 2.7559)
				(xy 1.905 2.7559) (xy 1.905 3.5179) (xy 8.255 3.5179) (xy 8.255 2.7559) (xy 22.8727 2.7559) (xy 22.8727 0.00635)
				(xy 23.6728 0.00635) (xy 23.6728 3.2639) (xy 8.763 3.2639) (xy 8.763 4.5466)
			)
			(stroke
				(width 0)
				(type default)
			)
			(fill no)
			(layer "F.CrtYd")
		)
		(fp_poly
			(pts
				(xy 1.397 4.5466) (xy 1.397 3.2639) (xy -23.6728 3.2639) (xy -23.6728 -3.5052) (xy 23.6728 -3.5052)
				(xy 23.6728 3.2639) (xy 8.763 3.2639) (xy 8.763 4.5466)
			)
			(stroke
				(width 0)
				(type default)
			)
			(fill no)
			(layer "F.Fab")
		)
		(pad "" np_thru_hole circle
			(at -18.874994 0 270)
			(size 0.254 0.254)
			(drill 1.3462)
			(layers "*.Cu" "*.Mask")
			(clearance 0.9017)
			(thermal_gap 0.9017)
		)
		(pad "" np_thru_hole circle
			(at 18.874994 0 270)
			(size 0.254 0.254)
			(drill 0.9398)
			(layers "*.Cu" "*.Mask")
			(clearance 0.6985)
			(thermal_gap 0.6985)
		)
		(pad "G1" smd rect
			(at 21.874988 0 270)
			(size 2.5908 2.5908)
			(layers "F.Cu" "F.Mask" "F.Paste")
			(net "GND")
		)
		(pad "G2" smd rect
			(at -21.874988 0 270)
			(size 2.5908 2.5908)
			(layers "F.Cu" "F.Mask" "F.Paste")
			(net "GND")
		)
		(pad "P1" smd rect
			(at 1.905 -1.82499 270)
			(size 0.6096 2.3622)
			(layers "F.Cu" "F.Mask" "F.Paste")
			(net "Net_1684")
		)
		(pad "P2" smd rect
			(at 0.635 -1.82499 270)
			(size 0.6096 2.3622)
			(layers "F.Cu" "F.Mask" "F.Paste")
			(net "Net_1685")
		)
		(pad "P3" smd rect
			(at -0.635 -1.82499 270)
			(size 0.6096 2.3622)
			(layers "F.Cu" "F.Mask" "F.Paste")
			(net "Net_1686")
		)
		(pad "P4" smd rect
			(at -1.905 -1.82499 270)
			(size 0.6096 2.3622)
			(layers "F.Cu" "F.Mask" "F.Paste")
			(net "GND")
		)
		(pad "P5" smd rect
			(at -3.175 -1.82499 270)
			(size 0.6096 2.3622)
			(layers "F.Cu" "F.Mask" "F.Paste")
			(net "HDD_PRSNT_23")
		)
		(pad "P6" smd rect
			(at -4.445 -1.82499 270)
			(size 0.6096 2.3622)
			(layers "F.Cu" "F.Mask" "F.Paste")
			(net "GND")
		)
		(pad "P7" smd rect
			(at -5.715 -1.82499 270)
			(size 0.6096 2.3622)
			(layers "F.Cu" "F.Mask" "F.Paste")
			(net "5V_PRE_23")
		)
		(pad "P8" smd rect
			(at -6.985 -1.82499 270)
			(size 0.6096 2.3622)
			(layers "F.Cu" "F.Mask" "F.Paste")
			(net "P5V_HDD23")
		)
		(pad "P9" smd rect
			(at -8.255 -1.82499 270)
			(size 0.6096 2.3622)
			(layers "F.Cu" "F.Mask" "F.Paste")
			(net "P5V_HDD23")
		)
		(pad "P10" smd rect
			(at -9.525 -1.82499 270)
			(size 0.6096 2.3622)
			(layers "F.Cu" "F.Mask" "F.Paste")
			(net "GND")
		)
		(pad "P11" smd rect
			(at -10.795 -1.82499 270)
			(size 0.6096 2.3622)
			(layers "F.Cu" "F.Mask" "F.Paste")
			(net "ACT_HDD_23")
		)
		(pad "P12" smd rect
			(at -12.065 -1.82499 270)
			(size 0.6096 2.3622)
			(layers "F.Cu" "F.Mask" "F.Paste")
			(net "GND")
		)
		(pad "P13" smd rect
			(at -13.335 -1.82499 270)
			(size 0.6096 2.3622)
			(layers "F.Cu" "F.Mask" "F.Paste")
			(net "12V_PRE_23")
		)
		(pad "P14" smd rect
			(at -14.605 -1.82499 270)
			(size 0.6096 2.3622)
			(layers "F.Cu" "F.Mask" "F.Paste")
			(net "P12V_HDD23")
		)
		(pad "P15" smd rect
			(at -15.875 -1.82499 270)
			(size 0.6096 2.3622)
			(layers "F.Cu" "F.Mask" "F.Paste")
			(net "P12V_HDD23")
		)
		(pad "S1" smd rect
			(at 15.875 -1.82499 270)
			(size 0.6096 2.3622)
			(layers "F.Cu" "F.Mask" "F.Paste")
			(net "GND")
		)
		(pad "S2" smd rect
			(at 14.605 -1.82499 270)
			(size 0.6096 2.3622)
			(layers "F.Cu" "F.Mask" "F.Paste")
			(net "SAS_HDD_RX_P23")
		)
		(pad "S3" smd rect
			(at 13.335 -1.82499 270)
			(size 0.6096 2.3622)
			(layers "F.Cu" "F.Mask" "F.Paste")
			(net "SAS_HDD_RX_N23")
		)
		(pad "S4" smd rect
			(at 12.065 -1.82499 270)
			(size 0.6096 2.3622)
			(layers "F.Cu" "F.Mask" "F.Paste")
			(net "GND")
		)
		(pad "S5" smd rect
			(at 10.795 -1.82499 270)
			(size 0.6096 2.3622)
			(layers "F.Cu" "F.Mask" "F.Paste")
			(net "PHY_DRV_B_TO_SCC_B_23_DN")
		)
		(pad "S6" smd rect
			(at 9.525 -1.82499 270)
			(size 0.6096 2.3622)
			(layers "F.Cu" "F.Mask" "F.Paste")
			(net "PHY_DRV_B_TO_SCC_B_23_DP")
		)
		(pad "S7" smd rect
			(at 8.255 -1.82499 270)
			(size 0.6096 2.3622)
			(layers "F.Cu" "F.Mask" "F.Paste")
			(net "GND")
		)
		(pad "S8" smd rect
			(at 7.480046 2.845054 270)
			(size 0.508 2.3622)
			(layers "F.Cu" "F.Mask" "F.Paste")
			(net "GND")
		)
		(pad "S9" smd rect
			(at 6.679946 2.845054 270)
			(size 0.508 2.3622)
			(layers "F.Cu" "F.Mask" "F.Paste")
			(net "Net_447")
		)
		(pad "S10" smd rect
			(at 5.8801 2.845054 270)
			(size 0.508 2.3622)
			(layers "F.Cu" "F.Mask" "F.Paste")
			(net "Net_339")
		)
		(pad "S11" smd rect
			(at 5.08 2.845054 270)
			(size 0.508 2.3622)
			(layers "F.Cu" "F.Mask" "F.Paste")
			(net "GND")
		)
		(pad "S12" smd rect
			(at 4.2799 2.845054 270)
			(size 0.508 2.3622)
			(layers "F.Cu" "F.Mask" "F.Paste")
			(net "Net_375")
		)
		(pad "S13" smd rect
			(at 3.480054 2.845054 270)
			(size 0.508 2.3622)
			(layers "F.Cu" "F.Mask" "F.Paste")
			(net "Net_411")
		)
		(pad "S14" smd rect
			(at 2.679954 2.845054 270)
			(size 0.508 2.3622)
			(layers "F.Cu" "F.Mask" "F.Paste")
			(net "GND")
		)
		(zone
			(layer "F.Cu")
			(hatch none 0.5)
			(connect_pads
				(clearance 0)
			)
			(min_thickness 0.25)
			(keepout
				(tracks not_allowed)
				(vias allowed)
				(pads allowed)
				(copperpour not_allowed)
				(footprints allowed)
			)
			(placement
				(enabled no)
				(sheetname "")
			)
			(fill
				(thermal_gap 0.5)
				(thermal_bridge_width 0.5)
				(island_removal_mode 0)
			)
			(polygon
				(pts
					(xy 486.957624 -160.64865) (xy 479.883724 -160.64865) (xy 479.883724 -167.58285) (xy 480.988624 -167.58285)
					(xy 480.988624 -163.46805) (xy 485.611424 -163.46805) (xy 485.611424 -167.58285) (xy 486.957624 -167.58285)
				)
			)
		)
		(zone
			(layer "F.Cu")
			(hatch none 0.5)
			(connect_pads
				(clearance 0)
			)
			(min_thickness 0.25)
			(keepout
				(tracks allowed)
				(vias not_allowed)
				(pads allowed)
				(copperpour not_allowed)
				(footprints allowed)
			)
			(placement
				(enabled no)
				(sheetname "")
			)
			(fill
				(thermal_gap 0.5)
				(thermal_bridge_width 0.5)
				(island_removal_mode 0)
			)
			(polygon
				(pts
					(xy 486.957624 -160.64865) (xy 479.883724 -160.64865) (xy 479.883724 -167.58285) (xy 480.988624 -167.58285)
					(xy 480.988624 -163.46805) (xy 485.611424 -163.46805) (xy 485.611424 -167.58285) (xy 486.957624 -167.58285)
				)
			)
		)
		(zone
			(layer "F.Cu")
			(hatch none 0.5)
			(connect_pads
				(clearance 0)
			)
			(min_thickness 0.25)
			(keepout
				(tracks allowed)
				(vias not_allowed)
				(pads allowed)
				(copperpour not_allowed)
				(footprints allowed)
			)
			(placement
				(enabled no)
				(sheetname "")
			)
			(fill
				(thermal_gap 0.5)
				(thermal_bridge_width 0.5)
				(island_removal_mode 0)
			)
			(polygon
				(pts
					(xy 486.957624 -127.17145) (xy 479.883724 -127.17145) (xy 479.883724 -120.23725) (xy 480.988624 -120.23725)
					(xy 480.988624 -124.35205) (xy 485.611424 -124.35205) (xy 485.611424 -120.23725) (xy 486.957624 -120.23725)
				)
			)
		)
		(zone
			(layer "F.Cu")
			(hatch none 0.5)
			(connect_pads
				(clearance 0)
			)
			(min_thickness 0.25)
			(keepout
				(tracks not_allowed)
				(vias allowed)
				(pads allowed)
				(copperpour not_allowed)
				(footprints allowed)
			)
			(placement
				(enabled no)
				(sheetname "")
			)
			(fill
				(thermal_gap 0.5)
				(thermal_bridge_width 0.5)
				(island_removal_mode 0)
			)
			(polygon
				(pts
					(xy 486.957624 -127.17145) (xy 479.883724 -127.17145) (xy 479.883724 -120.23725) (xy 480.988624 -120.23725)
					(xy 480.988624 -124.35205) (xy 485.611424 -124.35205) (xy 485.611424 -120.23725) (xy 486.957624 -120.23725)
				)
			)
		)
		(zone
			(layers "F.Cu" "B.Cu" "In1.Cu" "In2.Cu" "In3.Cu" "In4.Cu" "In5.Cu" "In6.Cu")
			(hatch none 0.5)
			(connect_pads
				(clearance 0)
			)
			(min_thickness 0.25)
			(keepout
				(tracks not_allowed)
				(vias allowed)
				(pads allowed)
				(copperpour not_allowed)
				(footprints allowed)
			)
			(placement
				(enabled no)
				(sheetname "")
			)
			(fill
				(thermal_gap 0.5)
				(thermal_bridge_width 0.5)
				(island_removal_mode 0)
			)
			(polygon
				(pts
					(arc
						(start 484.074724 -125.035056)
						(mid 482.525324 -125.035056)
						(end 484.074724 -125.035056)
					)
				)
			)
		)
		(zone
			(layers "F.Cu" "B.Cu" "In1.Cu" "In2.Cu" "In3.Cu" "In4.Cu" "In5.Cu" "In6.Cu")
			(hatch none 0.5)
			(connect_pads
				(clearance 0)
			)
			(min_thickness 0.25)
			(keepout
				(tracks not_allowed)
				(vias allowed)
				(pads allowed)
				(copperpour not_allowed)
				(footprints allowed)
			)
			(placement
				(enabled no)
				(sheetname "")
			)
			(fill
				(thermal_gap 0.5)
				(thermal_bridge_width 0.5)
				(island_removal_mode 0)
			)
			(polygon
				(pts
					(arc
						(start 484.277924 -162.785044)
						(mid 482.322124 -162.785044)
						(end 484.277924 -162.785044)
					)
				)
			)
		)
	)
	(footprint ""
		(layer "F.Cu")
		(at 248.524522 -366.623346 180)
		(property "Reference" "C570"
			(at 0 0 180)
			(layer "F.SilkS")
			(hide yes)
			(effects
				(font
					(size 1.27 1.27)
				)
			)
		)
		(property "Value" "SCD015U25V2KX-GP"
			(at 1.1811 -2.7051 180)
			(unlocked yes)
			(layer "F.Fab")
			(hide yes)
			(effects
				(font
					(size 1.016 1.016)
					(thickness 0.1524)
				)
			)
		)
		(property "Device Type" "C402H22"
			(at 1.1811 -4.2291 180)
			(unlocked yes)
			(layer "F.Fab")
			(hide yes)
			(effects
				(font
					(size 1.016 1.016)
					(thickness 0.1524)
				)
			)
		)
		(duplicate_pad_numbers_are_jumpers no)
		(fp_rect
			(start -0.4318 0.9525)
			(end 0.4318 -0.9525)
			(stroke
				(width 0)
				(type default)
			)
			(fill no)
			(layer "F.CrtYd")
		)
		(fp_rect
			(start -0.4318 0.9525)
			(end 0.4318 -0.9525)
			(stroke
				(width 0)
				(type default)
			)
			(fill no)
			(layer "F.Fab")
		)
		(pad "1" smd custom
			(at 0 -0.4445 180)
			(size 0.1524 0.1524)
			(layers "F.Cu" "F.Mask" "F.Paste")
			(net "MB3_HS_SENSE_P")
			(options
				(clearance outline)
				(anchor circle)
			)
			(primitives
				(gr_poly
					(pts
						(arc
							(start 0.3048 -0.2032)
							(mid 0.275042 -0.275042)
							(end 0.2032 -0.3048)
						)
						(arc
							(start -0.2032 -0.3048)
							(mid -0.275042 -0.275042)
							(end -0.3048 -0.2032)
						)
						(arc
							(start -0.3048 0.2032)
							(mid -0.275042 0.275042)
							(end -0.2032 0.3048)
						)
						(arc
							(start 0.2032 0.3048)
							(mid 0.275042 0.275042)
							(end 0.3048 0.2032)
						)
					)
					(width 0)
					(fill yes)
				)
			)
		)
		(pad "2" smd custom
			(at 0 0.4445 180)
			(size 0.1524 0.1524)
			(layers "F.Cu" "F.Mask" "F.Paste")
			(net "MB3_HS_SENSE_N")
			(options
				(clearance outline)
				(anchor circle)
			)
			(primitives
				(gr_poly
					(pts
						(arc
							(start 0.3048 -0.2032)
							(mid 0.275042 -0.275042)
							(end 0.2032 -0.3048)
						)
						(arc
							(start -0.2032 -0.3048)
							(mid -0.275042 -0.275042)
							(end -0.3048 -0.2032)
						)
						(arc
							(start -0.3048 0.2032)
							(mid -0.275042 0.275042)
							(end -0.2032 0.3048)
						)
						(arc
							(start 0.2032 0.3048)
							(mid 0.275042 0.275042)
							(end 0.3048 0.2032)
						)
					)
					(width 0)
					(fill yes)
				)
			)
		)
	)
	(footprint ""
		(layer "F.Cu")
		(at 129.67589 -362.745274 180)
		(property "Reference" "Q128"
			(at 0 0 180)
			(layer "F.SilkS")
			(hide yes)
			(effects
				(font
					(size 1.27 1.27)
				)
			)
		)
		(property "Value" "AO4407AL-GP"
			(at -3.707384 -1.5367 180)
			(unlocked yes)
			(layer "F.Fab")
			(hide yes)
			(effects
				(font
					(size 1.016 1.016)
					(thickness 0.1524)
				)
			)
		)
		(property "Device Type" "SOIC8H69"
			(at -3.707384 -3.0607 180)
			(unlocked yes)
			(layer "F.Fab")
			(hide yes)
			(effects
				(font
					(size 1.016 1.016)
					(thickness 0.1524)
				)
			)
		)
		(duplicate_pad_numbers_are_jumpers no)
		(fp_line
			(start 2.1336 1.4224)
			(end 2.1336 -1.4224)
			(stroke
				(width 0.1524)
				(type default)
			)
			(layer "F.SilkS")
		)
		(fp_line
			(start 2.1336 -1.4224)
			(end -2.7432 -1.4224)
			(stroke
				(width 0.1524)
				(type default)
			)
			(layer "F.SilkS")
		)
		(fp_line
			(start -2.1844 -0.0508)
			(end -2.7178 0.508)
			(stroke
				(width 0.1524)
				(type default)
			)
			(layer "F.SilkS")
		)
		(fp_line
			(start -2.6289 3.4417)
			(end -2.6289 1.4732)
			(stroke
				(width 0.381)
				(type default)
			)
			(layer "F.SilkS")
		)
		(fp_line
			(start -2.7178 -0.508)
			(end -2.1844 -0.0508)
			(stroke
				(width 0.1524)
				(type default)
			)
			(layer "F.SilkS")
		)
		(fp_line
			(start -2.7432 1.4224)
			(end 2.1336 1.4224)
			(stroke
				(width 0.1524)
				(type default)
			)
			(layer "F.SilkS")
		)
		(fp_line
			(start -2.7432 1.4224)
			(end -2.6416 1.4224)
			(stroke
				(width 0.1524)
				(type default)
			)
			(layer "F.SilkS")
		)
		(fp_line
			(start -2.7432 -1.4224)
			(end -2.7432 1.4224)
			(stroke
				(width 0.1524)
				(type default)
			)
			(layer "F.SilkS")
		)
		(fp_poly
			(pts
				(xy -2.2098 -1.4224) (xy -2.2098 1.4224) (xy 2.2098 1.4224) (xy 2.2098 -1.4224)
			)
			(stroke
				(width 0)
				(type default)
			)
			(fill yes)
			(layer "F.SilkS")
		)
		(fp_rect
			(start -2.450084 2.999994)
			(end 2.450084 -2.999994)
			(stroke
				(width 0)
				(type default)
			)
			(fill no)
			(layer "F.CrtYd")
		)
		(fp_poly
			(pts
				(xy -2.8194 3.6322) (xy -2.8194 -3.6322) (xy 2.8194 -3.6322) (xy 2.8194 1.18364) (xy 2.450084 1.18364)
				(xy 2.450084 -2.999994) (xy -2.450084 -2.999994) (xy -2.450084 2.999994) (xy 2.450084 2.999994)
				(xy 2.450084 1.18618) (xy 2.8194 1.18618) (xy 2.8194 3.6322)
			)
			(stroke
				(width 0)
				(type default)
			)
			(fill no)
			(layer "F.CrtYd")
		)
		(fp_rect
			(start -2.8194 3.6322)
			(end 2.8194 -3.6322)
			(stroke
				(width 0)
				(type default)
			)
			(fill no)
			(layer "F.Fab")
		)
		(pad "1" smd rect
			(at -1.905 2.54 180)
			(size 0.635 1.651)
			(layers "F.Cu" "F.Mask" "F.Paste")
			(net "P12V_IN")
		)
		(pad "2" smd rect
			(at -0.635 2.54 180)
			(size 0.635 1.651)
			(layers "F.Cu" "F.Mask" "F.Paste")
			(net "P12V_IN")
		)
		(pad "3" smd rect
			(at 0.635 2.54 180)
			(size 0.635 1.651)
			(layers "F.Cu" "F.Mask" "F.Paste")
			(net "P12V_IN")
		)
		(pad "4" smd rect
			(at 1.905 2.54 180)
			(size 0.635 1.651)
			(layers "F.Cu" "F.Mask" "F.Paste")
			(net "GATE_FAN1_R")
		)
		(pad "5" smd rect
			(at 1.905 -2.54 180)
			(size 0.635 1.651)
			(layers "F.Cu" "F.Mask" "F.Paste")
			(net "P12V_FAN1")
		)
		(pad "6" smd rect
			(at 0.635 -2.54 180)
			(size 0.635 1.651)
			(layers "F.Cu" "F.Mask" "F.Paste")
			(net "P12V_FAN1")
		)
		(pad "7" smd rect
			(at -0.635 -2.54 180)
			(size 0.635 1.651)
			(layers "F.Cu" "F.Mask" "F.Paste")
			(net "P12V_FAN1")
		)
		(pad "8" smd rect
			(at -1.905 -2.54 180)
			(size 0.635 1.651)
			(layers "F.Cu" "F.Mask" "F.Paste")
			(net "P12V_FAN1")
		)
	)
	(footprint ""
		(layer "F.Cu")
		(at 141.097 -145.796)
		(property "Reference" "Q72"
			(at 0 0 0)
			(layer "F.SilkS")
			(hide yes)
			(effects
				(font
					(size 1.27 1.27)
				)
			)
		)
		(property "Value" "AO4407AL-GP"
			(at -3.707384 -1.5367 0)
			(unlocked yes)
			(layer "F.Fab")
			(hide yes)
			(effects
				(font
					(size 1.016 1.016)
					(thickness 0.1524)
				)
			)
		)
		(property "Device Type" "SOIC8H69"
			(at -3.707384 -3.0607 0)
			(unlocked yes)
			(layer "F.Fab")
			(hide yes)
			(effects
				(font
					(size 1.016 1.016)
					(thickness 0.1524)
				)
			)
		)
		(duplicate_pad_numbers_are_jumpers no)
		(fp_line
			(start -2.7432 -1.4224)
			(end -2.7432 1.4224)
			(stroke
				(width 0.1524)
				(type default)
			)
			(layer "F.SilkS")
		)
		(fp_line
			(start -2.7432 1.4224)
			(end -2.6416 1.4224)
			(stroke
				(width 0.1524)
				(type default)
			)
			(layer "F.SilkS")
		)
		(fp_line
			(start -2.7432 1.4224)
			(end 2.1336 1.4224)
			(stroke
				(width 0.1524)
				(type default)
			)
			(layer "F.SilkS")
		)
		(fp_line
			(start -2.7178 -0.508)
			(end -2.1844 -0.0508)
			(stroke
				(width 0.1524)
				(type default)
			)
			(layer "F.SilkS")
		)
		(fp_line
			(start -2.6289 3.4417)
			(end -2.6289 1.4732)
			(stroke
				(width 0.381)
				(type default)
			)
			(layer "F.SilkS")
		)
		(fp_line
			(start -2.1844 -0.0508)
			(end -2.7178 0.508)
			(stroke
				(width 0.1524)
				(type default)
			)
			(layer "F.SilkS")
		)
		(fp_line
			(start 2.1336 -1.4224)
			(end -2.7432 -1.4224)
			(stroke
				(width 0.1524)
				(type default)
			)
			(layer "F.SilkS")
		)
		(fp_line
			(start 2.1336 1.4224)
			(end 2.1336 -1.4224)
			(stroke
				(width 0.1524)
				(type default)
			)
			(layer "F.SilkS")
		)
		(fp_poly
			(pts
				(xy -2.2098 -1.4224) (xy -2.2098 1.4224) (xy 2.2098 1.4224) (xy 2.2098 -1.4224)
			)
			(stroke
				(width 0)
				(type default)
			)
			(fill yes)
			(layer "F.SilkS")
		)
		(fp_rect
			(start -2.450084 2.999994)
			(end 2.450084 -2.999994)
			(stroke
				(width 0)
				(type default)
			)
			(fill no)
			(layer "F.CrtYd")
		)
		(fp_poly
			(pts
				(xy -2.8194 3.6322) (xy -2.8194 -3.6322) (xy 2.8194 -3.6322) (xy 2.8194 1.18364) (xy 2.450084 1.18364)
				(xy 2.450084 -2.999994) (xy -2.450084 -2.999994) (xy -2.450084 2.999994) (xy 2.450084 2.999994)
				(xy 2.450084 1.18618) (xy 2.8194 1.18618) (xy 2.8194 3.6322)
			)
			(stroke
				(width 0)
				(type default)
			)
			(fill no)
			(layer "F.CrtYd")
		)
		(fp_rect
			(start -2.8194 3.6322)
			(end 2.8194 -3.6322)
			(stroke
				(width 0)
				(type default)
			)
			(fill no)
			(layer "F.Fab")
		)
		(pad "1" smd rect
			(at -1.905 2.54)
			(size 0.635 1.651)
			(layers "F.Cu" "F.Mask" "F.Paste")
			(net "P12V_B")
		)
		(pad "2" smd rect
			(at -0.635 2.54)
			(size 0.635 1.651)
			(layers "F.Cu" "F.Mask" "F.Paste")
			(net "P12V_B")
		)
		(pad "3" smd rect
			(at 0.635 2.54)
			(size 0.635 1.651)
			(layers "F.Cu" "F.Mask" "F.Paste")
			(net "P12V_B")
		)
		(pad "4" smd rect
			(at 1.905 2.54)
			(size 0.635 1.651)
			(layers "F.Cu" "F.Mask" "F.Paste")
			(net "SW_HDD_N16")
		)
		(pad "5" smd rect
			(at 1.905 -2.54)
			(size 0.635 1.651)
			(layers "F.Cu" "F.Mask" "F.Paste")
			(net "P12V_HDD16")
		)
		(pad "6" smd rect
			(at 0.635 -2.54)
			(size 0.635 1.651)
			(layers "F.Cu" "F.Mask" "F.Paste")
			(net "P12V_HDD16")
		)
		(pad "7" smd rect
			(at -0.635 -2.54)
			(size 0.635 1.651)
			(layers "F.Cu" "F.Mask" "F.Paste")
			(net "P12V_HDD16")
		)
		(pad "8" smd rect
			(at -1.905 -2.54)
			(size 0.635 1.651)
			(layers "F.Cu" "F.Mask" "F.Paste")
			(net "P12V_HDD16")
		)
	)
	(footprint ""
		(layer "F.Cu")
		(at 35.306 -263.144 -90)
		(property "Reference" "R898"
			(at 0 0 270)
			(layer "F.SilkS")
			(hide yes)
			(effects
				(font
					(size 1.27 1.27)
				)
			)
		)
		(property "Value" "10KR2F-2-GP"
			(at 0.064008 -3.993896 270)
			(unlocked yes)
			(layer "F.Fab")
			(hide yes)
			(effects
				(font
					(size 1.016 1.016)
					(thickness 0.1524)
				)
			)
		)
		(property "Device Type" "R402H16"
			(at 0.064008 -5.517896 270)
			(unlocked yes)
			(layer "F.Fab")
			(hide yes)
			(effects
				(font
					(size 1.016 1.016)
					(thickness 0.1524)
				)
			)
		)
		(duplicate_pad_numbers_are_jumpers no)
		(fp_line
			(start -0.508 -0.9398)
			(end -0.508 0.9398)
			(stroke
				(width 0.1524)
				(type default)
			)
			(layer "F.SilkS")
		)
		(fp_line
			(start 0.508 -0.9398)
			(end -0.508 -0.9398)
			(stroke
				(width 0.1524)
				(type default)
			)
			(layer "F.SilkS")
		)
		(fp_rect
			(start -0.508 0.9398)
			(end 0.508 -0.9398)
			(stroke
				(width 0)
				(type default)
			)
			(fill no)
			(layer "F.CrtYd")
		)
		(fp_rect
			(start -0.508 0.9398)
			(end 0.508 -0.9398)
			(stroke
				(width 0)
				(type default)
			)
			(fill no)
			(layer "F.Fab")
		)
		(pad "1" smd custom
			(at 0 -0.4445 270)
			(size 0.1397 0.1397)
			(layers "F.Cu" "F.Mask" "F.Paste")
			(net "P3V3_STBY_B")
			(options
				(clearance outline)
				(anchor circle)
			)
			(primitives
				(gr_poly
					(pts
						(arc
							(start -0.1778 -0.2794)
							(mid -0.249642 -0.249642)
							(end -0.2794 -0.1778)
						)
						(arc
							(start -0.2794 0.1778)
							(mid -0.249642 0.249642)
							(end -0.1778 0.2794)
						)
						(arc
							(start 0.1778 0.2794)
							(mid 0.249642 0.249642)
							(end 0.2794 0.1778)
						)
						(arc
							(start 0.2794 -0.1778)
							(mid 0.249642 -0.249642)
							(end 0.1778 -0.2794)
						)
					)
					(width 0)
					(fill yes)
				)
			)
		)
		(pad "2" smd custom
			(at 0 0.4445 270)
			(size 0.1397 0.1397)
			(layers "F.Cu" "F.Mask" "F.Paste")
			(net "HDD_PRSNT_0")
			(options
				(clearance outline)
				(anchor circle)
			)
			(primitives
				(gr_poly
					(pts
						(arc
							(start -0.1778 -0.2794)
							(mid -0.249642 -0.249642)
							(end -0.2794 -0.1778)
						)
						(arc
							(start -0.2794 0.1778)
							(mid -0.249642 0.249642)
							(end -0.1778 0.2794)
						)
						(arc
							(start 0.1778 0.2794)
							(mid 0.249642 0.249642)
							(end 0.2794 0.1778)
						)
						(arc
							(start 0.2794 -0.1778)
							(mid 0.249642 -0.249642)
							(end 0.1778 -0.2794)
						)
					)
					(width 0)
					(fill yes)
				)
			)
		)
	)
	(footprint ""
		(layer "F.Cu")
		(at 24.257 -275.463 180)
		(property "Reference" "C504"
			(at 0 0 180)
			(layer "F.SilkS")
			(hide yes)
			(effects
				(font
					(size 1.27 1.27)
				)
			)
		)
		(property "Value" "SC1U25V3KX-GP"
			(at 0 -2.8194 180)
			(unlocked yes)
			(layer "F.Fab")
			(hide yes)
			(effects
				(font
					(size 1.016 1.016)
					(thickness 0.1524)
				)
			)
		)
		(property "Device Type" "C603H36"
			(at 0 -4.3434 180)
			(unlocked yes)
			(layer "F.Fab")
			(hide yes)
			(effects
				(font
					(size 1.016 1.016)
					(thickness 0.1524)
				)
			)
		)
		(duplicate_pad_numbers_are_jumpers no)
		(fp_line
			(start 0.508 0)
			(end -0.508 0)
			(stroke
				(width 0.2032)
				(type default)
			)
			(layer "F.SilkS")
		)
		(fp_rect
			(start -0.5842 1.3335)
			(end 0.5842 -1.3335)
			(stroke
				(width 0)
				(type default)
			)
			(fill no)
			(layer "F.CrtYd")
		)
		(fp_rect
			(start -0.5842 1.3335)
			(end 0.5842 -1.3335)
			(stroke
				(width 0)
				(type default)
			)
			(fill no)
			(layer "F.Fab")
		)
		(pad "1" smd custom
			(at 0 -0.762 180)
			(size 0.2159 0.2159)
			(layers "F.Cu" "F.Mask" "F.Paste")
			(net "P12V_HDD0")
			(options
				(clearance outline)
				(anchor circle)
			)
			(primitives
				(gr_poly
					(pts
						(arc
							(start -0.3302 -0.4318)
							(mid -0.402042 -0.402042)
							(end -0.4318 -0.3302)
						)
						(arc
							(start -0.4318 0.3302)
							(mid -0.402042 0.402042)
							(end -0.3302 0.4318)
						)
						(arc
							(start 0.3302 0.4318)
							(mid 0.402042 0.402042)
							(end 0.4318 0.3302)
						)
						(arc
							(start 0.4318 -0.3302)
							(mid 0.402042 -0.402042)
							(end 0.3302 -0.4318)
						)
					)
					(width 0)
					(fill yes)
				)
			)
		)
		(pad "2" smd custom
			(at 0 0.762 180)
			(size 0.2159 0.2159)
			(layers "F.Cu" "F.Mask" "F.Paste")
			(net "GND")
			(options
				(clearance outline)
				(anchor circle)
			)
			(primitives
				(gr_poly
					(pts
						(arc
							(start -0.3302 -0.4318)
							(mid -0.402042 -0.402042)
							(end -0.4318 -0.3302)
						)
						(arc
							(start -0.4318 0.3302)
							(mid -0.402042 0.402042)
							(end -0.3302 0.4318)
						)
						(arc
							(start 0.3302 0.4318)
							(mid 0.402042 0.402042)
							(end 0.4318 0.3302)
						)
						(arc
							(start 0.4318 -0.3302)
							(mid 0.402042 -0.402042)
							(end 0.3302 -0.4318)
						)
					)
					(width 0)
					(fill yes)
				)
			)
		)
	)
	(footprint ""
		(layer "F.Cu")
		(at 446.242186 -121.210578)
		(property "Reference" "TP205"
			(at 0 0 0)
			(layer "F.SilkS")
			(hide yes)
			(effects
				(font
					(size 1.27 1.27)
				)
			)
		)
		(property "Value" "*"
			(at -0.0508 -1.6764 0)
			(unlocked yes)
			(layer "F.Fab")
			(hide yes)
			(effects
				(font
					(size 1.016 1.016)
					(thickness 0.1524)
				)
			)
		)
		(property "Device Type" "TPAD32"
			(at -0.0508 -3.2004 0)
			(unlocked yes)
			(layer "F.Fab")
			(hide yes)
			(effects
				(font
					(size 1.016 1.016)
					(thickness 0.1524)
				)
			)
		)
		(duplicate_pad_numbers_are_jumpers no)
		(fp_poly
			(pts
				(arc
					(start 0.4064 0)
					(mid -0.4064 0)
					(end 0.4064 0)
				)
			)
			(stroke
				(width 0)
				(type default)
			)
			(fill no)
			(layer "F.CrtYd")
		)
		(fp_poly
			(pts
				(arc
					(start 0.7112 0)
					(mid -0.7112 0)
					(end 0.7112 0)
				)
			)
			(stroke
				(width 0)
				(type default)
			)
			(fill no)
			(layer "F.Fab")
		)
		(pad "1" smd circle
			(at 0 0)
			(size 0.8128 0.8128)
			(layers "F.Cu" "F.Mask" "F.Paste")
			(net "P5V_B_4_PGOOD")
		)
	)
	(footprint ""
		(layer "F.Cu")
		(at 469.773 -265.684 -90)
		(property "Reference" "C178"
			(at 0 0 270)
			(layer "F.SilkS")
			(hide yes)
			(effects
				(font
					(size 1.27 1.27)
				)
			)
		)
		(property "Value" "SC4D7U25V5KX-1-GP"
			(at -0.0762 -6.1214 270)
			(unlocked yes)
			(layer "F.Fab")
			(hide yes)
			(effects
				(font
					(size 1.016 1.016)
					(thickness 0.1524)
				)
			)
		)
		(property "Device Type" "C805H58"
			(at -0.0762 -8.1534 270)
			(unlocked yes)
			(layer "F.Fab")
			(hide yes)
			(effects
				(font
					(size 1.016 1.016)
					(thickness 0.1524)
				)
			)
		)
		(duplicate_pad_numbers_are_jumpers no)
		(fp_line
			(start 0.635 0)
			(end -0.635 0)
			(stroke
				(width 0.508)
				(type default)
			)
			(layer "F.SilkS")
		)
		(fp_rect
			(start -0.9652 1.778)
			(end 0.9652 -1.778)
			(stroke
				(width 0)
				(type default)
			)
			(fill no)
			(layer "F.CrtYd")
		)
		(fp_poly
			(pts
				(xy -0.9652 -1.778) (xy 0.9652 -1.778) (xy 0.9652 1.778) (xy -0.9652 1.778)
			)
			(stroke
				(width 0)
				(type default)
			)
			(fill no)
			(layer "F.Fab")
		)
		(pad "1" smd rect
			(at 0 -0.9652 270)
			(size 1.397 1.143)
			(layers "F.Cu" "F.Mask" "F.Paste")
			(net "P12V_HDD11")
		)
		(pad "2" smd rect
			(at 0 0.9652 270)
			(size 1.397 1.143)
			(layers "F.Cu" "F.Mask" "F.Paste")
			(net "GND")
		)
	)
	(footprint ""
		(layer "F.Cu")
		(at 243.713 -311.912 180)
		(property "Reference" "R1092"
			(at 0 0 180)
			(layer "F.SilkS")
			(hide yes)
			(effects
				(font
					(size 1.27 1.27)
				)
			)
		)
		(property "Value" "0R2J-2-GP"
			(at 0.064008 -3.993896 180)
			(unlocked yes)
			(layer "F.Fab")
			(hide yes)
			(effects
				(font
					(size 1.016 1.016)
					(thickness 0.1524)
				)
			)
		)
		(property "Device Type" "R402H16"
			(at 0.064008 -5.517896 180)
			(unlocked yes)
			(layer "F.Fab")
			(hide yes)
			(effects
				(font
					(size 1.016 1.016)
					(thickness 0.1524)
				)
			)
		)
		(duplicate_pad_numbers_are_jumpers no)
		(fp_line
			(start 0.508 -0.9398)
			(end -0.508 -0.9398)
			(stroke
				(width 0.1524)
				(type default)
			)
			(layer "F.SilkS")
		)
		(fp_line
			(start -0.508 -0.9398)
			(end -0.508 0.9398)
			(stroke
				(width 0.1524)
				(type default)
			)
			(layer "F.SilkS")
		)
		(fp_rect
			(start -0.508 0.9398)
			(end 0.508 -0.9398)
			(stroke
				(width 0)
				(type default)
			)
			(fill no)
			(layer "F.CrtYd")
		)
		(fp_rect
			(start -0.508 0.9398)
			(end 0.508 -0.9398)
			(stroke
				(width 0)
				(type default)
			)
			(fill no)
			(layer "F.Fab")
		)
		(pad "1" smd custom
			(at 0 -0.4445 180)
			(size 0.1397 0.1397)
			(layers "F.Cu" "F.Mask" "F.Paste")
			(net "MAX31790_A_ADD1")
			(options
				(clearance outline)
				(anchor circle)
			)
			(primitives
				(gr_poly
					(pts
						(arc
							(start -0.1778 -0.2794)
							(mid -0.249642 -0.249642)
							(end -0.2794 -0.1778)
						)
						(arc
							(start -0.2794 0.1778)
							(mid -0.249642 0.249642)
							(end -0.1778 0.2794)
						)
						(arc
							(start 0.1778 0.2794)
							(mid 0.249642 0.249642)
							(end 0.2794 0.1778)
						)
						(arc
							(start 0.2794 -0.1778)
							(mid 0.249642 -0.249642)
							(end 0.1778 -0.2794)
						)
					)
					(width 0)
					(fill yes)
				)
			)
		)
		(pad "2" smd custom
			(at 0 0.4445 180)
			(size 0.1397 0.1397)
			(layers "F.Cu" "F.Mask" "F.Paste")
			(net "GND")
			(options
				(clearance outline)
				(anchor circle)
			)
			(primitives
				(gr_poly
					(pts
						(arc
							(start -0.1778 -0.2794)
							(mid -0.249642 -0.249642)
							(end -0.2794 -0.1778)
						)
						(arc
							(start -0.2794 0.1778)
							(mid -0.249642 0.249642)
							(end -0.1778 0.2794)
						)
						(arc
							(start 0.1778 0.2794)
							(mid 0.249642 0.249642)
							(end 0.2794 0.1778)
						)
						(arc
							(start 0.2794 -0.1778)
							(mid 0.249642 -0.249642)
							(end 0.1778 -0.2794)
						)
					)
					(width 0)
					(fill yes)
				)
			)
		)
	)
	(footprint ""
		(layer "F.Cu")
		(at 201.955654 -344.193114 90)
		(property "Reference" "Q197"
			(at 0 0 90)
			(layer "F.SilkS")
			(hide yes)
			(effects
				(font
					(size 1.27 1.27)
				)
			)
		)
		(property "Value" "IRFH8201TRPBF-GP"
			(at -4.2164 -4.3688 90)
			(unlocked yes)
			(layer "F.Fab")
			(hide yes)
			(effects
				(font
					(size 1.016 1.016)
					(thickness 0.1524)
				)
			)
		)
		(property "Device Type" "PPAK-5PH42"
			(at -4.2164 -5.8928 90)
			(unlocked yes)
			(layer "F.Fab")
			(hide yes)
			(effects
				(font
					(size 1.016 1.016)
					(thickness 0.1524)
				)
			)
		)
		(duplicate_pad_numbers_are_jumpers no)
		(fp_line
			(start 2.8956 -2.794)
			(end 2.8956 4.826)
			(stroke
				(width 0.1524)
				(type default)
			)
			(layer "F.SilkS")
		)
		(fp_line
			(start -2.8956 -2.794)
			(end 2.8956 -2.794)
			(stroke
				(width 0.1524)
				(type default)
			)
			(layer "F.SilkS")
		)
		(fp_line
			(start 2.8956 4.826)
			(end -2.8956 4.826)
			(stroke
				(width 0.1524)
				(type default)
			)
			(layer "F.SilkS")
		)
		(fp_line
			(start -2.8956 4.826)
			(end -2.8956 -2.794)
			(stroke
				(width 0.1524)
				(type default)
			)
			(layer "F.SilkS")
		)
		(fp_line
			(start -1.9431 4.9276)
			(end -3.0353 4.9276)
			(stroke
				(width 0.3302)
				(type default)
			)
			(layer "F.SilkS")
		)
		(fp_line
			(start -3.0353 4.9276)
			(end -3.0353 3.9624)
			(stroke
				(width 0.3302)
				(type default)
			)
			(layer "F.SilkS")
		)
		(fp_poly
			(pts
				(xy -2.3622 5.334) (xy -1.4986 5.334) (xy -1.9304 4.9022)
			)
			(stroke
				(width 0)
				(type default)
			)
			(fill yes)
			(layer "F.SilkS")
		)
		(fp_poly
			(pts
				(xy 0.3556 -0.3556) (xy 2.6416 -0.3556) (xy 2.6416 -2.54) (xy 0.3556 -2.54)
			)
			(stroke
				(width 0)
				(type default)
			)
			(fill yes)
			(layer "F.Paste")
		)
		(fp_poly
			(pts
				(xy -2.6416 -0.3556) (xy -0.3556 -0.3556) (xy -0.3556 -2.54) (xy -2.6416 -2.54)
			)
			(stroke
				(width 0)
				(type default)
			)
			(fill yes)
			(layer "F.Paste")
		)
		(fp_poly
			(pts
				(xy 0.3556 2.54) (xy 2.6416 2.54) (xy 2.6416 0.3556) (xy 0.3556 0.3556)
			)
			(stroke
				(width 0)
				(type default)
			)
			(fill yes)
			(layer "F.Paste")
		)
		(fp_poly
			(pts
				(xy -2.6416 2.54) (xy -0.3556 2.54) (xy -0.3556 0.3556) (xy -2.6416 0.3556)
			)
			(stroke
				(width 0)
				(type default)
			)
			(fill yes)
			(layer "F.Paste")
		)
		(fp_rect
			(start -2.5781 3.9878)
			(end 2.5781 -2.1082)
			(stroke
				(width 0)
				(type default)
			)
			(fill no)
			(layer "F.CrtYd")
		)
		(fp_poly
			(pts
				(xy -3.1496 5.08) (xy -3.1496 -3.048) (xy 3.1496 -3.048) (xy 3.1496 3.9751) (xy 2.5781 3.9751) (xy 2.5781 -2.1082)
				(xy -2.5781 -2.1082) (xy -2.5781 3.9878) (xy 3.1496 3.9878) (xy 3.1496 5.08)
			)
			(stroke
				(width 0)
				(type default)
			)
			(fill no)
			(layer "F.CrtYd")
		)
		(fp_rect
			(start -3.1496 5.08)
			(end 3.1496 -3.048)
			(stroke
				(width 0)
				(type default)
			)
			(fill no)
			(layer "F.Fab")
		)
		(pad "1" smd rect
			(at -1.905 3.81 90)
			(size 0.762 1.524)
			(layers "F.Cu" "F.Mask" "F.Paste")
			(net "P12V_IN")
		)
		(pad "2" smd rect
			(at -0.635 3.81 90)
			(size 0.762 1.524)
			(layers "F.Cu" "F.Mask" "F.Paste")
			(net "P12V_IN")
		)
		(pad "3" smd rect
			(at 0.635 3.81 90)
			(size 0.762 1.524)
			(layers "F.Cu" "F.Mask" "F.Paste")
			(net "P12V_IN")
		)
		(pad "4" smd rect
			(at 1.905 3.81 90)
			(size 0.762 1.524)
			(layers "F.Cu" "F.Mask" "F.Paste")
			(net "MB0_12V_CTRL_GATE4")
		)
		(pad "5" smd rect
			(at 0 0 90)
			(size 5.2832 5.08)
			(layers "F.Cu" "F.Mask" "F.Paste")
			(net "MB0_P12V_IN_R")
		)
		(pad "6" smd rect
			(at 0.635 -2.032 90)
			(size 0.0254 0.0254)
			(layers "F.Cu" "F.Mask" "F.Paste")
			(net "MB0_P12V_IN_R")
		)
		(pad "7" smd rect
			(at -0.635 -2.032 90)
			(size 0.0254 0.0254)
			(layers "F.Cu" "F.Mask" "F.Paste")
			(net "MB0_P12V_IN_R")
		)
		(pad "8" smd rect
			(at -1.905 -2.032 90)
			(size 0.0254 0.0254)
			(layers "F.Cu" "F.Mask" "F.Paste")
			(net "MB0_P12V_IN_R")
		)
	)
	(footprint ""
		(layer "F.Cu")
		(at 239.395 -228.219 -90)
		(property "Reference" "R513"
			(at 0 0 270)
			(layer "F.SilkS")
			(hide yes)
			(effects
				(font
					(size 1.27 1.27)
				)
			)
		)
		(property "Value" "100KR2F-L1-GP"
			(at 0.064008 -3.993896 270)
			(unlocked yes)
			(layer "F.Fab")
			(hide yes)
			(effects
				(font
					(size 1.016 1.016)
					(thickness 0.1524)
				)
			)
		)
		(property "Device Type" "R402H16"
			(at 0.064008 -5.517896 270)
			(unlocked yes)
			(layer "F.Fab")
			(hide yes)
			(effects
				(font
					(size 1.016 1.016)
					(thickness 0.1524)
				)
			)
		)
		(duplicate_pad_numbers_are_jumpers no)
		(fp_line
			(start -0.508 -0.9398)
			(end -0.508 0.9398)
			(stroke
				(width 0.1524)
				(type default)
			)
			(layer "F.SilkS")
		)
		(fp_line
			(start 0.508 -0.9398)
			(end -0.508 -0.9398)
			(stroke
				(width 0.1524)
				(type default)
			)
			(layer "F.SilkS")
		)
		(fp_rect
			(start -0.508 0.9398)
			(end 0.508 -0.9398)
			(stroke
				(width 0)
				(type default)
			)
			(fill no)
			(layer "F.CrtYd")
		)
		(fp_rect
			(start -0.508 0.9398)
			(end 0.508 -0.9398)
			(stroke
				(width 0)
				(type default)
			)
			(fill no)
			(layer "F.Fab")
		)
		(pad "1" smd custom
			(at 0 -0.4445 270)
			(size 0.1397 0.1397)
			(layers "F.Cu" "F.Mask" "F.Paste")
			(net "GPIO_VCC_U10")
			(options
				(clearance outline)
				(anchor circle)
			)
			(primitives
				(gr_poly
					(pts
						(arc
							(start -0.1778 -0.2794)
							(mid -0.249642 -0.249642)
							(end -0.2794 -0.1778)
						)
						(arc
							(start -0.2794 0.1778)
							(mid -0.249642 0.249642)
							(end -0.1778 0.2794)
						)
						(arc
							(start 0.1778 0.2794)
							(mid 0.249642 0.249642)
							(end 0.2794 0.1778)
						)
						(arc
							(start 0.2794 -0.1778)
							(mid 0.249642 -0.249642)
							(end 0.1778 -0.2794)
						)
					)
					(width 0)
					(fill yes)
				)
			)
		)
		(pad "2" smd custom
			(at 0 0.4445 270)
			(size 0.1397 0.1397)
			(layers "F.Cu" "F.Mask" "F.Paste")
			(net "GND")
			(options
				(clearance outline)
				(anchor circle)
			)
			(primitives
				(gr_poly
					(pts
						(arc
							(start -0.1778 -0.2794)
							(mid -0.249642 -0.249642)
							(end -0.2794 -0.1778)
						)
						(arc
							(start -0.2794 0.1778)
							(mid -0.249642 0.249642)
							(end -0.1778 0.2794)
						)
						(arc
							(start 0.1778 0.2794)
							(mid 0.249642 0.249642)
							(end 0.2794 0.1778)
						)
						(arc
							(start 0.2794 -0.1778)
							(mid 0.249642 -0.249642)
							(end 0.1778 -0.2794)
						)
					)
					(width 0)
					(fill yes)
				)
			)
		)
	)
	(footprint ""
		(layer "F.Cu")
		(at 74.369168 -212.390228 -90)
		(property "Reference" "R172"
			(at 0 0 270)
			(layer "F.SilkS")
			(hide yes)
			(effects
				(font
					(size 1.27 1.27)
				)
			)
		)
		(property "Value" "4K7R2F-GP"
			(at 0.064008 -3.993896 270)
			(unlocked yes)
			(layer "F.Fab")
			(hide yes)
			(effects
				(font
					(size 1.016 1.016)
					(thickness 0.1524)
				)
			)
		)
		(property "Device Type" "R402H16"
			(at 0.064008 -5.517896 270)
			(unlocked yes)
			(layer "F.Fab")
			(hide yes)
			(effects
				(font
					(size 1.016 1.016)
					(thickness 0.1524)
				)
			)
		)
		(duplicate_pad_numbers_are_jumpers no)
		(fp_line
			(start -0.508 -0.9398)
			(end -0.508 0.9398)
			(stroke
				(width 0.1524)
				(type default)
			)
			(layer "F.SilkS")
		)
		(fp_line
			(start 0.508 -0.9398)
			(end -0.508 -0.9398)
			(stroke
				(width 0.1524)
				(type default)
			)
			(layer "F.SilkS")
		)
		(fp_rect
			(start -0.508 0.9398)
			(end 0.508 -0.9398)
			(stroke
				(width 0)
				(type default)
			)
			(fill no)
			(layer "F.CrtYd")
		)
		(fp_rect
			(start -0.508 0.9398)
			(end 0.508 -0.9398)
			(stroke
				(width 0)
				(type default)
			)
			(fill no)
			(layer "F.Fab")
		)
		(pad "1" smd custom
			(at 0 -0.4445 270)
			(size 0.1397 0.1397)
			(layers "F.Cu" "F.Mask" "F.Paste")
			(net "DRIVE_B_2_ACT")
			(options
				(clearance outline)
				(anchor circle)
			)
			(primitives
				(gr_poly
					(pts
						(arc
							(start -0.1778 -0.2794)
							(mid -0.249642 -0.249642)
							(end -0.2794 -0.1778)
						)
						(arc
							(start -0.2794 0.1778)
							(mid -0.249642 0.249642)
							(end -0.1778 0.2794)
						)
						(arc
							(start 0.1778 0.2794)
							(mid 0.249642 0.249642)
							(end 0.2794 0.1778)
						)
						(arc
							(start 0.2794 -0.1778)
							(mid 0.249642 -0.249642)
							(end 0.1778 -0.2794)
						)
					)
					(width 0)
					(fill yes)
				)
			)
		)
		(pad "2" smd custom
			(at 0 0.4445 270)
			(size 0.1397 0.1397)
			(layers "F.Cu" "F.Mask" "F.Paste")
			(net "GND")
			(options
				(clearance outline)
				(anchor circle)
			)
			(primitives
				(gr_poly
					(pts
						(arc
							(start -0.1778 -0.2794)
							(mid -0.249642 -0.249642)
							(end -0.2794 -0.1778)
						)
						(arc
							(start -0.2794 0.1778)
							(mid -0.249642 0.249642)
							(end -0.1778 0.2794)
						)
						(arc
							(start 0.1778 0.2794)
							(mid 0.249642 0.249642)
							(end 0.2794 0.1778)
						)
						(arc
							(start 0.2794 -0.1778)
							(mid 0.249642 -0.249642)
							(end 0.1778 -0.2794)
						)
					)
					(width 0)
					(fill yes)
				)
			)
		)
	)
	(footprint ""
		(layer "F.Cu")
		(at 331.4954 -134.62 90)
		(property "Reference" "R491"
			(at 0 0 90)
			(layer "F.SilkS")
			(hide yes)
			(effects
				(font
					(size 1.27 1.27)
				)
			)
		)
		(property "Value" "4K7R2J-2-GP"
			(at 0.064008 -3.993896 90)
			(unlocked yes)
			(layer "F.Fab")
			(hide yes)
			(effects
				(font
					(size 1.016 1.016)
					(thickness 0.1524)
				)
			)
		)
		(property "Device Type" "R402H16"
			(at 0.064008 -5.517896 90)
			(unlocked yes)
			(layer "F.Fab")
			(hide yes)
			(effects
				(font
					(size 1.016 1.016)
					(thickness 0.1524)
				)
			)
		)
		(duplicate_pad_numbers_are_jumpers no)
		(fp_line
			(start 0.508 -0.9398)
			(end -0.508 -0.9398)
			(stroke
				(width 0.1524)
				(type default)
			)
			(layer "F.SilkS")
		)
		(fp_line
			(start -0.508 -0.9398)
			(end -0.508 0.9398)
			(stroke
				(width 0.1524)
				(type default)
			)
			(layer "F.SilkS")
		)
		(fp_rect
			(start -0.508 0.9398)
			(end 0.508 -0.9398)
			(stroke
				(width 0)
				(type default)
			)
			(fill no)
			(layer "F.CrtYd")
		)
		(fp_rect
			(start -0.508 0.9398)
			(end 0.508 -0.9398)
			(stroke
				(width 0)
				(type default)
			)
			(fill no)
			(layer "F.Fab")
		)
		(pad "1" smd custom
			(at 0 -0.4445 90)
			(size 0.1397 0.1397)
			(layers "F.Cu" "F.Mask" "F.Paste")
			(net "P12V_B")
			(options
				(clearance outline)
				(anchor circle)
			)
			(primitives
				(gr_poly
					(pts
						(arc
							(start -0.1778 -0.2794)
							(mid -0.249642 -0.249642)
							(end -0.2794 -0.1778)
						)
						(arc
							(start -0.2794 0.1778)
							(mid -0.249642 0.249642)
							(end -0.1778 0.2794)
						)
						(arc
							(start 0.1778 0.2794)
							(mid 0.249642 0.249642)
							(end 0.2794 0.1778)
						)
						(arc
							(start 0.2794 -0.1778)
							(mid 0.249642 -0.249642)
							(end 0.1778 -0.2794)
						)
					)
					(width 0)
					(fill yes)
				)
			)
		)
		(pad "2" smd custom
			(at 0 0.4445 90)
			(size 0.1397 0.1397)
			(layers "F.Cu" "F.Mask" "F.Paste")
			(net "SW_HDD_P18")
			(options
				(clearance outline)
				(anchor circle)
			)
			(primitives
				(gr_poly
					(pts
						(arc
							(start -0.1778 -0.2794)
							(mid -0.249642 -0.249642)
							(end -0.2794 -0.1778)
						)
						(arc
							(start -0.2794 0.1778)
							(mid -0.249642 0.249642)
							(end -0.1778 0.2794)
						)
						(arc
							(start 0.1778 0.2794)
							(mid 0.249642 0.249642)
							(end 0.2794 0.1778)
						)
						(arc
							(start 0.2794 -0.1778)
							(mid 0.249642 -0.249642)
							(end 0.1778 -0.2794)
						)
					)
					(width 0)
					(fill yes)
				)
			)
		)
	)
	(footprint ""
		(layer "F.Cu")
		(at 281.94 -337.185 -90)
		(property "Reference" "C33"
			(at 0 0 270)
			(layer "F.SilkS")
			(hide yes)
			(effects
				(font
					(size 1.27 1.27)
				)
			)
		)
		(property "Value" "SC1U16V3KX-5GP"
			(at 0 -2.8194 270)
			(unlocked yes)
			(layer "F.Fab")
			(hide yes)
			(effects
				(font
					(size 1.016 1.016)
					(thickness 0.1524)
				)
			)
		)
		(property "Device Type" "C603H36"
			(at 0 -4.3434 270)
			(unlocked yes)
			(layer "F.Fab")
			(hide yes)
			(effects
				(font
					(size 1.016 1.016)
					(thickness 0.1524)
				)
			)
		)
		(duplicate_pad_numbers_are_jumpers no)
		(fp_line
			(start 0.508 0)
			(end -0.508 0)
			(stroke
				(width 0.2032)
				(type default)
			)
			(layer "F.SilkS")
		)
		(fp_rect
			(start -0.5842 1.3335)
			(end 0.5842 -1.3335)
			(stroke
				(width 0)
				(type default)
			)
			(fill no)
			(layer "F.CrtYd")
		)
		(fp_rect
			(start -0.5842 1.3335)
			(end 0.5842 -1.3335)
			(stroke
				(width 0)
				(type default)
			)
			(fill no)
			(layer "F.Fab")
		)
		(pad "1" smd custom
			(at 0 -0.762 270)
			(size 0.2159 0.2159)
			(layers "F.Cu" "F.Mask" "F.Paste")
			(net "P3V3_IN")
			(options
				(clearance outline)
				(anchor circle)
			)
			(primitives
				(gr_poly
					(pts
						(arc
							(start -0.3302 -0.4318)
							(mid -0.402042 -0.402042)
							(end -0.4318 -0.3302)
						)
						(arc
							(start -0.4318 0.3302)
							(mid -0.402042 0.402042)
							(end -0.3302 0.4318)
						)
						(arc
							(start 0.3302 0.4318)
							(mid 0.402042 0.402042)
							(end 0.4318 0.3302)
						)
						(arc
							(start 0.4318 -0.3302)
							(mid 0.402042 -0.402042)
							(end 0.3302 -0.4318)
						)
					)
					(width 0)
					(fill yes)
				)
			)
		)
		(pad "2" smd custom
			(at 0 0.762 270)
			(size 0.2159 0.2159)
			(layers "F.Cu" "F.Mask" "F.Paste")
			(net "GND")
			(options
				(clearance outline)
				(anchor circle)
			)
			(primitives
				(gr_poly
					(pts
						(arc
							(start -0.3302 -0.4318)
							(mid -0.402042 -0.402042)
							(end -0.4318 -0.3302)
						)
						(arc
							(start -0.4318 0.3302)
							(mid -0.402042 0.402042)
							(end -0.3302 0.4318)
						)
						(arc
							(start 0.3302 0.4318)
							(mid 0.402042 0.402042)
							(end 0.4318 0.3302)
						)
						(arc
							(start 0.4318 -0.3302)
							(mid 0.402042 -0.402042)
							(end 0.3302 -0.4318)
						)
					)
					(width 0)
					(fill yes)
				)
			)
		)
	)
	(footprint ""
		(layer "F.Cu")
		(at 181.483 -148.209)
		(property "Reference" "R460"
			(at 0 0 0)
			(layer "F.SilkS")
			(hide yes)
			(effects
				(font
					(size 1.27 1.27)
				)
			)
		)
		(property "Value" "2R6F-GP"
			(at -0.0508 -4.8514 0)
			(unlocked yes)
			(layer "F.Fab")
			(hide yes)
			(effects
				(font
					(size 1.016 1.016)
					(thickness 0.1524)
				)
			)
		)
		(property "Device Type" "R1206H26"
			(at 0 -6.3754 0)
			(unlocked yes)
			(layer "F.Fab")
			(hide yes)
			(effects
				(font
					(size 1.016 1.016)
					(thickness 0.1524)
				)
			)
		)
		(duplicate_pad_numbers_are_jumpers no)
		(fp_line
			(start -1.016 -2.2352)
			(end 1.016 -2.2352)
			(stroke
				(width 0.1524)
				(type default)
			)
			(layer "F.SilkS")
		)
		(fp_line
			(start -1.016 2.2352)
			(end -1.016 -2.2352)
			(stroke
				(width 0.1524)
				(type default)
			)
			(layer "F.SilkS")
		)
		(fp_line
			(start 1.016 -2.2352)
			(end 1.016 2.2352)
			(stroke
				(width 0.1524)
				(type default)
			)
			(layer "F.SilkS")
		)
		(fp_line
			(start 1.016 2.2352)
			(end -1.016 2.2352)
			(stroke
				(width 0.1524)
				(type default)
			)
			(layer "F.SilkS")
		)
		(fp_rect
			(start -1.0922 2.3114)
			(end 1.0922 -2.3114)
			(stroke
				(width 0)
				(type default)
			)
			(fill no)
			(layer "F.CrtYd")
		)
		(fp_poly
			(pts
				(xy -1.0922 -2.3114) (xy 1.0922 -2.3114) (xy 1.0922 2.3114) (xy -1.0922 2.3114)
			)
			(stroke
				(width 0)
				(type default)
			)
			(fill no)
			(layer "F.Fab")
		)
		(pad "1" smd rect
			(at 0 -1.397)
			(size 1.651 1.27)
			(layers "F.Cu" "F.Mask" "F.Paste")
			(net "P5V_HDD17")
		)
		(pad "2" smd rect
			(at 0 1.397)
			(size 1.651 1.27)
			(layers "F.Cu" "F.Mask" "F.Paste")
			(net "5V_PRE_17")
		)
	)
	(footprint ""
		(layer "F.Cu")
		(at 118.618 -42.291)
		(property "Reference" "C386"
			(at 0 0 0)
			(layer "F.SilkS")
			(hide yes)
			(effects
				(font
					(size 1.27 1.27)
				)
			)
		)
		(property "Value" "SC4D7U25V5KX-1-GP"
			(at -0.0762 -6.1214 0)
			(unlocked yes)
			(layer "F.Fab")
			(hide yes)
			(effects
				(font
					(size 1.016 1.016)
					(thickness 0.1524)
				)
			)
		)
		(property "Device Type" "C805H58"
			(at -0.0762 -8.1534 0)
			(unlocked yes)
			(layer "F.Fab")
			(hide yes)
			(effects
				(font
					(size 1.016 1.016)
					(thickness 0.1524)
				)
			)
		)
		(duplicate_pad_numbers_are_jumpers no)
		(fp_line
			(start 0.635 0)
			(end -0.635 0)
			(stroke
				(width 0.508)
				(type default)
			)
			(layer "F.SilkS")
		)
		(fp_rect
			(start -0.9652 1.778)
			(end 0.9652 -1.778)
			(stroke
				(width 0)
				(type default)
			)
			(fill no)
			(layer "F.CrtYd")
		)
		(fp_poly
			(pts
				(xy -0.9652 -1.778) (xy 0.9652 -1.778) (xy 0.9652 1.778) (xy -0.9652 1.778)
			)
			(stroke
				(width 0)
				(type default)
			)
			(fill no)
			(layer "F.Fab")
		)
		(pad "1" smd rect
			(at 0 -0.9652)
			(size 1.397 1.143)
			(layers "F.Cu" "F.Mask" "F.Paste")
			(net "P12V_HDD27")
		)
		(pad "2" smd rect
			(at 0 0.9652)
			(size 1.397 1.143)
			(layers "F.Cu" "F.Mask" "F.Paste")
			(net "GND")
		)
	)
	(footprint ""
		(layer "F.Cu")
		(at 41.275 -6.3754 -90)
		(property "Reference" "R125"
			(at 0 0 270)
			(layer "F.SilkS")
			(hide yes)
			(effects
				(font
					(size 1.27 1.27)
				)
			)
		)
		(property "Value" "4K7R2F-GP"
			(at 0.064008 -3.993896 270)
			(unlocked yes)
			(layer "F.Fab")
			(hide yes)
			(effects
				(font
					(size 1.016 1.016)
					(thickness 0.1524)
				)
			)
		)
		(property "Device Type" "R402H16"
			(at 0.064008 -5.517896 270)
			(unlocked yes)
			(layer "F.Fab")
			(hide yes)
			(effects
				(font
					(size 1.016 1.016)
					(thickness 0.1524)
				)
			)
		)
		(duplicate_pad_numbers_are_jumpers no)
		(fp_line
			(start -0.508 -0.9398)
			(end -0.508 0.9398)
			(stroke
				(width 0.1524)
				(type default)
			)
			(layer "F.SilkS")
		)
		(fp_line
			(start 0.508 -0.9398)
			(end -0.508 -0.9398)
			(stroke
				(width 0.1524)
				(type default)
			)
			(layer "F.SilkS")
		)
		(fp_rect
			(start -0.508 0.9398)
			(end 0.508 -0.9398)
			(stroke
				(width 0)
				(type default)
			)
			(fill no)
			(layer "F.CrtYd")
		)
		(fp_rect
			(start -0.508 0.9398)
			(end 0.508 -0.9398)
			(stroke
				(width 0)
				(type default)
			)
			(fill no)
			(layer "F.Fab")
		)
		(pad "1" smd custom
			(at 0 -0.4445 270)
			(size 0.1397 0.1397)
			(layers "F.Cu" "F.Mask" "F.Paste")
			(net "TEMP1_A1")
			(options
				(clearance outline)
				(anchor circle)
			)
			(primitives
				(gr_poly
					(pts
						(arc
							(start -0.1778 -0.2794)
							(mid -0.249642 -0.249642)
							(end -0.2794 -0.1778)
						)
						(arc
							(start -0.2794 0.1778)
							(mid -0.249642 0.249642)
							(end -0.1778 0.2794)
						)
						(arc
							(start 0.1778 0.2794)
							(mid 0.249642 0.249642)
							(end 0.2794 0.1778)
						)
						(arc
							(start 0.2794 -0.1778)
							(mid 0.249642 -0.249642)
							(end 0.1778 -0.2794)
						)
					)
					(width 0)
					(fill yes)
				)
			)
		)
		(pad "2" smd custom
			(at 0 0.4445 270)
			(size 0.1397 0.1397)
			(layers "F.Cu" "F.Mask" "F.Paste")
			(net "GND")
			(options
				(clearance outline)
				(anchor circle)
			)
			(primitives
				(gr_poly
					(pts
						(arc
							(start -0.1778 -0.2794)
							(mid -0.249642 -0.249642)
							(end -0.2794 -0.1778)
						)
						(arc
							(start -0.2794 0.1778)
							(mid -0.249642 0.249642)
							(end -0.1778 0.2794)
						)
						(arc
							(start 0.1778 0.2794)
							(mid 0.249642 0.249642)
							(end 0.2794 0.1778)
						)
						(arc
							(start 0.2794 -0.1778)
							(mid 0.249642 -0.249642)
							(end 0.1778 -0.2794)
						)
					)
					(width 0)
					(fill yes)
				)
			)
		)
	)
	(footprint ""
		(layer "F.Cu")
		(at 190.0428 -146.6342)
		(property "Reference" "C258"
			(at 0 0 0)
			(layer "F.SilkS")
			(hide yes)
			(effects
				(font
					(size 1.27 1.27)
				)
			)
		)
		(property "Value" "SCD01U50V2KX-1GP"
			(at 1.1811 -2.7051 0)
			(unlocked yes)
			(layer "F.Fab")
			(hide yes)
			(effects
				(font
					(size 1.016 1.016)
					(thickness 0.1524)
				)
			)
		)
		(property "Device Type" "C402H22"
			(at 1.1811 -4.2291 0)
			(unlocked yes)
			(layer "F.Fab")
			(hide yes)
			(effects
				(font
					(size 1.016 1.016)
					(thickness 0.1524)
				)
			)
		)
		(duplicate_pad_numbers_are_jumpers no)
		(fp_rect
			(start -0.4318 0.9525)
			(end 0.4318 -0.9525)
			(stroke
				(width 0)
				(type default)
			)
			(fill no)
			(layer "F.CrtYd")
		)
		(fp_rect
			(start -0.4318 0.9525)
			(end 0.4318 -0.9525)
			(stroke
				(width 0)
				(type default)
			)
			(fill no)
			(layer "F.Fab")
		)
		(pad "1" smd custom
			(at 0 -0.4445)
			(size 0.1524 0.1524)
			(layers "F.Cu" "F.Mask" "F.Paste")
			(net "HDD_PRSNT_17")
			(options
				(clearance outline)
				(anchor circle)
			)
			(primitives
				(gr_poly
					(pts
						(arc
							(start 0.3048 -0.2032)
							(mid 0.275042 -0.275042)
							(end 0.2032 -0.3048)
						)
						(arc
							(start -0.2032 -0.3048)
							(mid -0.275042 -0.275042)
							(end -0.3048 -0.2032)
						)
						(arc
							(start -0.3048 0.2032)
							(mid -0.275042 0.275042)
							(end -0.2032 0.3048)
						)
						(arc
							(start 0.2032 0.3048)
							(mid 0.275042 0.275042)
							(end 0.3048 0.2032)
						)
					)
					(width 0)
					(fill yes)
				)
			)
		)
		(pad "2" smd custom
			(at 0 0.4445)
			(size 0.1524 0.1524)
			(layers "F.Cu" "F.Mask" "F.Paste")
			(net "GND")
			(options
				(clearance outline)
				(anchor circle)
			)
			(primitives
				(gr_poly
					(pts
						(arc
							(start 0.3048 -0.2032)
							(mid 0.275042 -0.275042)
							(end 0.2032 -0.3048)
						)
						(arc
							(start -0.2032 -0.3048)
							(mid -0.275042 -0.275042)
							(end -0.3048 -0.2032)
						)
						(arc
							(start -0.3048 0.2032)
							(mid -0.275042 0.275042)
							(end -0.2032 0.3048)
						)
						(arc
							(start 0.2032 0.3048)
							(mid 0.275042 0.275042)
							(end 0.3048 0.2032)
						)
					)
					(width 0)
					(fill yes)
				)
			)
		)
	)
	(footprint ""
		(layer "F.Cu")
		(at 300.199806 -243.999766)
		(property "Reference" ""
			(at 0 0 0)
			(layer "F.SilkS")
			(hide yes)
			(effects
				(font
					(size 1.27 1.27)
				)
			)
		)
		(property "Value" "*"
			(at -8.398764 -8.057642 0)
			(unlocked yes)
			(layer "F.Fab")
			(hide yes)
			(effects
				(font
					(size 1.016 1.016)
					(thickness 0.1524)
				)
			)
		)
		(duplicate_pad_numbers_are_jumpers no)
		(fp_poly
			(pts
				(arc
					(start 7.3152 0)
					(mid 0 7.3152)
					(end -7.3152 0)
				)
				(arc
					(start -7.3152 -5.9944)
					(mid 0 -13.3096)
					(end 7.3152 -5.9944)
				)
			)
			(stroke
				(width 0)
				(type default)
			)
			(fill no)
			(layer "B.CrtYd")
		)
		(fp_poly
			(pts
				(arc
					(start 7.3152 0)
					(mid 0 7.3152)
					(end -7.3152 0)
				)
				(arc
					(start -7.3152 -5.9944)
					(mid 0 -13.3096)
					(end 7.3152 -5.9944)
				)
			)
			(stroke
				(width 0)
				(type default)
			)
			(fill no)
			(layer "F.CrtYd")
		)
		(fp_poly
			(pts
				(arc
					(start 7.3152 0)
					(mid 0 7.3152)
					(end -7.3152 0)
				)
				(arc
					(start -7.3152 -5.9944)
					(mid 0 -13.3096)
					(end 7.3152 -5.9944)
				)
			)
			(stroke
				(width 0)
				(type default)
			)
			(fill no)
			(layer "B.Fab")
		)
		(fp_poly
			(pts
				(arc
					(start 7.3152 0)
					(mid 0 7.3152)
					(end -7.3152 0)
				)
				(arc
					(start -7.3152 -5.9944)
					(mid 0 -13.3096)
					(end 7.3152 -5.9944)
				)
			)
			(stroke
				(width 0)
				(type default)
			)
			(fill no)
			(layer "F.Fab")
		)
		(pad "1" thru_hole oval
			(at 0 0)
			(size 14.0208 20.0152)
			(drill 0.0254
				(offset 0 -2.9972)
			)
			(layers "*.Cu" "*.Mask")
			(remove_unused_layers no)
			(net "Net_21")
			(clearance -1.002284)
			(thermal_gap 0.1524)
			(padstack
				(mode front_inner_back)
				(layer "Inner"
					(shape custom)
					(size 2.928012 2.928012)
					(options
						(anchor circle)
					)
					(primitives
						(gr_poly
							(pts
								(arc
									(start 4.571746 -2.084324)
									(mid 0.000333 7.430372)
									(end -4.571492 -2.084324)
								)
								(arc
									(start -4.571492 -2.084324)
									(mid -3.570296 -3.611977)
									(end -2.875026 -5.30098)
								)
								(arc
									(start -2.875026 -5.30098)
									(mid 0.000217 -7.43089)
									(end 2.87528 -5.30098)
								)
								(arc
									(start 2.87528 -5.30098)
									(mid 3.570511 -3.611956)
									(end 4.571746 -2.084324)
								)
							)
							(width 0)
							(fill yes)
						)
					)
					(clearance 0.1524)
				)
				(layer "B.Cu"
					(shape oval)
					(size 14.0208 20.0152)
					(offset 0 -2.9972)
					(clearance -1.002284)
				)
			)
		)
		(zone
			(layers "F.Cu" "B.Cu" "In1.Cu" "In2.Cu" "In3.Cu" "In4.Cu" "In5.Cu" "In6.Cu")
			(hatch none 0.5)
			(connect_pads
				(clearance 0)
			)
			(min_thickness 0.25)
			(keepout
				(tracks not_allowed)
				(vias allowed)
				(pads allowed)
				(copperpour not_allowed)
				(footprints allowed)
			)
			(placement
				(enabled no)
				(sheetname "")
			)
			(fill
				(thermal_gap 0.5)
				(thermal_bridge_width 0.5)
				(island_removal_mode 0)
			)
			(polygon
				(pts
					(arc
						(start 293.189406 -249.994166)
						(mid 300.199806 -257.004566)
						(end 307.210206 -249.994166)
					)
					(arc
						(start 307.210206 -243.999766)
						(mid 300.199806 -236.989366)
						(end 293.189406 -243.999766)
					)
				)
			)
		)
	)
	(footprint ""
		(layer "F.Cu")
		(at 144.526 -99.314)
		(property "Reference" "R421"
			(at 0 0 0)
			(layer "F.SilkS")
			(hide yes)
			(effects
				(font
					(size 1.27 1.27)
				)
			)
		)
		(property "Value" "91R3F-1-GP"
			(at -0.0254 -2.5146 0)
			(unlocked yes)
			(layer "F.Fab")
			(hide yes)
			(effects
				(font
					(size 1.016 1.016)
					(thickness 0.1524)
				)
			)
		)
		(property "Device Type" "R603H22"
			(at -0.0254 -4.0386 0)
			(unlocked yes)
			(layer "F.Fab")
			(hide yes)
			(effects
				(font
					(size 1.016 1.016)
					(thickness 0.1524)
				)
			)
		)
		(duplicate_pad_numbers_are_jumpers no)
		(fp_line
			(start -0.4826 0)
			(end -0.2032 0)
			(stroke
				(width 0.2032)
				(type default)
			)
			(layer "F.SilkS")
		)
		(fp_line
			(start 0.2032 0)
			(end 0.4826 0)
			(stroke
				(width 0.2032)
				(type default)
			)
			(layer "F.SilkS")
		)
		(fp_rect
			(start -0.5842 1.3335)
			(end 0.5842 -1.3335)
			(stroke
				(width 0)
				(type default)
			)
			(fill no)
			(layer "F.CrtYd")
		)
		(fp_rect
			(start -0.5842 1.3335)
			(end 0.5842 -1.3335)
			(stroke
				(width 0)
				(type default)
			)
			(fill no)
			(layer "F.Fab")
		)
		(pad "1" smd custom
			(at 0 -0.762)
			(size 0.2159 0.2159)
			(layers "F.Cu" "F.Mask" "F.Paste")
			(net "P5V_B_2")
			(options
				(clearance outline)
				(anchor circle)
			)
			(primitives
				(gr_poly
					(pts
						(arc
							(start -0.3302 -0.4318)
							(mid -0.402042 -0.402042)
							(end -0.4318 -0.3302)
						)
						(arc
							(start -0.4318 0.3302)
							(mid -0.402042 0.402042)
							(end -0.3302 0.4318)
						)
						(arc
							(start 0.3302 0.4318)
							(mid 0.402042 0.402042)
							(end 0.4318 0.3302)
						)
						(arc
							(start 0.4318 -0.3302)
							(mid 0.402042 -0.402042)
							(end 0.3302 -0.4318)
						)
					)
					(width 0)
					(fill yes)
				)
			)
		)
		(pad "2" smd custom
			(at 0 0.762)
			(size 0.2159 0.2159)
			(layers "F.Cu" "F.Mask" "F.Paste")
			(net "DRV_ACT_16")
			(options
				(clearance outline)
				(anchor circle)
			)
			(primitives
				(gr_poly
					(pts
						(arc
							(start -0.3302 -0.4318)
							(mid -0.402042 -0.402042)
							(end -0.4318 -0.3302)
						)
						(arc
							(start -0.4318 0.3302)
							(mid -0.402042 0.402042)
							(end -0.3302 0.4318)
						)
						(arc
							(start 0.3302 0.4318)
							(mid 0.402042 0.402042)
							(end 0.4318 0.3302)
						)
						(arc
							(start 0.4318 -0.3302)
							(mid 0.402042 -0.402042)
							(end 0.3302 -0.4318)
						)
					)
					(width 0)
					(fill yes)
				)
			)
		)
	)
	(footprint ""
		(layer "F.Cu")
		(at 394.716 -250.5964 -90)
		(property "Reference" "C142"
			(at 0 0 270)
			(layer "F.SilkS")
			(hide yes)
			(effects
				(font
					(size 1.27 1.27)
				)
			)
		)
		(property "Value" "SCD033U25V2KX-GP"
			(at 1.1811 -2.7051 270)
			(unlocked yes)
			(layer "F.Fab")
			(hide yes)
			(effects
				(font
					(size 1.016 1.016)
					(thickness 0.1524)
				)
			)
		)
		(property "Device Type" "C402H22"
			(at 1.1811 -4.2291 270)
			(unlocked yes)
			(layer "F.Fab")
			(hide yes)
			(effects
				(font
					(size 1.016 1.016)
					(thickness 0.1524)
				)
			)
		)
		(duplicate_pad_numbers_are_jumpers no)
		(fp_rect
			(start -0.4318 0.9525)
			(end 0.4318 -0.9525)
			(stroke
				(width 0)
				(type default)
			)
			(fill no)
			(layer "F.CrtYd")
		)
		(fp_rect
			(start -0.4318 0.9525)
			(end 0.4318 -0.9525)
			(stroke
				(width 0)
				(type default)
			)
			(fill no)
			(layer "F.Fab")
		)
		(pad "1" smd custom
			(at 0 -0.4445 270)
			(size 0.1524 0.1524)
			(layers "F.Cu" "F.Mask" "F.Paste")
			(net "SW_HDD_P8")
			(options
				(clearance outline)
				(anchor circle)
			)
			(primitives
				(gr_poly
					(pts
						(arc
							(start 0.3048 -0.2032)
							(mid 0.275042 -0.275042)
							(end 0.2032 -0.3048)
						)
						(arc
							(start -0.2032 -0.3048)
							(mid -0.275042 -0.275042)
							(end -0.3048 -0.2032)
						)
						(arc
							(start -0.3048 0.2032)
							(mid -0.275042 0.275042)
							(end -0.2032 0.3048)
						)
						(arc
							(start 0.2032 0.3048)
							(mid 0.275042 0.275042)
							(end 0.3048 0.2032)
						)
					)
					(width 0)
					(fill yes)
				)
			)
		)
		(pad "2" smd custom
			(at 0 0.4445 270)
			(size 0.1524 0.1524)
			(layers "F.Cu" "F.Mask" "F.Paste")
			(net "GND")
			(options
				(clearance outline)
				(anchor circle)
			)
			(primitives
				(gr_poly
					(pts
						(arc
							(start 0.3048 -0.2032)
							(mid 0.275042 -0.275042)
							(end 0.2032 -0.3048)
						)
						(arc
							(start -0.2032 -0.3048)
							(mid -0.275042 -0.275042)
							(end -0.3048 -0.2032)
						)
						(arc
							(start -0.3048 0.2032)
							(mid -0.275042 0.275042)
							(end -0.2032 0.3048)
						)
						(arc
							(start 0.2032 0.3048)
							(mid 0.275042 0.275042)
							(end 0.3048 0.2032)
						)
					)
					(width 0)
					(fill yes)
				)
			)
		)
	)
	(footprint ""
		(layer "F.Cu")
		(at 477.0374 -37.9984)
		(property "Reference" "TP196"
			(at 0 0 0)
			(layer "F.SilkS")
			(hide yes)
			(effects
				(font
					(size 1.27 1.27)
				)
			)
		)
		(property "Value" "*"
			(at -0.0508 -1.6764 0)
			(unlocked yes)
			(layer "F.Fab")
			(hide yes)
			(effects
				(font
					(size 1.016 1.016)
					(thickness 0.1524)
				)
			)
		)
		(property "Device Type" "TPAD32"
			(at -0.0508 -3.2004 0)
			(unlocked yes)
			(layer "F.Fab")
			(hide yes)
			(effects
				(font
					(size 1.016 1.016)
					(thickness 0.1524)
				)
			)
		)
		(duplicate_pad_numbers_are_jumpers no)
		(fp_poly
			(pts
				(arc
					(start 0.4064 0)
					(mid -0.4064 0)
					(end 0.4064 0)
				)
			)
			(stroke
				(width 0)
				(type default)
			)
			(fill no)
			(layer "F.CrtYd")
		)
		(fp_poly
			(pts
				(arc
					(start 0.7112 0)
					(mid -0.7112 0)
					(end 0.7112 0)
				)
			)
			(stroke
				(width 0)
				(type default)
			)
			(fill no)
			(layer "F.Fab")
		)
		(pad "1" smd circle
			(at 0 0)
			(size 0.8128 0.8128)
			(layers "F.Cu" "F.Mask" "F.Paste")
			(net "ACT_HDD_35")
		)
	)
	(footprint ""
		(layer "F.Cu")
		(at 57.244996 -363.22 90)
		(property "Reference" "C522"
			(at 0 0 90)
			(layer "F.SilkS")
			(hide yes)
			(effects
				(font
					(size 1.27 1.27)
				)
			)
		)
		(property "Value" "SC1U25V3KX-GP"
			(at 0 -2.8194 90)
			(unlocked yes)
			(layer "F.Fab")
			(hide yes)
			(effects
				(font
					(size 1.016 1.016)
					(thickness 0.1524)
				)
			)
		)
		(property "Device Type" "C603H36"
			(at 0 -4.3434 90)
			(unlocked yes)
			(layer "F.Fab")
			(hide yes)
			(effects
				(font
					(size 1.016 1.016)
					(thickness 0.1524)
				)
			)
		)
		(duplicate_pad_numbers_are_jumpers no)
		(fp_line
			(start 0.508 0)
			(end -0.508 0)
			(stroke
				(width 0.2032)
				(type default)
			)
			(layer "F.SilkS")
		)
		(fp_rect
			(start -0.5842 1.3335)
			(end 0.5842 -1.3335)
			(stroke
				(width 0)
				(type default)
			)
			(fill no)
			(layer "F.CrtYd")
		)
		(fp_rect
			(start -0.5842 1.3335)
			(end 0.5842 -1.3335)
			(stroke
				(width 0)
				(type default)
			)
			(fill no)
			(layer "F.Fab")
		)
		(pad "1" smd custom
			(at 0 -0.762 90)
			(size 0.2159 0.2159)
			(layers "F.Cu" "F.Mask" "F.Paste")
			(net "P12V_FAN0")
			(options
				(clearance outline)
				(anchor circle)
			)
			(primitives
				(gr_poly
					(pts
						(arc
							(start -0.3302 -0.4318)
							(mid -0.402042 -0.402042)
							(end -0.4318 -0.3302)
						)
						(arc
							(start -0.4318 0.3302)
							(mid -0.402042 0.402042)
							(end -0.3302 0.4318)
						)
						(arc
							(start 0.3302 0.4318)
							(mid 0.402042 0.402042)
							(end 0.4318 0.3302)
						)
						(arc
							(start 0.4318 -0.3302)
							(mid 0.402042 -0.402042)
							(end 0.3302 -0.4318)
						)
					)
					(width 0)
					(fill yes)
				)
			)
		)
		(pad "2" smd custom
			(at 0 0.762 90)
			(size 0.2159 0.2159)
			(layers "F.Cu" "F.Mask" "F.Paste")
			(net "GND")
			(options
				(clearance outline)
				(anchor circle)
			)
			(primitives
				(gr_poly
					(pts
						(arc
							(start -0.3302 -0.4318)
							(mid -0.402042 -0.402042)
							(end -0.4318 -0.3302)
						)
						(arc
							(start -0.4318 0.3302)
							(mid -0.402042 0.402042)
							(end -0.3302 0.4318)
						)
						(arc
							(start 0.3302 0.4318)
							(mid 0.402042 0.402042)
							(end 0.4318 0.3302)
						)
						(arc
							(start 0.4318 -0.3302)
							(mid 0.402042 -0.402042)
							(end 0.3302 -0.4318)
						)
					)
					(width 0)
					(fill yes)
				)
			)
		)
	)
	(footprint ""
		(layer "F.Cu")
		(at 386.41655 -132.437124)
		(property "Reference" "VIA42"
			(at 0 0 0)
			(layer "F.SilkS")
			(hide yes)
			(effects
				(font
					(size 1.27 1.27)
				)
			)
		)
		(property "Value" "100OHM-8L-2D36MM-L16-GP"
			(at -3.4036 -0.4572 0)
			(unlocked yes)
			(layer "F.Fab")
			(hide yes)
			(effects
				(font
					(size 1.016 1.016)
					(thickness 0.1524)
				)
			)
		)
		(property "Device Type" "VIA-PCIE-4P-427097"
			(at -3.4036 -1.9812 0)
			(unlocked yes)
			(layer "F.Fab")
			(hide yes)
			(effects
				(font
					(size 1.016 1.016)
					(thickness 0.1524)
				)
			)
		)
		(duplicate_pad_numbers_are_jumpers no)
		(fp_rect
			(start -2.1336 0.4826)
			(end 2.1336 -0.4826)
			(stroke
				(width 0)
				(type default)
			)
			(fill no)
			(layer "F.CrtYd")
		)
		(fp_rect
			(start -2.1336 0.4826)
			(end 2.1336 -0.4826)
			(stroke
				(width 0)
				(type default)
			)
			(fill no)
			(layer "F.Fab")
		)
		(pad "1" thru_hole circle
			(at -1.651 0)
			(size 0.508 0.508)
			(drill 0.254)
			(layers "*.Cu" "*.Mask")
			(remove_unused_layers no)
			(net "GND")
			(clearance 0.2286)
			(thermal_gap 0.2286)
		)
		(pad "2" thru_hole circle
			(at -0.635 0)
			(size 0.508 0.508)
			(drill 0.254)
			(layers "*.Cu" "*.Mask")
			(remove_unused_layers no)
			(net "PHY_DRV_B_TO_SCC_B_20_DP")
			(clearance 0.2286)
			(thermal_gap 0.2286)
		)
		(pad "3" thru_hole circle
			(at 0.635 0)
			(size 0.508 0.508)
			(drill 0.254)
			(layers "*.Cu" "*.Mask")
			(remove_unused_layers no)
			(net "PHY_DRV_B_TO_SCC_B_20_DN")
			(clearance 0.2286)
			(thermal_gap 0.2286)
		)
		(pad "4" thru_hole circle
			(at 1.651 0)
			(size 0.508 0.508)
			(drill 0.254)
			(layers "*.Cu" "*.Mask")
			(remove_unused_layers no)
			(net "GND")
			(clearance 0.2286)
			(thermal_gap 0.2286)
		)
	)
	(footprint ""
		(layer "F.Cu")
		(at 256.499614 -227.34143 90)
		(property "Reference" "C39"
			(at 0 0 90)
			(layer "F.SilkS")
			(hide yes)
			(effects
				(font
					(size 1.27 1.27)
				)
			)
		)
		(property "Value" "SCD1U16V2KX-3GP"
			(at 1.1811 -2.7051 90)
			(unlocked yes)
			(layer "F.Fab")
			(hide yes)
			(effects
				(font
					(size 1.016 1.016)
					(thickness 0.1524)
				)
			)
		)
		(property "Device Type" "C402H22"
			(at 1.1811 -4.2291 90)
			(unlocked yes)
			(layer "F.Fab")
			(hide yes)
			(effects
				(font
					(size 1.016 1.016)
					(thickness 0.1524)
				)
			)
		)
		(duplicate_pad_numbers_are_jumpers no)
		(fp_rect
			(start -0.4318 0.9525)
			(end 0.4318 -0.9525)
			(stroke
				(width 0)
				(type default)
			)
			(fill no)
			(layer "F.CrtYd")
		)
		(fp_rect
			(start -0.4318 0.9525)
			(end 0.4318 -0.9525)
			(stroke
				(width 0)
				(type default)
			)
			(fill no)
			(layer "F.Fab")
		)
		(pad "1" smd custom
			(at 0 -0.4445 90)
			(size 0.1524 0.1524)
			(layers "F.Cu" "F.Mask" "F.Paste")
			(net "P5V_B_2_SENSE")
			(options
				(clearance outline)
				(anchor circle)
			)
			(primitives
				(gr_poly
					(pts
						(arc
							(start 0.3048 -0.2032)
							(mid 0.275042 -0.275042)
							(end 0.2032 -0.3048)
						)
						(arc
							(start -0.2032 -0.3048)
							(mid -0.275042 -0.275042)
							(end -0.3048 -0.2032)
						)
						(arc
							(start -0.3048 0.2032)
							(mid -0.275042 0.275042)
							(end -0.2032 0.3048)
						)
						(arc
							(start 0.2032 0.3048)
							(mid 0.275042 0.275042)
							(end 0.3048 0.2032)
						)
					)
					(width 0)
					(fill yes)
				)
			)
		)
		(pad "2" smd custom
			(at 0 0.4445 90)
			(size 0.1524 0.1524)
			(layers "F.Cu" "F.Mask" "F.Paste")
			(net "GND")
			(options
				(clearance outline)
				(anchor circle)
			)
			(primitives
				(gr_poly
					(pts
						(arc
							(start 0.3048 -0.2032)
							(mid 0.275042 -0.275042)
							(end 0.2032 -0.3048)
						)
						(arc
							(start -0.2032 -0.3048)
							(mid -0.275042 -0.275042)
							(end -0.3048 -0.2032)
						)
						(arc
							(start -0.3048 0.2032)
							(mid -0.275042 0.275042)
							(end -0.2032 0.3048)
						)
						(arc
							(start 0.2032 0.3048)
							(mid 0.275042 0.275042)
							(end 0.3048 0.2032)
						)
					)
					(width 0)
					(fill yes)
				)
			)
		)
	)
	(footprint ""
		(layer "F.Cu")
		(at 52.197 -26.289 180)
		(property "Reference" "Q124"
			(at 0 0 180)
			(layer "F.SilkS")
			(hide yes)
			(effects
				(font
					(size 1.27 1.27)
				)
			)
		)
		(property "Value" "AO4406AL-GP"
			(at -3.707384 -1.5367 180)
			(unlocked yes)
			(layer "F.Fab")
			(hide yes)
			(effects
				(font
					(size 1.016 1.016)
					(thickness 0.1524)
				)
			)
		)
		(property "Device Type" "SOIC8H69"
			(at -3.707384 -3.0607 180)
			(unlocked yes)
			(layer "F.Fab")
			(hide yes)
			(effects
				(font
					(size 1.016 1.016)
					(thickness 0.1524)
				)
			)
		)
		(duplicate_pad_numbers_are_jumpers no)
		(fp_line
			(start 2.1336 1.4224)
			(end 2.1336 -1.4224)
			(stroke
				(width 0.1524)
				(type default)
			)
			(layer "F.SilkS")
		)
		(fp_line
			(start 2.1336 -1.4224)
			(end -2.7432 -1.4224)
			(stroke
				(width 0.1524)
				(type default)
			)
			(layer "F.SilkS")
		)
		(fp_line
			(start -2.1844 -0.0508)
			(end -2.7178 0.508)
			(stroke
				(width 0.1524)
				(type default)
			)
			(layer "F.SilkS")
		)
		(fp_line
			(start -2.6289 3.4417)
			(end -2.6289 1.4732)
			(stroke
				(width 0.381)
				(type default)
			)
			(layer "F.SilkS")
		)
		(fp_line
			(start -2.7178 -0.508)
			(end -2.1844 -0.0508)
			(stroke
				(width 0.1524)
				(type default)
			)
			(layer "F.SilkS")
		)
		(fp_line
			(start -2.7432 1.4224)
			(end 2.1336 1.4224)
			(stroke
				(width 0.1524)
				(type default)
			)
			(layer "F.SilkS")
		)
		(fp_line
			(start -2.7432 1.4224)
			(end -2.6416 1.4224)
			(stroke
				(width 0.1524)
				(type default)
			)
			(layer "F.SilkS")
		)
		(fp_line
			(start -2.7432 -1.4224)
			(end -2.7432 1.4224)
			(stroke
				(width 0.1524)
				(type default)
			)
			(layer "F.SilkS")
		)
		(fp_poly
			(pts
				(xy -2.2098 -1.4224) (xy -2.2098 1.4224) (xy 2.2098 1.4224) (xy 2.2098 -1.4224)
			)
			(stroke
				(width 0)
				(type default)
			)
			(fill yes)
			(layer "F.SilkS")
		)
		(fp_rect
			(start -2.450084 2.999994)
			(end 2.450084 -2.999994)
			(stroke
				(width 0)
				(type default)
			)
			(fill no)
			(layer "F.CrtYd")
		)
		(fp_poly
			(pts
				(xy -2.8194 3.6322) (xy -2.8194 -3.6322) (xy 2.8194 -3.6322) (xy 2.8194 1.18364) (xy 2.450084 1.18364)
				(xy 2.450084 -2.999994) (xy -2.450084 -2.999994) (xy -2.450084 2.999994) (xy 2.450084 2.999994)
				(xy 2.450084 1.18618) (xy 2.8194 1.18618) (xy 2.8194 3.6322)
			)
			(stroke
				(width 0)
				(type default)
			)
			(fill no)
			(layer "F.CrtYd")
		)
		(fp_rect
			(start -2.8194 3.6322)
			(end 2.8194 -3.6322)
			(stroke
				(width 0)
				(type default)
			)
			(fill no)
			(layer "F.Fab")
		)
		(pad "1" smd rect
			(at -1.905 2.54 180)
			(size 0.635 1.651)
			(layers "F.Cu" "F.Mask" "F.Paste")
			(net "P5V_HDD25")
		)
		(pad "2" smd rect
			(at -0.635 2.54 180)
			(size 0.635 1.651)
			(layers "F.Cu" "F.Mask" "F.Paste")
			(net "P5V_HDD25")
		)
		(pad "3" smd rect
			(at 0.635 2.54 180)
			(size 0.635 1.651)
			(layers "F.Cu" "F.Mask" "F.Paste")
			(net "P5V_HDD25")
		)
		(pad "4" smd rect
			(at 1.905 2.54 180)
			(size 0.635 1.651)
			(layers "F.Cu" "F.Mask" "F.Paste")
			(net "SW_HDD_P25")
		)
		(pad "5" smd rect
			(at 1.905 -2.54 180)
			(size 0.635 1.651)
			(layers "F.Cu" "F.Mask" "F.Paste")
			(net "P5V_B_2")
		)
		(pad "6" smd rect
			(at 0.635 -2.54 180)
			(size 0.635 1.651)
			(layers "F.Cu" "F.Mask" "F.Paste")
			(net "P5V_B_2")
		)
		(pad "7" smd rect
			(at -0.635 -2.54 180)
			(size 0.635 1.651)
			(layers "F.Cu" "F.Mask" "F.Paste")
			(net "P5V_B_2")
		)
		(pad "8" smd rect
			(at -1.905 -2.54 180)
			(size 0.635 1.651)
			(layers "F.Cu" "F.Mask" "F.Paste")
			(net "P5V_B_2")
		)
	)
	(footprint ""
		(layer "F.Cu")
		(at 35.306 -148.082 -90)
		(property "Reference" "R351"
			(at 0 0 270)
			(layer "F.SilkS")
			(hide yes)
			(effects
				(font
					(size 1.27 1.27)
				)
			)
		)
		(property "Value" "10KR2F-2-GP"
			(at 0.064008 -3.993896 270)
			(unlocked yes)
			(layer "F.Fab")
			(hide yes)
			(effects
				(font
					(size 1.016 1.016)
					(thickness 0.1524)
				)
			)
		)
		(property "Device Type" "R402H16"
			(at 0.064008 -5.517896 270)
			(unlocked yes)
			(layer "F.Fab")
			(hide yes)
			(effects
				(font
					(size 1.016 1.016)
					(thickness 0.1524)
				)
			)
		)
		(duplicate_pad_numbers_are_jumpers no)
		(fp_line
			(start -0.508 -0.9398)
			(end -0.508 0.9398)
			(stroke
				(width 0.1524)
				(type default)
			)
			(layer "F.SilkS")
		)
		(fp_line
			(start 0.508 -0.9398)
			(end -0.508 -0.9398)
			(stroke
				(width 0.1524)
				(type default)
			)
			(layer "F.SilkS")
		)
		(fp_rect
			(start -0.508 0.9398)
			(end 0.508 -0.9398)
			(stroke
				(width 0)
				(type default)
			)
			(fill no)
			(layer "F.CrtYd")
		)
		(fp_rect
			(start -0.508 0.9398)
			(end 0.508 -0.9398)
			(stroke
				(width 0)
				(type default)
			)
			(fill no)
			(layer "F.Fab")
		)
		(pad "1" smd custom
			(at 0 -0.4445 270)
			(size 0.1397 0.1397)
			(layers "F.Cu" "F.Mask" "F.Paste")
			(net "P3V3_STBY_B")
			(options
				(clearance outline)
				(anchor circle)
			)
			(primitives
				(gr_poly
					(pts
						(arc
							(start -0.1778 -0.2794)
							(mid -0.249642 -0.249642)
							(end -0.2794 -0.1778)
						)
						(arc
							(start -0.2794 0.1778)
							(mid -0.249642 0.249642)
							(end -0.1778 0.2794)
						)
						(arc
							(start 0.1778 0.2794)
							(mid 0.249642 0.249642)
							(end 0.2794 0.1778)
						)
						(arc
							(start 0.2794 -0.1778)
							(mid 0.249642 -0.249642)
							(end 0.1778 -0.2794)
						)
					)
					(width 0)
					(fill yes)
				)
			)
		)
		(pad "2" smd custom
			(at 0 0.4445 270)
			(size 0.1397 0.1397)
			(layers "F.Cu" "F.Mask" "F.Paste")
			(net "HDD_PRSNT_12")
			(options
				(clearance outline)
				(anchor circle)
			)
			(primitives
				(gr_poly
					(pts
						(arc
							(start -0.1778 -0.2794)
							(mid -0.249642 -0.249642)
							(end -0.2794 -0.1778)
						)
						(arc
							(start -0.2794 0.1778)
							(mid -0.249642 0.249642)
							(end -0.1778 0.2794)
						)
						(arc
							(start 0.1778 0.2794)
							(mid 0.249642 0.249642)
							(end 0.2794 0.1778)
						)
						(arc
							(start 0.2794 -0.1778)
							(mid 0.249642 -0.249642)
							(end 0.1778 -0.2794)
						)
					)
					(width 0)
					(fill yes)
				)
			)
		)
	)
	(footprint ""
		(layer "F.Cu")
		(at 331.47 -32.004 -90)
		(property "Reference" "R759"
			(at 0 0 270)
			(layer "F.SilkS")
			(hide yes)
			(effects
				(font
					(size 1.27 1.27)
				)
			)
		)
		(property "Value" "2R6F-GP"
			(at -0.0508 -4.8514 270)
			(unlocked yes)
			(layer "F.Fab")
			(hide yes)
			(effects
				(font
					(size 1.016 1.016)
					(thickness 0.1524)
				)
			)
		)
		(property "Device Type" "R1206H26"
			(at 0 -6.3754 270)
			(unlocked yes)
			(layer "F.Fab")
			(hide yes)
			(effects
				(font
					(size 1.016 1.016)
					(thickness 0.1524)
				)
			)
		)
		(duplicate_pad_numbers_are_jumpers no)
		(fp_line
			(start -1.016 2.2352)
			(end -1.016 -2.2352)
			(stroke
				(width 0.1524)
				(type default)
			)
			(layer "F.SilkS")
		)
		(fp_line
			(start 1.016 2.2352)
			(end -1.016 2.2352)
			(stroke
				(width 0.1524)
				(type default)
			)
			(layer "F.SilkS")
		)
		(fp_line
			(start -1.016 -2.2352)
			(end 1.016 -2.2352)
			(stroke
				(width 0.1524)
				(type default)
			)
			(layer "F.SilkS")
		)
		(fp_line
			(start 1.016 -2.2352)
			(end 1.016 2.2352)
			(stroke
				(width 0.1524)
				(type default)
			)
			(layer "F.SilkS")
		)
		(fp_rect
			(start -1.0922 2.3114)
			(end 1.0922 -2.3114)
			(stroke
				(width 0)
				(type default)
			)
			(fill no)
			(layer "F.CrtYd")
		)
		(fp_poly
			(pts
				(xy -1.0922 -2.3114) (xy 1.0922 -2.3114) (xy 1.0922 2.3114) (xy -1.0922 2.3114)
			)
			(stroke
				(width 0)
				(type default)
			)
			(fill no)
			(layer "F.Fab")
		)
		(pad "1" smd rect
			(at 0 -1.397 270)
			(size 1.651 1.27)
			(layers "F.Cu" "F.Mask" "F.Paste")
			(net "P5V_HDD30")
		)
		(pad "2" smd rect
			(at 0 1.397 270)
			(size 1.651 1.27)
			(layers "F.Cu" "F.Mask" "F.Paste")
			(net "5V_PRE_30")
		)
	)
	(footprint ""
		(layer "F.Cu")
		(at 24.196802 -224.31375)
		(property "Reference" "R1101"
			(at 0 0 0)
			(layer "F.SilkS")
			(hide yes)
			(effects
				(font
					(size 1.27 1.27)
				)
			)
		)
		(property "Value" "0R3J-0-U-GP"
			(at -0.0254 -2.5146 0)
			(unlocked yes)
			(layer "F.Fab")
			(hide yes)
			(effects
				(font
					(size 1.016 1.016)
					(thickness 0.1524)
				)
			)
		)
		(property "Device Type" "R603H22"
			(at -0.0254 -4.0386 0)
			(unlocked yes)
			(layer "F.Fab")
			(hide yes)
			(effects
				(font
					(size 1.016 1.016)
					(thickness 0.1524)
				)
			)
		)
		(duplicate_pad_numbers_are_jumpers no)
		(fp_line
			(start -0.4826 0)
			(end -0.2032 0)
			(stroke
				(width 0.2032)
				(type default)
			)
			(layer "F.SilkS")
		)
		(fp_line
			(start 0.2032 0)
			(end 0.4826 0)
			(stroke
				(width 0.2032)
				(type default)
			)
			(layer "F.SilkS")
		)
		(fp_rect
			(start -0.5842 1.3335)
			(end 0.5842 -1.3335)
			(stroke
				(width 0)
				(type default)
			)
			(fill no)
			(layer "F.CrtYd")
		)
		(fp_rect
			(start -0.5842 1.3335)
			(end 0.5842 -1.3335)
			(stroke
				(width 0)
				(type default)
			)
			(fill no)
			(layer "F.Fab")
		)
		(pad "1" smd custom
			(at 0 -0.762)
			(size 0.2159 0.2159)
			(layers "F.Cu" "F.Mask" "F.Paste")
			(net "P5V_B_1_VBST")
			(options
				(clearance outline)
				(anchor circle)
			)
			(primitives
				(gr_poly
					(pts
						(arc
							(start -0.3302 -0.4318)
							(mid -0.402042 -0.402042)
							(end -0.4318 -0.3302)
						)
						(arc
							(start -0.4318 0.3302)
							(mid -0.402042 0.402042)
							(end -0.3302 0.4318)
						)
						(arc
							(start 0.3302 0.4318)
							(mid 0.402042 0.402042)
							(end 0.4318 0.3302)
						)
						(arc
							(start 0.4318 -0.3302)
							(mid 0.402042 -0.402042)
							(end 0.3302 -0.4318)
						)
					)
					(width 0)
					(fill yes)
				)
			)
		)
		(pad "2" smd custom
			(at 0 0.762)
			(size 0.2159 0.2159)
			(layers "F.Cu" "F.Mask" "F.Paste")
			(net "P5V_B_1_VBST_RC")
			(options
				(clearance outline)
				(anchor circle)
			)
			(primitives
				(gr_poly
					(pts
						(arc
							(start -0.3302 -0.4318)
							(mid -0.402042 -0.402042)
							(end -0.4318 -0.3302)
						)
						(arc
							(start -0.4318 0.3302)
							(mid -0.402042 0.402042)
							(end -0.3302 0.4318)
						)
						(arc
							(start 0.3302 0.4318)
							(mid 0.402042 0.402042)
							(end 0.4318 0.3302)
						)
						(arc
							(start 0.4318 -0.3302)
							(mid 0.402042 -0.402042)
							(end 0.3302 -0.4318)
						)
					)
					(width 0)
					(fill yes)
				)
			)
		)
	)
	(footprint ""
		(layer "F.Cu")
		(at 143.999966 -180.399944)
		(property "Reference" "LED5"
			(at 0 0 0)
			(layer "F.SilkS")
			(hide yes)
			(effects
				(font
					(size 1.27 1.27)
				)
			)
		)
		(property "Value" "LED-BY-19-GP"
			(at -2.132076 1.414018 0)
			(unlocked yes)
			(layer "F.Fab")
			(hide yes)
			(effects
				(font
					(size 1.016 1.016)
					(thickness 0.1524)
				)
			)
		)
		(property "Device Type" "LED-1615-4PH26"
			(at -2.132076 -0.109982 0)
			(unlocked yes)
			(layer "F.Fab")
			(hide yes)
			(effects
				(font
					(size 1.016 1.016)
					(thickness 0.1524)
				)
			)
		)
		(duplicate_pad_numbers_are_jumpers no)
		(fp_line
			(start -1.2954 0.254)
			(end -1.2954 1.6002)
			(stroke
				(width 0.508)
				(type default)
			)
			(layer "F.SilkS")
		)
		(fp_line
			(start -1.2954 1.6002)
			(end 1.2954 1.6002)
			(stroke
				(width 0.508)
				(type default)
			)
			(layer "F.SilkS")
		)
		(fp_line
			(start -1.1176 -1.4224)
			(end 1.1176 -1.4224)
			(stroke
				(width 0.1524)
				(type default)
			)
			(layer "F.SilkS")
		)
		(fp_line
			(start -1.1176 1.4224)
			(end -1.1176 -1.4224)
			(stroke
				(width 0.1524)
				(type default)
			)
			(layer "F.SilkS")
		)
		(fp_line
			(start 1.1176 -1.4224)
			(end 1.1176 1.4224)
			(stroke
				(width 0.1524)
				(type default)
			)
			(layer "F.SilkS")
		)
		(fp_line
			(start 1.1176 1.4224)
			(end -1.1176 1.4224)
			(stroke
				(width 0.1524)
				(type default)
			)
			(layer "F.SilkS")
		)
		(fp_line
			(start 1.2954 1.6002)
			(end 1.2954 0.254)
			(stroke
				(width 0.508)
				(type default)
			)
			(layer "F.SilkS")
		)
		(fp_rect
			(start -0.7493 0.8001)
			(end 0.7493 -0.8001)
			(stroke
				(width 0)
				(type default)
			)
			(fill no)
			(layer "F.CrtYd")
		)
		(fp_poly
			(pts
				(xy -1.3716 1.6764) (xy -1.3716 -1.6764) (xy 1.3716 -1.6764) (xy 1.3716 0.0635) (xy 0.7493 0.0635)
				(xy 0.7493 -0.8001) (xy -0.7493 -0.8001) (xy -0.7493 0.8001) (xy 0.7493 0.8001) (xy 0.7493 0.0762)
				(xy 1.3716 0.0762) (xy 1.3716 1.6764)
			)
			(stroke
				(width 0)
				(type default)
			)
			(fill no)
			(layer "F.CrtYd")
		)
		(fp_rect
			(start -1.3716 1.6764)
			(end 1.3716 -1.6764)
			(stroke
				(width 0)
				(type default)
			)
			(fill no)
			(layer "F.Fab")
		)
		(pad "1" smd rect
			(at 0.50038 -0.73025)
			(size 0.7112 0.8636)
			(layers "F.Cu" "F.Mask" "F.Paste")
			(net "DRV_ACT_4")
		)
		(pad "2" smd rect
			(at -0.50038 -0.73025)
			(size 0.7112 0.8636)
			(layers "F.Cu" "F.Mask" "F.Paste")
			(net "FLT_HDD4")
		)
		(pad "3" smd rect
			(at 0.50038 0.73025)
			(size 0.7112 0.8636)
			(layers "F.Cu" "F.Mask" "F.Paste")
			(net "DRV_ACT_4_N")
		)
		(pad "4" smd rect
			(at -0.50038 0.73025)
			(size 0.7112 0.8636)
			(layers "F.Cu" "F.Mask" "F.Paste")
			(net "FLT_HDD4_N")
		)
	)
	(footprint ""
		(layer "F.Cu")
		(at 189.009528 -366.124236 180)
		(property "Reference" "U50"
			(at 0 0 180)
			(layer "F.SilkS")
			(hide yes)
			(effects
				(font
					(size 1.27 1.27)
				)
			)
		)
		(property "Value" "SN74LVC1G08DCKR-GP"
			(at -2.3368 -8.6868 180)
			(unlocked yes)
			(layer "F.Fab")
			(hide yes)
			(effects
				(font
					(size 1.016 1.016)
					(thickness 0.1524)
				)
			)
		)
		(property "Device Type" "SC70-5H44"
			(at -2.3114 -10.414 180)
			(unlocked yes)
			(layer "F.Fab")
			(hide yes)
			(effects
				(font
					(size 1.016 1.016)
					(thickness 0.1524)
				)
			)
		)
		(duplicate_pad_numbers_are_jumpers no)
		(fp_line
			(start 1.3843 -1.8034)
			(end 1.3843 -1.1176)
			(stroke
				(width 0.3302)
				(type default)
			)
			(layer "F.SilkS")
		)
		(fp_line
			(start 1.27 1.7018)
			(end -1.27 1.7018)
			(stroke
				(width 0.1524)
				(type default)
			)
			(layer "F.SilkS")
		)
		(fp_line
			(start 1.27 -1.7018)
			(end 1.27 1.7018)
			(stroke
				(width 0.1524)
				(type default)
			)
			(layer "F.SilkS")
		)
		(fp_line
			(start 0.6604 -1.8034)
			(end 1.3843 -1.8034)
			(stroke
				(width 0.3302)
				(type default)
			)
			(layer "F.SilkS")
		)
		(fp_line
			(start -1.27 1.7018)
			(end -1.27 -1.7018)
			(stroke
				(width 0.1524)
				(type default)
			)
			(layer "F.SilkS")
		)
		(fp_line
			(start -1.27 -1.7018)
			(end 1.27 -1.7018)
			(stroke
				(width 0.1524)
				(type default)
			)
			(layer "F.SilkS")
		)
		(fp_rect
			(start -1.524 1.9558)
			(end 1.524 -1.9558)
			(stroke
				(width 0)
				(type default)
			)
			(fill no)
			(layer "F.CrtYd")
		)
		(fp_poly
			(pts
				(xy -1.524 -1.9558) (xy 1.524 -1.9558) (xy 1.524 1.9558) (xy -1.524 1.9558)
			)
			(stroke
				(width 0)
				(type default)
			)
			(fill no)
			(layer "F.Fab")
		)
		(pad "1" smd rect
			(at 0.65024 -0.8255 180)
			(size 0.4064 1.2192)
			(layers "F.Cu" "F.Mask" "F.Paste")
			(net "RDPB_FAN_LED1")
		)
		(pad "2" smd rect
			(at 0 -0.8255 180)
			(size 0.4064 1.2192)
			(layers "F.Cu" "F.Mask" "F.Paste")
			(net "FDPB_FAN_LED1")
		)
		(pad "3" smd rect
			(at -0.65024 -0.8255 180)
			(size 0.4064 1.2192)
			(layers "F.Cu" "F.Mask" "F.Paste")
			(net "GND")
		)
		(pad "4" smd rect
			(at -0.65024 0.8255 180)
			(size 0.4064 1.2192)
			(layers "F.Cu" "F.Mask" "F.Paste")
			(net "FAN_LED1")
		)
		(pad "5" smd rect
			(at 0.65024 0.8255 180)
			(size 0.4064 1.2192)
			(layers "F.Cu" "F.Mask" "F.Paste")
			(net "P3V3_IN")
		)
	)
	(footprint ""
		(layer "F.Cu")
		(at 426.2882 -135.6614 -90)
		(property "Reference" "C311"
			(at 0 0 270)
			(layer "F.SilkS")
			(hide yes)
			(effects
				(font
					(size 1.27 1.27)
				)
			)
		)
		(property "Value" "SCD033U25V2KX-GP"
			(at 1.1811 -2.7051 270)
			(unlocked yes)
			(layer "F.Fab")
			(hide yes)
			(effects
				(font
					(size 1.016 1.016)
					(thickness 0.1524)
				)
			)
		)
		(property "Device Type" "C402H22"
			(at 1.1811 -4.2291 270)
			(unlocked yes)
			(layer "F.Fab")
			(hide yes)
			(effects
				(font
					(size 1.016 1.016)
					(thickness 0.1524)
				)
			)
		)
		(duplicate_pad_numbers_are_jumpers no)
		(fp_rect
			(start -0.4318 0.9525)
			(end 0.4318 -0.9525)
			(stroke
				(width 0)
				(type default)
			)
			(fill no)
			(layer "F.CrtYd")
		)
		(fp_rect
			(start -0.4318 0.9525)
			(end 0.4318 -0.9525)
			(stroke
				(width 0)
				(type default)
			)
			(fill no)
			(layer "F.Fab")
		)
		(pad "1" smd custom
			(at 0 -0.4445 270)
			(size 0.1524 0.1524)
			(layers "F.Cu" "F.Mask" "F.Paste")
			(net "SW_HDD_P21")
			(options
				(clearance outline)
				(anchor circle)
			)
			(primitives
				(gr_poly
					(pts
						(arc
							(start 0.3048 -0.2032)
							(mid 0.275042 -0.275042)
							(end 0.2032 -0.3048)
						)
						(arc
							(start -0.2032 -0.3048)
							(mid -0.275042 -0.275042)
							(end -0.3048 -0.2032)
						)
						(arc
							(start -0.3048 0.2032)
							(mid -0.275042 0.275042)
							(end -0.2032 0.3048)
						)
						(arc
							(start 0.2032 0.3048)
							(mid 0.275042 0.275042)
							(end 0.3048 0.2032)
						)
					)
					(width 0)
					(fill yes)
				)
			)
		)
		(pad "2" smd custom
			(at 0 0.4445 270)
			(size 0.1524 0.1524)
			(layers "F.Cu" "F.Mask" "F.Paste")
			(net "GND")
			(options
				(clearance outline)
				(anchor circle)
			)
			(primitives
				(gr_poly
					(pts
						(arc
							(start 0.3048 -0.2032)
							(mid 0.275042 -0.275042)
							(end 0.2032 -0.3048)
						)
						(arc
							(start -0.2032 -0.3048)
							(mid -0.275042 -0.275042)
							(end -0.3048 -0.2032)
						)
						(arc
							(start -0.3048 0.2032)
							(mid -0.275042 0.275042)
							(end -0.2032 0.3048)
						)
						(arc
							(start 0.2032 0.3048)
							(mid 0.275042 0.275042)
							(end 0.3048 0.2032)
						)
					)
					(width 0)
					(fill yes)
				)
			)
		)
	)
	(footprint ""
		(layer "F.Cu")
		(at 308.701694 -212.390228 -90)
		(property "Reference" "R245"
			(at 0 0 270)
			(layer "F.SilkS")
			(hide yes)
			(effects
				(font
					(size 1.27 1.27)
				)
			)
		)
		(property "Value" "4K7R2F-GP"
			(at 0.064008 -3.993896 270)
			(unlocked yes)
			(layer "F.Fab")
			(hide yes)
			(effects
				(font
					(size 1.016 1.016)
					(thickness 0.1524)
				)
			)
		)
		(property "Device Type" "R402H16"
			(at 0.064008 -5.517896 270)
			(unlocked yes)
			(layer "F.Fab")
			(hide yes)
			(effects
				(font
					(size 1.016 1.016)
					(thickness 0.1524)
				)
			)
		)
		(duplicate_pad_numbers_are_jumpers no)
		(fp_line
			(start -0.508 -0.9398)
			(end -0.508 0.9398)
			(stroke
				(width 0.1524)
				(type default)
			)
			(layer "F.SilkS")
		)
		(fp_line
			(start 0.508 -0.9398)
			(end -0.508 -0.9398)
			(stroke
				(width 0.1524)
				(type default)
			)
			(layer "F.SilkS")
		)
		(fp_rect
			(start -0.508 0.9398)
			(end 0.508 -0.9398)
			(stroke
				(width 0)
				(type default)
			)
			(fill no)
			(layer "F.CrtYd")
		)
		(fp_rect
			(start -0.508 0.9398)
			(end 0.508 -0.9398)
			(stroke
				(width 0)
				(type default)
			)
			(fill no)
			(layer "F.Fab")
		)
		(pad "1" smd custom
			(at 0 -0.4445 270)
			(size 0.1397 0.1397)
			(layers "F.Cu" "F.Mask" "F.Paste")
			(net "DRIVE_B_6_ACT")
			(options
				(clearance outline)
				(anchor circle)
			)
			(primitives
				(gr_poly
					(pts
						(arc
							(start -0.1778 -0.2794)
							(mid -0.249642 -0.249642)
							(end -0.2794 -0.1778)
						)
						(arc
							(start -0.2794 0.1778)
							(mid -0.249642 0.249642)
							(end -0.1778 0.2794)
						)
						(arc
							(start 0.1778 0.2794)
							(mid 0.249642 0.249642)
							(end 0.2794 0.1778)
						)
						(arc
							(start 0.2794 -0.1778)
							(mid 0.249642 -0.249642)
							(end 0.1778 -0.2794)
						)
					)
					(width 0)
					(fill yes)
				)
			)
		)
		(pad "2" smd custom
			(at 0 0.4445 270)
			(size 0.1397 0.1397)
			(layers "F.Cu" "F.Mask" "F.Paste")
			(net "GND")
			(options
				(clearance outline)
				(anchor circle)
			)
			(primitives
				(gr_poly
					(pts
						(arc
							(start -0.1778 -0.2794)
							(mid -0.249642 -0.249642)
							(end -0.2794 -0.1778)
						)
						(arc
							(start -0.2794 0.1778)
							(mid -0.249642 0.249642)
							(end -0.1778 0.2794)
						)
						(arc
							(start 0.1778 0.2794)
							(mid 0.249642 0.249642)
							(end 0.2794 0.1778)
						)
						(arc
							(start 0.2794 -0.1778)
							(mid 0.249642 -0.249642)
							(end 0.1778 -0.2794)
						)
					)
					(width 0)
					(fill yes)
				)
			)
		)
	)
	(footprint ""
		(layer "F.Cu")
		(at 430.403 -13.589 180)
		(property "Reference" "R839"
			(at 0 0 180)
			(layer "F.SilkS")
			(hide yes)
			(effects
				(font
					(size 1.27 1.27)
				)
			)
		)
		(property "Value" "0R2J-2-GP"
			(at 0.064008 -3.993896 180)
			(unlocked yes)
			(layer "F.Fab")
			(hide yes)
			(effects
				(font
					(size 1.016 1.016)
					(thickness 0.1524)
				)
			)
		)
		(property "Device Type" "R402H16"
			(at 0.064008 -5.517896 180)
			(unlocked yes)
			(layer "F.Fab")
			(hide yes)
			(effects
				(font
					(size 1.016 1.016)
					(thickness 0.1524)
				)
			)
		)
		(duplicate_pad_numbers_are_jumpers no)
		(fp_line
			(start 0.508 -0.9398)
			(end -0.508 -0.9398)
			(stroke
				(width 0.1524)
				(type default)
			)
			(layer "F.SilkS")
		)
		(fp_line
			(start -0.508 -0.9398)
			(end -0.508 0.9398)
			(stroke
				(width 0.1524)
				(type default)
			)
			(layer "F.SilkS")
		)
		(fp_rect
			(start -0.508 0.9398)
			(end 0.508 -0.9398)
			(stroke
				(width 0)
				(type default)
			)
			(fill no)
			(layer "F.CrtYd")
		)
		(fp_rect
			(start -0.508 0.9398)
			(end 0.508 -0.9398)
			(stroke
				(width 0)
				(type default)
			)
			(fill no)
			(layer "F.Fab")
		)
		(pad "1" smd custom
			(at 0 -0.4445 180)
			(size 0.1397 0.1397)
			(layers "F.Cu" "F.Mask" "F.Paste")
			(net "DRIVE_B_33_PWR")
			(options
				(clearance outline)
				(anchor circle)
			)
			(primitives
				(gr_poly
					(pts
						(arc
							(start -0.1778 -0.2794)
							(mid -0.249642 -0.249642)
							(end -0.2794 -0.1778)
						)
						(arc
							(start -0.2794 0.1778)
							(mid -0.249642 0.249642)
							(end -0.1778 0.2794)
						)
						(arc
							(start 0.1778 0.2794)
							(mid 0.249642 0.249642)
							(end 0.2794 0.1778)
						)
						(arc
							(start 0.2794 -0.1778)
							(mid 0.249642 -0.249642)
							(end 0.1778 -0.2794)
						)
					)
					(width 0)
					(fill yes)
				)
			)
		)
		(pad "2" smd custom
			(at 0 0.4445 180)
			(size 0.1397 0.1397)
			(layers "F.Cu" "F.Mask" "F.Paste")
			(net "SW_PWR_R_HDD33")
			(options
				(clearance outline)
				(anchor circle)
			)
			(primitives
				(gr_poly
					(pts
						(arc
							(start -0.1778 -0.2794)
							(mid -0.249642 -0.249642)
							(end -0.2794 -0.1778)
						)
						(arc
							(start -0.2794 0.1778)
							(mid -0.249642 0.249642)
							(end -0.1778 0.2794)
						)
						(arc
							(start 0.1778 0.2794)
							(mid 0.249642 0.249642)
							(end 0.2794 0.1778)
						)
						(arc
							(start 0.2794 -0.1778)
							(mid 0.249642 -0.249642)
							(end 0.1778 -0.2794)
						)
					)
					(width 0)
					(fill yes)
				)
			)
		)
	)
	(footprint ""
		(layer "F.Cu")
		(at 190.812928 -372.347236 90)
		(property "Reference" "R1298"
			(at 0 0 90)
			(layer "F.SilkS")
			(hide yes)
			(effects
				(font
					(size 1.27 1.27)
				)
			)
		)
		(property "Value" "4K7R2F-GP"
			(at 0.064008 -3.993896 90)
			(unlocked yes)
			(layer "F.Fab")
			(hide yes)
			(effects
				(font
					(size 1.016 1.016)
					(thickness 0.1524)
				)
			)
		)
		(property "Device Type" "R402H16"
			(at 0.064008 -5.517896 90)
			(unlocked yes)
			(layer "F.Fab")
			(hide yes)
			(effects
				(font
					(size 1.016 1.016)
					(thickness 0.1524)
				)
			)
		)
		(duplicate_pad_numbers_are_jumpers no)
		(fp_line
			(start 0.508 -0.9398)
			(end -0.508 -0.9398)
			(stroke
				(width 0.1524)
				(type default)
			)
			(layer "F.SilkS")
		)
		(fp_line
			(start -0.508 -0.9398)
			(end -0.508 0.9398)
			(stroke
				(width 0.1524)
				(type default)
			)
			(layer "F.SilkS")
		)
		(fp_rect
			(start -0.508 0.9398)
			(end 0.508 -0.9398)
			(stroke
				(width 0)
				(type default)
			)
			(fill no)
			(layer "F.CrtYd")
		)
		(fp_rect
			(start -0.508 0.9398)
			(end 0.508 -0.9398)
			(stroke
				(width 0)
				(type default)
			)
			(fill no)
			(layer "F.Fab")
		)
		(pad "1" smd custom
			(at 0 -0.4445 90)
			(size 0.1397 0.1397)
			(layers "F.Cu" "F.Mask" "F.Paste")
			(net "FAN_YELLOW_LED1")
			(options
				(clearance outline)
				(anchor circle)
			)
			(primitives
				(gr_poly
					(pts
						(arc
							(start -0.1778 -0.2794)
							(mid -0.249642 -0.249642)
							(end -0.2794 -0.1778)
						)
						(arc
							(start -0.2794 0.1778)
							(mid -0.249642 0.249642)
							(end -0.1778 0.2794)
						)
						(arc
							(start 0.1778 0.2794)
							(mid 0.249642 0.249642)
							(end 0.2794 0.1778)
						)
						(arc
							(start 0.2794 -0.1778)
							(mid 0.249642 -0.249642)
							(end 0.1778 -0.2794)
						)
					)
					(width 0)
					(fill yes)
				)
			)
		)
		(pad "2" smd custom
			(at 0 0.4445 90)
			(size 0.1397 0.1397)
			(layers "F.Cu" "F.Mask" "F.Paste")
			(net "P12V_IN")
			(options
				(clearance outline)
				(anchor circle)
			)
			(primitives
				(gr_poly
					(pts
						(arc
							(start -0.1778 -0.2794)
							(mid -0.249642 -0.249642)
							(end -0.2794 -0.1778)
						)
						(arc
							(start -0.2794 0.1778)
							(mid -0.249642 0.249642)
							(end -0.1778 0.2794)
						)
						(arc
							(start 0.1778 0.2794)
							(mid 0.249642 0.249642)
							(end 0.2794 0.1778)
						)
						(arc
							(start 0.2794 -0.1778)
							(mid 0.249642 -0.249642)
							(end 0.1778 -0.2794)
						)
					)
					(width 0)
					(fill yes)
				)
			)
		)
	)
	(footprint ""
		(layer "F.Cu")
		(at 80.01 -17.653 180)
		(property "Reference" "D26"
			(at 0 0 180)
			(layer "F.SilkS")
			(hide yes)
			(effects
				(font
					(size 1.27 1.27)
				)
			)
		)
		(property "Value" "RB551V30-GP"
			(at 0 -6.7818 180)
			(unlocked yes)
			(layer "F.Fab")
			(hide yes)
			(effects
				(font
					(size 1.016 1.016)
					(thickness 0.1524)
				)
			)
		)
		(property "Device Type" "SOD323AKH38"
			(at 0 -8.6868 180)
			(unlocked yes)
			(layer "F.Fab")
			(hide yes)
			(effects
				(font
					(size 1.016 1.016)
					(thickness 0.1524)
				)
			)
		)
		(duplicate_pad_numbers_are_jumpers no)
		(fp_line
			(start 0.889 2.159)
			(end -0.889 2.159)
			(stroke
				(width 0.1524)
				(type default)
			)
			(layer "F.SilkS")
		)
		(fp_line
			(start 0.889 -1.9304)
			(end 0.889 2.159)
			(stroke
				(width 0.1524)
				(type default)
			)
			(layer "F.SilkS")
		)
		(fp_line
			(start 0.762 2.0574)
			(end -0.762 2.0574)
			(stroke
				(width 0.508)
				(type default)
			)
			(layer "F.SilkS")
		)
		(fp_line
			(start -0.889 2.159)
			(end -0.889 -1.9304)
			(stroke
				(width 0.1524)
				(type default)
			)
			(layer "F.SilkS")
		)
		(fp_line
			(start -0.889 -1.9304)
			(end 0.889 -1.9304)
			(stroke
				(width 0.1524)
				(type default)
			)
			(layer "F.SilkS")
		)
		(fp_rect
			(start -1.016 2.3114)
			(end 1.016 -2.0066)
			(stroke
				(width 0)
				(type default)
			)
			(fill no)
			(layer "F.CrtYd")
		)
		(fp_poly
			(pts
				(xy -1.016 -2.0066) (xy 1.016 -2.0066) (xy 1.016 2.3114) (xy -1.016 2.3114)
			)
			(stroke
				(width 0)
				(type default)
			)
			(fill no)
			(layer "F.Fab")
		)
		(pad "A" smd rect
			(at 0 -1.143 180)
			(size 0.5588 1.016)
			(layers "F.Cu" "F.Mask" "F.Paste")
			(net "SW_HDD_R26")
		)
		(pad "K" smd rect
			(at 0 1.143 180)
			(size 0.5588 1.016)
			(layers "F.Cu" "F.Mask" "F.Paste")
			(net "SW_HDD_N26")
		)
	)
	(footprint ""
		(layer "F.Cu")
		(at 318.356996 -372.0846)
		(property "Reference" "C712"
			(at 0 0 0)
			(layer "F.SilkS")
			(hide yes)
			(effects
				(font
					(size 1.27 1.27)
				)
			)
		)
		(property "Value" "SCD1U16V2KX-3GP"
			(at 1.1811 -2.7051 0)
			(unlocked yes)
			(layer "F.Fab")
			(hide yes)
			(effects
				(font
					(size 1.016 1.016)
					(thickness 0.1524)
				)
			)
		)
		(property "Device Type" "C402H22"
			(at 1.1811 -4.2291 0)
			(unlocked yes)
			(layer "F.Fab")
			(hide yes)
			(effects
				(font
					(size 1.016 1.016)
					(thickness 0.1524)
				)
			)
		)
		(duplicate_pad_numbers_are_jumpers no)
		(fp_rect
			(start -0.4318 0.9525)
			(end 0.4318 -0.9525)
			(stroke
				(width 0)
				(type default)
			)
			(fill no)
			(layer "F.CrtYd")
		)
		(fp_rect
			(start -0.4318 0.9525)
			(end 0.4318 -0.9525)
			(stroke
				(width 0)
				(type default)
			)
			(fill no)
			(layer "F.Fab")
		)
		(pad "1" smd custom
			(at 0 -0.4445)
			(size 0.1524 0.1524)
			(layers "F.Cu" "F.Mask" "F.Paste")
			(net "P3V3_IN")
			(options
				(clearance outline)
				(anchor circle)
			)
			(primitives
				(gr_poly
					(pts
						(arc
							(start 0.3048 -0.2032)
							(mid 0.275042 -0.275042)
							(end 0.2032 -0.3048)
						)
						(arc
							(start -0.2032 -0.3048)
							(mid -0.275042 -0.275042)
							(end -0.3048 -0.2032)
						)
						(arc
							(start -0.3048 0.2032)
							(mid -0.275042 0.275042)
							(end -0.2032 0.3048)
						)
						(arc
							(start 0.2032 0.3048)
							(mid 0.275042 0.275042)
							(end 0.3048 0.2032)
						)
					)
					(width 0)
					(fill yes)
				)
			)
		)
		(pad "2" smd custom
			(at 0 0.4445)
			(size 0.1524 0.1524)
			(layers "F.Cu" "F.Mask" "F.Paste")
			(net "GND")
			(options
				(clearance outline)
				(anchor circle)
			)
			(primitives
				(gr_poly
					(pts
						(arc
							(start 0.3048 -0.2032)
							(mid 0.275042 -0.275042)
							(end 0.2032 -0.3048)
						)
						(arc
							(start -0.2032 -0.3048)
							(mid -0.275042 -0.275042)
							(end -0.3048 -0.2032)
						)
						(arc
							(start -0.3048 0.2032)
							(mid -0.275042 0.275042)
							(end -0.2032 0.3048)
						)
						(arc
							(start 0.2032 0.3048)
							(mid 0.275042 0.275042)
							(end 0.3048 0.2032)
						)
					)
					(width 0)
					(fill yes)
				)
			)
		)
	)
	(footprint ""
		(layer "F.Cu")
		(at 474.345 -250.2408)
		(property "Reference" "R337"
			(at 0 0 0)
			(layer "F.SilkS")
			(hide yes)
			(effects
				(font
					(size 1.27 1.27)
				)
			)
		)
		(property "Value" "220R3F-1-GP"
			(at -0.0254 -2.5146 0)
			(unlocked yes)
			(layer "F.Fab")
			(hide yes)
			(effects
				(font
					(size 1.016 1.016)
					(thickness 0.1524)
				)
			)
		)
		(property "Device Type" "R603H22"
			(at -0.0254 -4.0386 0)
			(unlocked yes)
			(layer "F.Fab")
			(hide yes)
			(effects
				(font
					(size 1.016 1.016)
					(thickness 0.1524)
				)
			)
		)
		(duplicate_pad_numbers_are_jumpers no)
		(fp_line
			(start -0.4826 0)
			(end -0.2032 0)
			(stroke
				(width 0.2032)
				(type default)
			)
			(layer "F.SilkS")
		)
		(fp_line
			(start 0.2032 0)
			(end 0.4826 0)
			(stroke
				(width 0.2032)
				(type default)
			)
			(layer "F.SilkS")
		)
		(fp_rect
			(start -0.5842 1.3335)
			(end 0.5842 -1.3335)
			(stroke
				(width 0)
				(type default)
			)
			(fill no)
			(layer "F.CrtYd")
		)
		(fp_rect
			(start -0.5842 1.3335)
			(end 0.5842 -1.3335)
			(stroke
				(width 0)
				(type default)
			)
			(fill no)
			(layer "F.Fab")
		)
		(pad "1" smd custom
			(at 0 -0.762)
			(size 0.2159 0.2159)
			(layers "F.Cu" "F.Mask" "F.Paste")
			(net "HDD_PRSNT_11")
			(options
				(clearance outline)
				(anchor circle)
			)
			(primitives
				(gr_poly
					(pts
						(arc
							(start -0.3302 -0.4318)
							(mid -0.402042 -0.402042)
							(end -0.4318 -0.3302)
						)
						(arc
							(start -0.4318 0.3302)
							(mid -0.402042 0.402042)
							(end -0.3302 0.4318)
						)
						(arc
							(start 0.3302 0.4318)
							(mid 0.402042 0.402042)
							(end 0.4318 0.3302)
						)
						(arc
							(start 0.4318 -0.3302)
							(mid 0.402042 -0.402042)
							(end 0.3302 -0.4318)
						)
					)
					(width 0)
					(fill yes)
				)
			)
		)
		(pad "2" smd custom
			(at 0 0.762)
			(size 0.2159 0.2159)
			(layers "F.Cu" "F.Mask" "F.Paste")
			(net "DRIVE_B_11_INS")
			(options
				(clearance outline)
				(anchor circle)
			)
			(primitives
				(gr_poly
					(pts
						(arc
							(start -0.3302 -0.4318)
							(mid -0.402042 -0.402042)
							(end -0.4318 -0.3302)
						)
						(arc
							(start -0.4318 0.3302)
							(mid -0.402042 0.402042)
							(end -0.3302 0.4318)
						)
						(arc
							(start 0.3302 0.4318)
							(mid 0.402042 0.402042)
							(end 0.4318 0.3302)
						)
						(arc
							(start 0.4318 -0.3302)
							(mid 0.402042 -0.402042)
							(end 0.3302 -0.4318)
						)
					)
					(width 0)
					(fill yes)
				)
			)
		)
	)
	(footprint ""
		(layer "F.Cu")
		(at 255.509522 -358.622346)
		(property "Reference" "C554"
			(at 0 0 0)
			(layer "F.SilkS")
			(hide yes)
			(effects
				(font
					(size 1.27 1.27)
				)
			)
		)
		(property "Value" "SCD22U16V2KX-GP"
			(at 1.1811 -2.7051 0)
			(unlocked yes)
			(layer "F.Fab")
			(hide yes)
			(effects
				(font
					(size 1.016 1.016)
					(thickness 0.1524)
				)
			)
		)
		(property "Device Type" "C402H22"
			(at 1.1811 -4.2291 0)
			(unlocked yes)
			(layer "F.Fab")
			(hide yes)
			(effects
				(font
					(size 1.016 1.016)
					(thickness 0.1524)
				)
			)
		)
		(duplicate_pad_numbers_are_jumpers no)
		(fp_rect
			(start -0.4318 0.9525)
			(end 0.4318 -0.9525)
			(stroke
				(width 0)
				(type default)
			)
			(fill no)
			(layer "F.CrtYd")
		)
		(fp_rect
			(start -0.4318 0.9525)
			(end 0.4318 -0.9525)
			(stroke
				(width 0)
				(type default)
			)
			(fill no)
			(layer "F.Fab")
		)
		(pad "1" smd custom
			(at 0 -0.4445)
			(size 0.1524 0.1524)
			(layers "F.Cu" "F.Mask" "F.Paste")
			(net "MB3_TIME_R")
			(options
				(clearance outline)
				(anchor circle)
			)
			(primitives
				(gr_poly
					(pts
						(arc
							(start 0.3048 -0.2032)
							(mid 0.275042 -0.275042)
							(end 0.2032 -0.3048)
						)
						(arc
							(start -0.2032 -0.3048)
							(mid -0.275042 -0.275042)
							(end -0.3048 -0.2032)
						)
						(arc
							(start -0.3048 0.2032)
							(mid -0.275042 0.275042)
							(end -0.2032 0.3048)
						)
						(arc
							(start 0.2032 0.3048)
							(mid 0.275042 0.275042)
							(end 0.3048 0.2032)
						)
					)
					(width 0)
					(fill yes)
				)
			)
		)
		(pad "2" smd custom
			(at 0 0.4445)
			(size 0.1524 0.1524)
			(layers "F.Cu" "F.Mask" "F.Paste")
			(net "AGND_CURRENT_DPB")
			(options
				(clearance outline)
				(anchor circle)
			)
			(primitives
				(gr_poly
					(pts
						(arc
							(start 0.3048 -0.2032)
							(mid 0.275042 -0.275042)
							(end 0.2032 -0.3048)
						)
						(arc
							(start -0.2032 -0.3048)
							(mid -0.275042 -0.275042)
							(end -0.3048 -0.2032)
						)
						(arc
							(start -0.3048 0.2032)
							(mid -0.275042 0.275042)
							(end -0.2032 0.3048)
						)
						(arc
							(start 0.2032 0.3048)
							(mid 0.275042 0.275042)
							(end 0.3048 0.2032)
						)
					)
					(width 0)
					(fill yes)
				)
			)
		)
	)
	(footprint ""
		(layer "F.Cu")
		(at 282.984448 -347.541342 180)
		(property "Reference" "R1081"
			(at 0 0 180)
			(layer "F.SilkS")
			(hide yes)
			(effects
				(font
					(size 1.27 1.27)
				)
			)
		)
		(property "Value" "0R2J-2-GP"
			(at 0.064008 -3.993896 180)
			(unlocked yes)
			(layer "F.Fab")
			(hide yes)
			(effects
				(font
					(size 1.016 1.016)
					(thickness 0.1524)
				)
			)
		)
		(property "Device Type" "R402H16"
			(at 0.064008 -5.517896 180)
			(unlocked yes)
			(layer "F.Fab")
			(hide yes)
			(effects
				(font
					(size 1.016 1.016)
					(thickness 0.1524)
				)
			)
		)
		(duplicate_pad_numbers_are_jumpers no)
		(fp_line
			(start 0.508 -0.9398)
			(end -0.508 -0.9398)
			(stroke
				(width 0.1524)
				(type default)
			)
			(layer "F.SilkS")
		)
		(fp_line
			(start -0.508 -0.9398)
			(end -0.508 0.9398)
			(stroke
				(width 0.1524)
				(type default)
			)
			(layer "F.SilkS")
		)
		(fp_rect
			(start -0.508 0.9398)
			(end 0.508 -0.9398)
			(stroke
				(width 0)
				(type default)
			)
			(fill no)
			(layer "F.CrtYd")
		)
		(fp_rect
			(start -0.508 0.9398)
			(end 0.508 -0.9398)
			(stroke
				(width 0)
				(type default)
			)
			(fill no)
			(layer "F.Fab")
		)
		(pad "1" smd custom
			(at 0 -0.4445 180)
			(size 0.1397 0.1397)
			(layers "F.Cu" "F.Mask" "F.Paste")
			(net "GND")
			(options
				(clearance outline)
				(anchor circle)
			)
			(primitives
				(gr_poly
					(pts
						(arc
							(start -0.1778 -0.2794)
							(mid -0.249642 -0.249642)
							(end -0.2794 -0.1778)
						)
						(arc
							(start -0.2794 0.1778)
							(mid -0.249642 0.249642)
							(end -0.1778 0.2794)
						)
						(arc
							(start 0.1778 0.2794)
							(mid 0.249642 0.249642)
							(end 0.2794 0.1778)
						)
						(arc
							(start 0.2794 -0.1778)
							(mid 0.249642 -0.249642)
							(end 0.1778 -0.2794)
						)
					)
					(width 0)
					(fill yes)
				)
			)
		)
		(pad "2" smd custom
			(at 0 0.4445 180)
			(size 0.1397 0.1397)
			(layers "F.Cu" "F.Mask" "F.Paste")
			(net "MAX31790_B_FREQ_ST")
			(options
				(clearance outline)
				(anchor circle)
			)
			(primitives
				(gr_poly
					(pts
						(arc
							(start -0.1778 -0.2794)
							(mid -0.249642 -0.249642)
							(end -0.2794 -0.1778)
						)
						(arc
							(start -0.2794 0.1778)
							(mid -0.249642 0.249642)
							(end -0.1778 0.2794)
						)
						(arc
							(start 0.1778 0.2794)
							(mid 0.249642 0.249642)
							(end 0.2794 0.1778)
						)
						(arc
							(start 0.2794 -0.1778)
							(mid 0.249642 -0.249642)
							(end 0.1778 -0.2794)
						)
					)
					(width 0)
					(fill yes)
				)
			)
		)
	)
	(footprint ""
		(layer "F.Cu")
		(at 235.52404 -233.01198)
		(property "Reference" "R62"
			(at 0 0 0)
			(layer "F.SilkS")
			(hide yes)
			(effects
				(font
					(size 1.27 1.27)
				)
			)
		)
		(property "Value" "4K7R2F-GP"
			(at 0.064008 -3.993896 0)
			(unlocked yes)
			(layer "F.Fab")
			(hide yes)
			(effects
				(font
					(size 1.016 1.016)
					(thickness 0.1524)
				)
			)
		)
		(property "Device Type" "R402H16"
			(at 0.064008 -5.517896 0)
			(unlocked yes)
			(layer "F.Fab")
			(hide yes)
			(effects
				(font
					(size 1.016 1.016)
					(thickness 0.1524)
				)
			)
		)
		(duplicate_pad_numbers_are_jumpers no)
		(fp_line
			(start -0.508 -0.9398)
			(end -0.508 0.9398)
			(stroke
				(width 0.1524)
				(type default)
			)
			(layer "F.SilkS")
		)
		(fp_line
			(start 0.508 -0.9398)
			(end -0.508 -0.9398)
			(stroke
				(width 0.1524)
				(type default)
			)
			(layer "F.SilkS")
		)
		(fp_rect
			(start -0.508 0.9398)
			(end 0.508 -0.9398)
			(stroke
				(width 0)
				(type default)
			)
			(fill no)
			(layer "F.CrtYd")
		)
		(fp_rect
			(start -0.508 0.9398)
			(end 0.508 -0.9398)
			(stroke
				(width 0)
				(type default)
			)
			(fill no)
			(layer "F.Fab")
		)
		(pad "1" smd custom
			(at 0 -0.4445)
			(size 0.1397 0.1397)
			(layers "F.Cu" "F.Mask" "F.Paste")
			(net "P3V3_STBY_B")
			(options
				(clearance outline)
				(anchor circle)
			)
			(primitives
				(gr_poly
					(pts
						(arc
							(start -0.1778 -0.2794)
							(mid -0.249642 -0.249642)
							(end -0.2794 -0.1778)
						)
						(arc
							(start -0.2794 0.1778)
							(mid -0.249642 0.249642)
							(end -0.1778 0.2794)
						)
						(arc
							(start 0.1778 0.2794)
							(mid 0.249642 0.249642)
							(end 0.2794 0.1778)
						)
						(arc
							(start 0.2794 -0.1778)
							(mid 0.249642 -0.249642)
							(end 0.1778 -0.2794)
						)
					)
					(width 0)
					(fill yes)
				)
			)
		)
		(pad "2" smd custom
			(at 0 0.4445)
			(size 0.1397 0.1397)
			(layers "F.Cu" "F.Mask" "F.Paste")
			(net "IO_EXP1_INT_N")
			(options
				(clearance outline)
				(anchor circle)
			)
			(primitives
				(gr_poly
					(pts
						(arc
							(start -0.1778 -0.2794)
							(mid -0.249642 -0.249642)
							(end -0.2794 -0.1778)
						)
						(arc
							(start -0.2794 0.1778)
							(mid -0.249642 0.249642)
							(end -0.1778 0.2794)
						)
						(arc
							(start 0.1778 0.2794)
							(mid 0.249642 0.249642)
							(end 0.2794 0.1778)
						)
						(arc
							(start 0.2794 -0.1778)
							(mid 0.249642 -0.249642)
							(end 0.1778 -0.2794)
						)
					)
					(width 0)
					(fill yes)
				)
			)
		)
	)
	(footprint ""
		(layer "F.Cu")
		(at 476.9866 -135.7884 90)
		(property "Reference" "C335"
			(at 0 0 90)
			(layer "F.SilkS")
			(hide yes)
			(effects
				(font
					(size 1.27 1.27)
				)
			)
		)
		(property "Value" "SCD01U50V2KX-1GP"
			(at 1.1811 -2.7051 90)
			(unlocked yes)
			(layer "F.Fab")
			(hide yes)
			(effects
				(font
					(size 1.016 1.016)
					(thickness 0.1524)
				)
			)
		)
		(property "Device Type" "C402H22"
			(at 1.1811 -4.2291 90)
			(unlocked yes)
			(layer "F.Fab")
			(hide yes)
			(effects
				(font
					(size 1.016 1.016)
					(thickness 0.1524)
				)
			)
		)
		(duplicate_pad_numbers_are_jumpers no)
		(fp_rect
			(start -0.4318 0.9525)
			(end 0.4318 -0.9525)
			(stroke
				(width 0)
				(type default)
			)
			(fill no)
			(layer "F.CrtYd")
		)
		(fp_rect
			(start -0.4318 0.9525)
			(end 0.4318 -0.9525)
			(stroke
				(width 0)
				(type default)
			)
			(fill no)
			(layer "F.Fab")
		)
		(pad "1" smd custom
			(at 0 -0.4445 90)
			(size 0.1524 0.1524)
			(layers "F.Cu" "F.Mask" "F.Paste")
			(net "HDD_PRSNT_23")
			(options
				(clearance outline)
				(anchor circle)
			)
			(primitives
				(gr_poly
					(pts
						(arc
							(start 0.3048 -0.2032)
							(mid 0.275042 -0.275042)
							(end 0.2032 -0.3048)
						)
						(arc
							(start -0.2032 -0.3048)
							(mid -0.275042 -0.275042)
							(end -0.3048 -0.2032)
						)
						(arc
							(start -0.3048 0.2032)
							(mid -0.275042 0.275042)
							(end -0.2032 0.3048)
						)
						(arc
							(start 0.2032 0.3048)
							(mid 0.275042 0.275042)
							(end 0.3048 0.2032)
						)
					)
					(width 0)
					(fill yes)
				)
			)
		)
		(pad "2" smd custom
			(at 0 0.4445 90)
			(size 0.1524 0.1524)
			(layers "F.Cu" "F.Mask" "F.Paste")
			(net "GND")
			(options
				(clearance outline)
				(anchor circle)
			)
			(primitives
				(gr_poly
					(pts
						(arc
							(start 0.3048 -0.2032)
							(mid 0.275042 -0.275042)
							(end 0.2032 -0.3048)
						)
						(arc
							(start -0.2032 -0.3048)
							(mid -0.275042 -0.275042)
							(end -0.3048 -0.2032)
						)
						(arc
							(start -0.3048 0.2032)
							(mid -0.275042 0.275042)
							(end -0.2032 0.3048)
						)
						(arc
							(start 0.2032 0.3048)
							(mid 0.275042 0.275042)
							(end 0.3048 0.2032)
						)
					)
					(width 0)
					(fill yes)
				)
			)
		)
	)
	(footprint ""
		(layer "F.Cu")
		(at 51.562 -146.939 -90)
		(property "Reference" "C200"
			(at 0 0 270)
			(layer "F.SilkS")
			(hide yes)
			(effects
				(font
					(size 1.27 1.27)
				)
			)
		)
		(property "Value" "SC10U16V6KX-2GP"
			(at -0.0762 -5.1308 270)
			(unlocked yes)
			(layer "F.Fab")
			(hide yes)
			(effects
				(font
					(size 1.016 1.016)
					(thickness 0.1524)
				)
			)
		)
		(property "Device Type" "C1206H71"
			(at -0.127 -6.6548 270)
			(unlocked yes)
			(layer "F.Fab")
			(hide yes)
			(effects
				(font
					(size 1.016 1.016)
					(thickness 0.1524)
				)
			)
		)
		(duplicate_pad_numbers_are_jumpers no)
		(fp_line
			(start -1.016 2.2352)
			(end -1.016 0.8382)
			(stroke
				(width 0.1524)
				(type default)
			)
			(layer "F.SilkS")
		)
		(fp_line
			(start 1.016 2.2352)
			(end -1.016 2.2352)
			(stroke
				(width 0.1524)
				(type default)
			)
			(layer "F.SilkS")
		)
		(fp_line
			(start 1.016 0.8382)
			(end 1.016 2.2352)
			(stroke
				(width 0.1524)
				(type default)
			)
			(layer "F.SilkS")
		)
		(fp_line
			(start -1.016 -0.8382)
			(end -1.016 -2.2352)
			(stroke
				(width 0.1524)
				(type default)
			)
			(layer "F.SilkS")
		)
		(fp_line
			(start -1.016 -2.2352)
			(end 1.016 -2.2352)
			(stroke
				(width 0.1524)
				(type default)
			)
			(layer "F.SilkS")
		)
		(fp_line
			(start 1.016 -2.2352)
			(end 1.016 -0.8382)
			(stroke
				(width 0.1524)
				(type default)
			)
			(layer "F.SilkS")
		)
		(fp_rect
			(start -1.0922 2.3114)
			(end 1.0922 -2.3114)
			(stroke
				(width 0)
				(type default)
			)
			(fill no)
			(layer "F.CrtYd")
		)
		(fp_poly
			(pts
				(xy 1.0922 -2.3114) (xy 1.0922 2.3114) (xy -1.0922 2.3114) (xy -1.0922 -2.3114)
			)
			(stroke
				(width 0)
				(type default)
			)
			(fill no)
			(layer "F.Fab")
		)
		(pad "1" smd rect
			(at 0 -1.397 270)
			(size 1.651 1.27)
			(layers "F.Cu" "F.Mask" "F.Paste")
			(net "P5V_HDD13")
		)
		(pad "2" smd rect
			(at 0 1.397 270)
			(size 1.651 1.27)
			(layers "F.Cu" "F.Mask" "F.Paste")
			(net "GND")
		)
	)
	(footprint ""
		(layer "F.Cu")
		(at 440.69 -214.249)
		(property "Reference" "R364"
			(at 0 0 0)
			(layer "F.SilkS")
			(hide yes)
			(effects
				(font
					(size 1.27 1.27)
				)
			)
		)
		(property "Value" "130R3F-GP"
			(at -0.0254 -2.5146 0)
			(unlocked yes)
			(layer "F.Fab")
			(hide yes)
			(effects
				(font
					(size 1.016 1.016)
					(thickness 0.1524)
				)
			)
		)
		(property "Device Type" "R603H22"
			(at -0.0254 -4.0386 0)
			(unlocked yes)
			(layer "F.Fab")
			(hide yes)
			(effects
				(font
					(size 1.016 1.016)
					(thickness 0.1524)
				)
			)
		)
		(duplicate_pad_numbers_are_jumpers no)
		(fp_line
			(start -0.4826 0)
			(end -0.2032 0)
			(stroke
				(width 0.2032)
				(type default)
			)
			(layer "F.SilkS")
		)
		(fp_line
			(start 0.2032 0)
			(end 0.4826 0)
			(stroke
				(width 0.2032)
				(type default)
			)
			(layer "F.SilkS")
		)
		(fp_rect
			(start -0.5842 1.3335)
			(end 0.5842 -1.3335)
			(stroke
				(width 0)
				(type default)
			)
			(fill no)
			(layer "F.CrtYd")
		)
		(fp_rect
			(start -0.5842 1.3335)
			(end 0.5842 -1.3335)
			(stroke
				(width 0)
				(type default)
			)
			(fill no)
			(layer "F.Fab")
		)
		(pad "1" smd custom
			(at 0 -0.762)
			(size 0.2159 0.2159)
			(layers "F.Cu" "F.Mask" "F.Paste")
			(net "P5V_B_3")
			(options
				(clearance outline)
				(anchor circle)
			)
			(primitives
				(gr_poly
					(pts
						(arc
							(start -0.3302 -0.4318)
							(mid -0.402042 -0.402042)
							(end -0.4318 -0.3302)
						)
						(arc
							(start -0.4318 0.3302)
							(mid -0.402042 0.402042)
							(end -0.3302 0.4318)
						)
						(arc
							(start 0.3302 0.4318)
							(mid 0.402042 0.402042)
							(end 0.4318 0.3302)
						)
						(arc
							(start 0.4318 -0.3302)
							(mid 0.402042 -0.402042)
							(end 0.3302 -0.4318)
						)
					)
					(width 0)
					(fill yes)
				)
			)
		)
		(pad "2" smd custom
			(at 0 0.762)
			(size 0.2159 0.2159)
			(layers "F.Cu" "F.Mask" "F.Paste")
			(net "FLT_HDD10")
			(options
				(clearance outline)
				(anchor circle)
			)
			(primitives
				(gr_poly
					(pts
						(arc
							(start -0.3302 -0.4318)
							(mid -0.402042 -0.402042)
							(end -0.4318 -0.3302)
						)
						(arc
							(start -0.4318 0.3302)
							(mid -0.402042 0.402042)
							(end -0.3302 0.4318)
						)
						(arc
							(start 0.3302 0.4318)
							(mid 0.402042 0.402042)
							(end 0.4318 0.3302)
						)
						(arc
							(start 0.4318 -0.3302)
							(mid 0.402042 -0.402042)
							(end 0.3302 -0.4318)
						)
					)
					(width 0)
					(fill yes)
				)
			)
		)
	)
	(footprint ""
		(layer "F.Cu")
		(at 392.938 -275.336 180)
		(property "Reference" "C140"
			(at 0 0 180)
			(layer "F.SilkS")
			(hide yes)
			(effects
				(font
					(size 1.27 1.27)
				)
			)
		)
		(property "Value" "SC1U25V3KX-GP"
			(at 0 -2.8194 180)
			(unlocked yes)
			(layer "F.Fab")
			(hide yes)
			(effects
				(font
					(size 1.016 1.016)
					(thickness 0.1524)
				)
			)
		)
		(property "Device Type" "C603H36"
			(at 0 -4.3434 180)
			(unlocked yes)
			(layer "F.Fab")
			(hide yes)
			(effects
				(font
					(size 1.016 1.016)
					(thickness 0.1524)
				)
			)
		)
		(duplicate_pad_numbers_are_jumpers no)
		(fp_line
			(start 0.508 0)
			(end -0.508 0)
			(stroke
				(width 0.2032)
				(type default)
			)
			(layer "F.SilkS")
		)
		(fp_rect
			(start -0.5842 1.3335)
			(end 0.5842 -1.3335)
			(stroke
				(width 0)
				(type default)
			)
			(fill no)
			(layer "F.CrtYd")
		)
		(fp_rect
			(start -0.5842 1.3335)
			(end 0.5842 -1.3335)
			(stroke
				(width 0)
				(type default)
			)
			(fill no)
			(layer "F.Fab")
		)
		(pad "1" smd custom
			(at 0 -0.762 180)
			(size 0.2159 0.2159)
			(layers "F.Cu" "F.Mask" "F.Paste")
			(net "P12V_HDD8")
			(options
				(clearance outline)
				(anchor circle)
			)
			(primitives
				(gr_poly
					(pts
						(arc
							(start -0.3302 -0.4318)
							(mid -0.402042 -0.402042)
							(end -0.4318 -0.3302)
						)
						(arc
							(start -0.4318 0.3302)
							(mid -0.402042 0.402042)
							(end -0.3302 0.4318)
						)
						(arc
							(start 0.3302 0.4318)
							(mid 0.402042 0.402042)
							(end 0.4318 0.3302)
						)
						(arc
							(start 0.4318 -0.3302)
							(mid 0.402042 -0.402042)
							(end 0.3302 -0.4318)
						)
					)
					(width 0)
					(fill yes)
				)
			)
		)
		(pad "2" smd custom
			(at 0 0.762 180)
			(size 0.2159 0.2159)
			(layers "F.Cu" "F.Mask" "F.Paste")
			(net "GND")
			(options
				(clearance outline)
				(anchor circle)
			)
			(primitives
				(gr_poly
					(pts
						(arc
							(start -0.3302 -0.4318)
							(mid -0.402042 -0.402042)
							(end -0.4318 -0.3302)
						)
						(arc
							(start -0.4318 0.3302)
							(mid -0.402042 0.402042)
							(end -0.3302 0.4318)
						)
						(arc
							(start 0.3302 0.4318)
							(mid 0.402042 0.402042)
							(end 0.4318 0.3302)
						)
						(arc
							(start 0.4318 -0.3302)
							(mid 0.402042 -0.402042)
							(end 0.3302 -0.4318)
						)
					)
					(width 0)
					(fill yes)
				)
			)
		)
	)
	(footprint ""
		(layer "F.Cu")
		(at 266.192 -226.568)
		(property "Reference" "R8"
			(at 0 0 0)
			(layer "F.SilkS")
			(hide yes)
			(effects
				(font
					(size 1.27 1.27)
				)
			)
		)
		(property "Value" "1KR2F-3-GP"
			(at 0.064008 -3.993896 0)
			(unlocked yes)
			(layer "F.Fab")
			(hide yes)
			(effects
				(font
					(size 1.016 1.016)
					(thickness 0.1524)
				)
			)
		)
		(property "Device Type" "R402H16"
			(at 0.064008 -5.517896 0)
			(unlocked yes)
			(layer "F.Fab")
			(hide yes)
			(effects
				(font
					(size 1.016 1.016)
					(thickness 0.1524)
				)
			)
		)
		(duplicate_pad_numbers_are_jumpers no)
		(fp_line
			(start -0.508 -0.9398)
			(end -0.508 0.9398)
			(stroke
				(width 0.1524)
				(type default)
			)
			(layer "F.SilkS")
		)
		(fp_line
			(start 0.508 -0.9398)
			(end -0.508 -0.9398)
			(stroke
				(width 0.1524)
				(type default)
			)
			(layer "F.SilkS")
		)
		(fp_rect
			(start -0.508 0.9398)
			(end 0.508 -0.9398)
			(stroke
				(width 0)
				(type default)
			)
			(fill no)
			(layer "F.CrtYd")
		)
		(fp_rect
			(start -0.508 0.9398)
			(end 0.508 -0.9398)
			(stroke
				(width 0)
				(type default)
			)
			(fill no)
			(layer "F.Fab")
		)
		(pad "1" smd custom
			(at 0 -0.4445)
			(size 0.1397 0.1397)
			(layers "F.Cu" "F.Mask" "F.Paste")
			(net "P3V3_IN")
			(options
				(clearance outline)
				(anchor circle)
			)
			(primitives
				(gr_poly
					(pts
						(arc
							(start -0.1778 -0.2794)
							(mid -0.249642 -0.249642)
							(end -0.2794 -0.1778)
						)
						(arc
							(start -0.2794 0.1778)
							(mid -0.249642 0.249642)
							(end -0.1778 0.2794)
						)
						(arc
							(start 0.1778 0.2794)
							(mid 0.249642 0.249642)
							(end 0.2794 0.1778)
						)
						(arc
							(start 0.2794 -0.1778)
							(mid 0.249642 -0.249642)
							(end 0.1778 -0.2794)
						)
					)
					(width 0)
					(fill yes)
				)
			)
		)
		(pad "2" smd custom
			(at 0 0.4445)
			(size 0.1397 0.1397)
			(layers "F.Cu" "F.Mask" "F.Paste")
			(net "I2C_CLIP_B_SCL")
			(options
				(clearance outline)
				(anchor circle)
			)
			(primitives
				(gr_poly
					(pts
						(arc
							(start -0.1778 -0.2794)
							(mid -0.249642 -0.249642)
							(end -0.2794 -0.1778)
						)
						(arc
							(start -0.2794 0.1778)
							(mid -0.249642 0.249642)
							(end -0.1778 0.2794)
						)
						(arc
							(start 0.1778 0.2794)
							(mid 0.249642 0.249642)
							(end 0.2794 0.1778)
						)
						(arc
							(start 0.2794 -0.1778)
							(mid 0.249642 -0.249642)
							(end 0.1778 -0.2794)
						)
					)
					(width 0)
					(fill yes)
				)
			)
		)
	)
	(footprint ""
		(layer "F.Cu")
		(at 245.578122 -366.115346 90)
		(property "Reference" "R1061"
			(at 0 0 90)
			(layer "F.SilkS")
			(hide yes)
			(effects
				(font
					(size 1.27 1.27)
				)
			)
		)
		(property "Value" "10R2F-L-GP"
			(at 0.064008 -3.993896 90)
			(unlocked yes)
			(layer "F.Fab")
			(hide yes)
			(effects
				(font
					(size 1.016 1.016)
					(thickness 0.1524)
				)
			)
		)
		(property "Device Type" "R402H14"
			(at 0.064008 -5.517896 90)
			(unlocked yes)
			(layer "F.Fab")
			(hide yes)
			(effects
				(font
					(size 1.016 1.016)
					(thickness 0.1524)
				)
			)
		)
		(duplicate_pad_numbers_are_jumpers no)
		(fp_line
			(start 0.508 -0.9398)
			(end -0.508 -0.9398)
			(stroke
				(width 0.1524)
				(type default)
			)
			(layer "F.SilkS")
		)
		(fp_line
			(start -0.508 -0.9398)
			(end -0.508 0.9398)
			(stroke
				(width 0.1524)
				(type default)
			)
			(layer "F.SilkS")
		)
		(fp_rect
			(start -0.508 0.9398)
			(end 0.508 -0.9398)
			(stroke
				(width 0)
				(type default)
			)
			(fill no)
			(layer "F.CrtYd")
		)
		(fp_rect
			(start -0.508 0.9398)
			(end 0.508 -0.9398)
			(stroke
				(width 0)
				(type default)
			)
			(fill no)
			(layer "F.Fab")
		)
		(pad "1" smd custom
			(at 0 -0.4445 90)
			(size 0.1397 0.1397)
			(layers "F.Cu" "F.Mask" "F.Paste")
			(net "MB3_CM_SENSE_R1_P")
			(options
				(clearance outline)
				(anchor circle)
			)
			(primitives
				(gr_poly
					(pts
						(arc
							(start -0.1778 -0.2794)
							(mid -0.249642 -0.249642)
							(end -0.2794 -0.1778)
						)
						(arc
							(start -0.2794 0.1778)
							(mid -0.249642 0.249642)
							(end -0.1778 0.2794)
						)
						(arc
							(start 0.1778 0.2794)
							(mid 0.249642 0.249642)
							(end 0.2794 0.1778)
						)
						(arc
							(start 0.2794 -0.1778)
							(mid 0.249642 -0.249642)
							(end 0.1778 -0.2794)
						)
					)
					(width 0)
					(fill yes)
				)
			)
		)
		(pad "2" smd custom
			(at 0 0.4445 90)
			(size 0.1397 0.1397)
			(layers "F.Cu" "F.Mask" "F.Paste")
			(net "MB3_HS_SENSE_P")
			(options
				(clearance outline)
				(anchor circle)
			)
			(primitives
				(gr_poly
					(pts
						(arc
							(start -0.1778 -0.2794)
							(mid -0.249642 -0.249642)
							(end -0.2794 -0.1778)
						)
						(arc
							(start -0.2794 0.1778)
							(mid -0.249642 0.249642)
							(end -0.1778 0.2794)
						)
						(arc
							(start 0.1778 0.2794)
							(mid 0.249642 0.249642)
							(end 0.2794 0.1778)
						)
						(arc
							(start 0.2794 -0.1778)
							(mid 0.249642 -0.249642)
							(end 0.1778 -0.2794)
						)
					)
					(width 0)
					(fill yes)
				)
			)
		)
	)
	(footprint ""
		(layer "F.Cu")
		(at 401.828 -257.81 -90)
		(property "Reference" "R297"
			(at 0 0 270)
			(layer "F.SilkS")
			(hide yes)
			(effects
				(font
					(size 1.27 1.27)
				)
			)
		)
		(property "Value" "300KR2F-GP"
			(at 0.064008 -3.993896 270)
			(unlocked yes)
			(layer "F.Fab")
			(hide yes)
			(effects
				(font
					(size 1.016 1.016)
					(thickness 0.1524)
				)
			)
		)
		(property "Device Type" "R402H16"
			(at 0.064008 -5.517896 270)
			(unlocked yes)
			(layer "F.Fab")
			(hide yes)
			(effects
				(font
					(size 1.016 1.016)
					(thickness 0.1524)
				)
			)
		)
		(duplicate_pad_numbers_are_jumpers no)
		(fp_line
			(start -0.508 -0.9398)
			(end -0.508 0.9398)
			(stroke
				(width 0.1524)
				(type default)
			)
			(layer "F.SilkS")
		)
		(fp_line
			(start 0.508 -0.9398)
			(end -0.508 -0.9398)
			(stroke
				(width 0.1524)
				(type default)
			)
			(layer "F.SilkS")
		)
		(fp_rect
			(start -0.508 0.9398)
			(end 0.508 -0.9398)
			(stroke
				(width 0)
				(type default)
			)
			(fill no)
			(layer "F.CrtYd")
		)
		(fp_rect
			(start -0.508 0.9398)
			(end 0.508 -0.9398)
			(stroke
				(width 0)
				(type default)
			)
			(fill no)
			(layer "F.Fab")
		)
		(pad "1" smd custom
			(at 0 -0.4445 270)
			(size 0.1397 0.1397)
			(layers "F.Cu" "F.Mask" "F.Paste")
			(net "SW_HDD_N8")
			(options
				(clearance outline)
				(anchor circle)
			)
			(primitives
				(gr_poly
					(pts
						(arc
							(start -0.1778 -0.2794)
							(mid -0.249642 -0.249642)
							(end -0.2794 -0.1778)
						)
						(arc
							(start -0.2794 0.1778)
							(mid -0.249642 0.249642)
							(end -0.1778 0.2794)
						)
						(arc
							(start 0.1778 0.2794)
							(mid 0.249642 0.249642)
							(end 0.2794 0.1778)
						)
						(arc
							(start 0.2794 -0.1778)
							(mid 0.249642 -0.249642)
							(end 0.1778 -0.2794)
						)
					)
					(width 0)
					(fill yes)
				)
			)
		)
		(pad "2" smd custom
			(at 0 0.4445 270)
			(size 0.1397 0.1397)
			(layers "F.Cu" "F.Mask" "F.Paste")
			(net "P12V_B")
			(options
				(clearance outline)
				(anchor circle)
			)
			(primitives
				(gr_poly
					(pts
						(arc
							(start -0.1778 -0.2794)
							(mid -0.249642 -0.249642)
							(end -0.2794 -0.1778)
						)
						(arc
							(start -0.2794 0.1778)
							(mid -0.249642 0.249642)
							(end -0.1778 0.2794)
						)
						(arc
							(start 0.1778 0.2794)
							(mid 0.249642 0.249642)
							(end 0.2794 0.1778)
						)
						(arc
							(start 0.2794 -0.1778)
							(mid 0.249642 -0.249642)
							(end 0.1778 -0.2794)
						)
					)
					(width 0)
					(fill yes)
				)
			)
		)
	)
	(footprint ""
		(layer "F.Cu")
		(at 33.3248 -178.799998)
		(property "Reference" ""
			(at 0 0 0)
			(layer "F.SilkS")
			(hide yes)
			(effects
				(font
					(size 1.27 1.27)
				)
			)
		)
		(property "Value" "*"
			(at -8.398764 -8.057642 0)
			(unlocked yes)
			(layer "F.Fab")
			(hide yes)
			(effects
				(font
					(size 1.016 1.016)
					(thickness 0.1524)
				)
			)
		)
		(duplicate_pad_numbers_are_jumpers no)
		(fp_poly
			(pts
				(arc
					(start 7.3152 0)
					(mid 0 7.3152)
					(end -7.3152 0)
				)
				(arc
					(start -7.3152 -5.9944)
					(mid 0 -13.3096)
					(end 7.3152 -5.9944)
				)
			)
			(stroke
				(width 0)
				(type default)
			)
			(fill no)
			(layer "B.CrtYd")
		)
		(fp_poly
			(pts
				(arc
					(start 7.3152 0)
					(mid 0 7.3152)
					(end -7.3152 0)
				)
				(arc
					(start -7.3152 -5.9944)
					(mid 0 -13.3096)
					(end 7.3152 -5.9944)
				)
			)
			(stroke
				(width 0)
				(type default)
			)
			(fill no)
			(layer "F.CrtYd")
		)
		(fp_poly
			(pts
				(arc
					(start 7.3152 0)
					(mid 0 7.3152)
					(end -7.3152 0)
				)
				(arc
					(start -7.3152 -5.9944)
					(mid 0 -13.3096)
					(end 7.3152 -5.9944)
				)
			)
			(stroke
				(width 0)
				(type default)
			)
			(fill no)
			(layer "B.Fab")
		)
		(fp_poly
			(pts
				(arc
					(start 7.3152 0)
					(mid 0 7.3152)
					(end -7.3152 0)
				)
				(arc
					(start -7.3152 -5.9944)
					(mid 0 -13.3096)
					(end 7.3152 -5.9944)
				)
			)
			(stroke
				(width 0)
				(type default)
			)
			(fill no)
			(layer "F.Fab")
		)
		(pad "1" thru_hole oval
			(at 0 0)
			(size 14.0208 20.0152)
			(drill 0.0254
				(offset 0 -2.9972)
			)
			(layers "*.Cu" "*.Mask")
			(remove_unused_layers no)
			(net "Net_47")
			(clearance -1.002284)
			(thermal_gap 0.1524)
			(padstack
				(mode front_inner_back)
				(layer "Inner"
					(shape custom)
					(size 2.928012 2.928012)
					(options
						(anchor circle)
					)
					(primitives
						(gr_poly
							(pts
								(arc
									(start 4.571746 -2.084324)
									(mid 0.000333 7.430372)
									(end -4.571492 -2.084324)
								)
								(arc
									(start -4.571492 -2.084324)
									(mid -3.570296 -3.611977)
									(end -2.875026 -5.30098)
								)
								(arc
									(start -2.875026 -5.30098)
									(mid 0.000217 -7.43089)
									(end 2.87528 -5.30098)
								)
								(arc
									(start 2.87528 -5.30098)
									(mid 3.570511 -3.611956)
									(end 4.571746 -2.084324)
								)
							)
							(width 0)
							(fill yes)
						)
					)
					(clearance 0.1524)
				)
				(layer "B.Cu"
					(shape oval)
					(size 14.0208 20.0152)
					(offset 0 -2.9972)
					(clearance -1.002284)
				)
			)
		)
		(zone
			(layers "F.Cu" "B.Cu" "In1.Cu" "In2.Cu" "In3.Cu" "In4.Cu" "In5.Cu" "In6.Cu")
			(hatch none 0.5)
			(connect_pads
				(clearance 0)
			)
			(min_thickness 0.25)
			(keepout
				(tracks not_allowed)
				(vias allowed)
				(pads allowed)
				(copperpour not_allowed)
				(footprints allowed)
			)
			(placement
				(enabled no)
				(sheetname "")
			)
			(fill
				(thermal_gap 0.5)
				(thermal_bridge_width 0.5)
				(island_removal_mode 0)
			)
			(polygon
				(pts
					(arc
						(start 26.3144 -184.794398)
						(mid 33.3248 -191.804798)
						(end 40.3352 -184.794398)
					)
					(arc
						(start 40.3352 -178.799998)
						(mid 33.3248 -171.789598)
						(end 26.3144 -178.799998)
					)
				)
			)
		)
	)
	(footprint ""
		(layer "F.Cu")
		(at 178.816 -16.637 -90)
		(property "Reference" "Q149"
			(at 0 0 270)
			(layer "F.SilkS")
			(hide yes)
			(effects
				(font
					(size 1.27 1.27)
				)
			)
		)
		(property "Value" "2N7002KDW-GP"
			(at -2.3622 -8.2042 270)
			(unlocked yes)
			(layer "F.Fab")
			(hide yes)
			(effects
				(font
					(size 1.016 1.016)
					(thickness 0.1524)
				)
			)
		)
		(property "Device Type" "SOT-363H44"
			(at -2.3622 -10.1092 270)
			(unlocked yes)
			(layer "F.Fab")
			(hide yes)
			(effects
				(font
					(size 1.016 1.016)
					(thickness 0.1524)
				)
			)
		)
		(duplicate_pad_numbers_are_jumpers no)
		(fp_line
			(start -1.4478 1.7018)
			(end 1.4478 1.7018)
			(stroke
				(width 0.1524)
				(type default)
			)
			(layer "F.SilkS")
		)
		(fp_line
			(start 1.4478 1.7018)
			(end 1.4478 -1.7018)
			(stroke
				(width 0.1524)
				(type default)
			)
			(layer "F.SilkS")
		)
		(fp_line
			(start -1.27 1.524)
			(end -1.27 0.6604)
			(stroke
				(width 0.4826)
				(type default)
			)
			(layer "F.SilkS")
		)
		(fp_line
			(start -1.4478 -1.7018)
			(end -1.4478 1.7018)
			(stroke
				(width 0.1524)
				(type default)
			)
			(layer "F.SilkS")
		)
		(fp_line
			(start 1.4478 -1.7018)
			(end -1.4478 -1.7018)
			(stroke
				(width 0.1524)
				(type default)
			)
			(layer "F.SilkS")
		)
		(fp_poly
			(pts
				(xy -1.524 -1.778) (xy 1.524 -1.778) (xy 1.524 1.778) (xy -1.524 1.778)
			)
			(stroke
				(width 0)
				(type default)
			)
			(fill no)
			(layer "F.CrtYd")
		)
		(fp_poly
			(pts
				(xy -1.524 -1.778) (xy 1.524 -1.778) (xy 1.524 1.778) (xy -1.524 1.778)
			)
			(stroke
				(width 0)
				(type default)
			)
			(fill no)
			(layer "F.Fab")
		)
		(pad "1" smd rect
			(at -0.65024 0.9398 270)
			(size 0.4064 1.016)
			(layers "F.Cu" "F.Mask" "F.Paste")
			(net "GND")
		)
		(pad "2" smd rect
			(at 0 0.9398 270)
			(size 0.4064 1.016)
			(layers "F.Cu" "F.Mask" "F.Paste")
			(net "SW_PWR_R_HDD29")
		)
		(pad "3" smd rect
			(at 0.65024 0.9398 270)
			(size 0.4064 1.016)
			(layers "F.Cu" "F.Mask" "F.Paste")
			(net "SW_HDD_P29")
		)
		(pad "4" smd rect
			(at 0.65024 -0.9398 270)
			(size 0.4064 1.016)
			(layers "F.Cu" "F.Mask" "F.Paste")
			(net "GND")
		)
		(pad "5" smd rect
			(at 0 -0.9398 270)
			(size 0.4064 1.016)
			(layers "F.Cu" "F.Mask" "F.Paste")
			(net "SW_HDD_G29")
		)
		(pad "6" smd rect
			(at -0.65024 -0.9398 270)
			(size 0.4064 1.016)
			(layers "F.Cu" "F.Mask" "F.Paste")
			(net "SW_HDD_R29")
		)
	)
	(footprint ""
		(layer "F.Cu")
		(at 330.294996 -369.697)
		(property "Reference" "C529"
			(at 0 0 0)
			(layer "F.SilkS")
			(hide yes)
			(effects
				(font
					(size 1.27 1.27)
				)
			)
		)
		(property "Value" "SCD1U25V2KX-2-GP"
			(at 1.1811 -2.7051 0)
			(unlocked yes)
			(layer "F.Fab")
			(hide yes)
			(effects
				(font
					(size 1.016 1.016)
					(thickness 0.1524)
				)
			)
		)
		(property "Device Type" "C402H22"
			(at 1.1811 -4.2291 0)
			(unlocked yes)
			(layer "F.Fab")
			(hide yes)
			(effects
				(font
					(size 1.016 1.016)
					(thickness 0.1524)
				)
			)
		)
		(duplicate_pad_numbers_are_jumpers no)
		(fp_rect
			(start -0.4318 0.9525)
			(end 0.4318 -0.9525)
			(stroke
				(width 0)
				(type default)
			)
			(fill no)
			(layer "F.CrtYd")
		)
		(fp_rect
			(start -0.4318 0.9525)
			(end 0.4318 -0.9525)
			(stroke
				(width 0)
				(type default)
			)
			(fill no)
			(layer "F.Fab")
		)
		(pad "1" smd custom
			(at 0 -0.4445)
			(size 0.1524 0.1524)
			(layers "F.Cu" "F.Mask" "F.Paste")
			(net "FAN_2_TACH0")
			(options
				(clearance outline)
				(anchor circle)
			)
			(primitives
				(gr_poly
					(pts
						(arc
							(start 0.3048 -0.2032)
							(mid 0.275042 -0.275042)
							(end 0.2032 -0.3048)
						)
						(arc
							(start -0.2032 -0.3048)
							(mid -0.275042 -0.275042)
							(end -0.3048 -0.2032)
						)
						(arc
							(start -0.3048 0.2032)
							(mid -0.275042 0.275042)
							(end -0.2032 0.3048)
						)
						(arc
							(start 0.2032 0.3048)
							(mid 0.275042 0.275042)
							(end 0.3048 0.2032)
						)
					)
					(width 0)
					(fill yes)
				)
			)
		)
		(pad "2" smd custom
			(at 0 0.4445)
			(size 0.1524 0.1524)
			(layers "F.Cu" "F.Mask" "F.Paste")
			(net "GND")
			(options
				(clearance outline)
				(anchor circle)
			)
			(primitives
				(gr_poly
					(pts
						(arc
							(start 0.3048 -0.2032)
							(mid 0.275042 -0.275042)
							(end 0.2032 -0.3048)
						)
						(arc
							(start -0.2032 -0.3048)
							(mid -0.275042 -0.275042)
							(end -0.3048 -0.2032)
						)
						(arc
							(start -0.3048 0.2032)
							(mid -0.275042 0.275042)
							(end -0.2032 0.3048)
						)
						(arc
							(start 0.2032 0.3048)
							(mid 0.275042 0.275042)
							(end 0.3048 0.2032)
						)
					)
					(width 0)
					(fill yes)
				)
			)
		)
	)
	(footprint ""
		(layer "F.Cu")
		(at 447.834512 -14.660626 -90)
		(property "Reference" "C471"
			(at 0 0 270)
			(layer "F.SilkS")
			(hide yes)
			(effects
				(font
					(size 1.27 1.27)
				)
			)
		)
		(property "Value" "SCD01U16V1KX-GP"
			(at -2.8321 -1.7399 270)
			(unlocked yes)
			(layer "F.Fab")
			(hide yes)
			(effects
				(font
					(size 1.016 1.016)
					(thickness 0.1524)
				)
			)
		)
		(property "Device Type" "C0201H13"
			(at -2.8321 -3.2639 270)
			(unlocked yes)
			(layer "F.Fab")
			(hide yes)
			(effects
				(font
					(size 1.016 1.016)
					(thickness 0.1524)
				)
			)
		)
		(duplicate_pad_numbers_are_jumpers no)
		(fp_rect
			(start -0.2794 0.6477)
			(end 0.2794 -0.6477)
			(stroke
				(width 0)
				(type default)
			)
			(fill no)
			(layer "F.CrtYd")
		)
		(fp_rect
			(start -0.2794 0.6477)
			(end 0.2794 -0.6477)
			(stroke
				(width 0)
				(type default)
			)
			(fill no)
			(layer "F.Fab")
		)
		(pad "1" smd custom
			(at 0 -0.2794 270)
			(size 0.0762 0.0762)
			(layers "F.Cu" "F.Mask" "F.Paste")
			(net "SAS_HDD_RX_P34")
			(options
				(clearance outline)
				(anchor circle)
			)
			(primitives
				(gr_poly
					(pts
						(arc
							(start 0.1524 -0.127)
							(mid 0.137521 -0.162921)
							(end 0.1016 -0.1778)
						)
						(arc
							(start -0.1016 -0.1778)
							(mid -0.137521 -0.162921)
							(end -0.1524 -0.127)
						)
						(arc
							(start -0.1524 0.127)
							(mid -0.137521 0.162921)
							(end -0.1016 0.1778)
						)
						(arc
							(start 0.1016 0.1778)
							(mid 0.137521 0.162921)
							(end 0.1524 0.127)
						)
					)
					(width 0)
					(fill yes)
				)
			)
		)
		(pad "2" smd custom
			(at 0 0.2794 270)
			(size 0.0762 0.0762)
			(layers "F.Cu" "F.Mask" "F.Paste")
			(net "PHY_SCC_B_TO_DRV_B_34_DP")
			(options
				(clearance outline)
				(anchor circle)
			)
			(primitives
				(gr_poly
					(pts
						(arc
							(start 0.1524 -0.127)
							(mid 0.137521 -0.162921)
							(end 0.1016 -0.1778)
						)
						(arc
							(start -0.1016 -0.1778)
							(mid -0.137521 -0.162921)
							(end -0.1524 -0.127)
						)
						(arc
							(start -0.1524 0.127)
							(mid -0.137521 0.162921)
							(end -0.1016 0.1778)
						)
						(arc
							(start 0.1016 0.1778)
							(mid 0.137521 0.162921)
							(end 0.1524 0.127)
						)
					)
					(width 0)
					(fill yes)
				)
			)
		)
	)
	(footprint ""
		(layer "F.Cu")
		(at 248.889774 -142.156434 90)
		(property "Reference" "C72"
			(at 0 0 90)
			(layer "F.SilkS")
			(hide yes)
			(effects
				(font
					(size 1.27 1.27)
				)
			)
		)
		(property "Value" "SCD1U16V2KX-3GP"
			(at 1.1811 -2.7051 90)
			(unlocked yes)
			(layer "F.Fab")
			(hide yes)
			(effects
				(font
					(size 1.016 1.016)
					(thickness 0.1524)
				)
			)
		)
		(property "Device Type" "C402H22"
			(at 1.1811 -4.2291 90)
			(unlocked yes)
			(layer "F.Fab")
			(hide yes)
			(effects
				(font
					(size 1.016 1.016)
					(thickness 0.1524)
				)
			)
		)
		(duplicate_pad_numbers_are_jumpers no)
		(fp_rect
			(start -0.4318 0.9525)
			(end 0.4318 -0.9525)
			(stroke
				(width 0)
				(type default)
			)
			(fill no)
			(layer "F.CrtYd")
		)
		(fp_rect
			(start -0.4318 0.9525)
			(end 0.4318 -0.9525)
			(stroke
				(width 0)
				(type default)
			)
			(fill no)
			(layer "F.Fab")
		)
		(pad "1" smd custom
			(at 0 -0.4445 90)
			(size 0.1524 0.1524)
			(layers "F.Cu" "F.Mask" "F.Paste")
			(net "P3V3_STBY_B")
			(options
				(clearance outline)
				(anchor circle)
			)
			(primitives
				(gr_poly
					(pts
						(arc
							(start 0.3048 -0.2032)
							(mid 0.275042 -0.275042)
							(end 0.2032 -0.3048)
						)
						(arc
							(start -0.2032 -0.3048)
							(mid -0.275042 -0.275042)
							(end -0.3048 -0.2032)
						)
						(arc
							(start -0.3048 0.2032)
							(mid -0.275042 0.275042)
							(end -0.2032 0.3048)
						)
						(arc
							(start 0.2032 0.3048)
							(mid 0.275042 0.275042)
							(end 0.3048 0.2032)
						)
					)
					(width 0)
					(fill yes)
				)
			)
		)
		(pad "2" smd custom
			(at 0 0.4445 90)
			(size 0.1524 0.1524)
			(layers "F.Cu" "F.Mask" "F.Paste")
			(net "GND")
			(options
				(clearance outline)
				(anchor circle)
			)
			(primitives
				(gr_poly
					(pts
						(arc
							(start 0.3048 -0.2032)
							(mid 0.275042 -0.275042)
							(end 0.2032 -0.3048)
						)
						(arc
							(start -0.2032 -0.3048)
							(mid -0.275042 -0.275042)
							(end -0.3048 -0.2032)
						)
						(arc
							(start -0.3048 0.2032)
							(mid -0.275042 0.275042)
							(end -0.2032 0.3048)
						)
						(arc
							(start 0.2032 0.3048)
							(mid 0.275042 0.275042)
							(end 0.3048 0.2032)
						)
					)
					(width 0)
					(fill yes)
				)
			)
		)
	)
	(footprint ""
		(layer "F.Cu")
		(at 396.621 -44.958 180)
		(property "Reference" "C451"
			(at 0 0 180)
			(layer "F.SilkS")
			(hide yes)
			(effects
				(font
					(size 1.27 1.27)
				)
			)
		)
		(property "Value" "SC4D7U25V5KX-1-GP"
			(at -0.0762 -6.1214 180)
			(unlocked yes)
			(layer "F.Fab")
			(hide yes)
			(effects
				(font
					(size 1.016 1.016)
					(thickness 0.1524)
				)
			)
		)
		(property "Device Type" "C805H58"
			(at -0.0762 -8.1534 180)
			(unlocked yes)
			(layer "F.Fab")
			(hide yes)
			(effects
				(font
					(size 1.016 1.016)
					(thickness 0.1524)
				)
			)
		)
		(duplicate_pad_numbers_are_jumpers no)
		(fp_line
			(start 0.635 0)
			(end -0.635 0)
			(stroke
				(width 0.508)
				(type default)
			)
			(layer "F.SilkS")
		)
		(fp_rect
			(start -0.9652 1.778)
			(end 0.9652 -1.778)
			(stroke
				(width 0)
				(type default)
			)
			(fill no)
			(layer "F.CrtYd")
		)
		(fp_poly
			(pts
				(xy -0.9652 -1.778) (xy 0.9652 -1.778) (xy 0.9652 1.778) (xy -0.9652 1.778)
			)
			(stroke
				(width 0)
				(type default)
			)
			(fill no)
			(layer "F.Fab")
		)
		(pad "1" smd rect
			(at 0 -0.9652 180)
			(size 1.397 1.143)
			(layers "F.Cu" "F.Mask" "F.Paste")
			(net "P12V_HDD32")
		)
		(pad "2" smd rect
			(at 0 0.9652 180)
			(size 1.397 1.143)
			(layers "F.Cu" "F.Mask" "F.Paste")
			(net "GND")
		)
	)
	(footprint ""
		(layer "F.Cu")
		(at 18.415 -16.637)
		(property "Reference" "R639"
			(at 0 0 0)
			(layer "F.SilkS")
			(hide yes)
			(effects
				(font
					(size 1.27 1.27)
				)
			)
		)
		(property "Value" "0R2J-2-GP"
			(at 0.064008 -3.993896 0)
			(unlocked yes)
			(layer "F.Fab")
			(hide yes)
			(effects
				(font
					(size 1.016 1.016)
					(thickness 0.1524)
				)
			)
		)
		(property "Device Type" "R402H16"
			(at 0.064008 -5.517896 0)
			(unlocked yes)
			(layer "F.Fab")
			(hide yes)
			(effects
				(font
					(size 1.016 1.016)
					(thickness 0.1524)
				)
			)
		)
		(duplicate_pad_numbers_are_jumpers no)
		(fp_line
			(start -0.508 -0.9398)
			(end -0.508 0.9398)
			(stroke
				(width 0.1524)
				(type default)
			)
			(layer "F.SilkS")
		)
		(fp_line
			(start 0.508 -0.9398)
			(end -0.508 -0.9398)
			(stroke
				(width 0.1524)
				(type default)
			)
			(layer "F.SilkS")
		)
		(fp_rect
			(start -0.508 0.9398)
			(end 0.508 -0.9398)
			(stroke
				(width 0)
				(type default)
			)
			(fill no)
			(layer "F.CrtYd")
		)
		(fp_rect
			(start -0.508 0.9398)
			(end 0.508 -0.9398)
			(stroke
				(width 0)
				(type default)
			)
			(fill no)
			(layer "F.Fab")
		)
		(pad "1" smd custom
			(at 0 -0.4445)
			(size 0.1397 0.1397)
			(layers "F.Cu" "F.Mask" "F.Paste")
			(net "SW_HDD_G24")
			(options
				(clearance outline)
				(anchor circle)
			)
			(primitives
				(gr_poly
					(pts
						(arc
							(start -0.1778 -0.2794)
							(mid -0.249642 -0.249642)
							(end -0.2794 -0.1778)
						)
						(arc
							(start -0.2794 0.1778)
							(mid -0.249642 0.249642)
							(end -0.1778 0.2794)
						)
						(arc
							(start 0.1778 0.2794)
							(mid 0.249642 0.249642)
							(end 0.2794 0.1778)
						)
						(arc
							(start 0.2794 -0.1778)
							(mid 0.249642 -0.249642)
							(end 0.1778 -0.2794)
						)
					)
					(width 0)
					(fill yes)
				)
			)
		)
		(pad "2" smd custom
			(at 0 0.4445)
			(size 0.1397 0.1397)
			(layers "F.Cu" "F.Mask" "F.Paste")
			(net "SW_HDD_R24")
			(options
				(clearance outline)
				(anchor circle)
			)
			(primitives
				(gr_poly
					(pts
						(arc
							(start -0.1778 -0.2794)
							(mid -0.249642 -0.249642)
							(end -0.2794 -0.1778)
						)
						(arc
							(start -0.2794 0.1778)
							(mid -0.249642 0.249642)
							(end -0.1778 0.2794)
						)
						(arc
							(start 0.1778 0.2794)
							(mid 0.249642 0.249642)
							(end 0.2794 0.1778)
						)
						(arc
							(start 0.2794 -0.1778)
							(mid 0.249642 -0.249642)
							(end 0.1778 -0.2794)
						)
					)
					(width 0)
					(fill yes)
				)
			)
		)
	)
	(footprint ""
		(layer "F.Cu")
		(at 343.454228 -214.757 180)
		(property "Reference" "Q226"
			(at 0 0 180)
			(layer "F.SilkS")
			(hide yes)
			(effects
				(font
					(size 1.27 1.27)
				)
			)
		)
		(property "Value" "2N7002K-2-GP"
			(at 0.127 -8.9662 180)
			(unlocked yes)
			(layer "F.Fab")
			(hide yes)
			(effects
				(font
					(size 1.016 1.016)
					(thickness 0.1524)
				)
			)
		)
		(property "Device Type" "SOT23DGS2D4H44"
			(at 0.127 -10.4902 180)
			(unlocked yes)
			(layer "F.Fab")
			(hide yes)
			(effects
				(font
					(size 1.016 1.016)
					(thickness 0.1524)
				)
			)
		)
		(duplicate_pad_numbers_are_jumpers no)
		(fp_line
			(start 1.651 1.778)
			(end 1.651 -1.778)
			(stroke
				(width 0.1524)
				(type default)
			)
			(layer "F.SilkS")
		)
		(fp_line
			(start 1.651 -1.778)
			(end -1.651 -1.778)
			(stroke
				(width 0.1524)
				(type default)
			)
			(layer "F.SilkS")
		)
		(fp_line
			(start -1.651 1.778)
			(end 1.651 1.778)
			(stroke
				(width 0.1524)
				(type default)
			)
			(layer "F.SilkS")
		)
		(fp_line
			(start -1.651 -1.778)
			(end -1.651 1.778)
			(stroke
				(width 0.1524)
				(type default)
			)
			(layer "F.SilkS")
		)
		(fp_poly
			(pts
				(xy -1.778 1.8796) (xy -1.778 -1.8796) (xy 1.778 -1.8796) (xy 1.778 1.8796)
			)
			(stroke
				(width 0)
				(type default)
			)
			(fill no)
			(layer "F.CrtYd")
		)
		(fp_poly
			(pts
				(xy -1.778 1.8796) (xy -1.778 -1.8796) (xy 1.778 -1.8796) (xy 1.778 1.8796)
			)
			(stroke
				(width 0)
				(type default)
			)
			(fill no)
			(layer "F.Fab")
		)
		(pad "D" smd custom
			(at 0 -0.9525 180)
			(size 0.1905 0.1905)
			(layers "F.Cu" "F.Mask" "F.Paste")
			(net "FLT_HDD7_N")
			(options
				(clearance outline)
				(anchor circle)
			)
			(primitives
				(gr_poly
					(pts
						(arc
							(start -0.1778 0.5715)
							(mid -0.321484 0.511984)
							(end -0.381 0.3683)
						)
						(arc
							(start -0.381 -0.3683)
							(mid -0.321484 -0.511984)
							(end -0.1778 -0.5715)
						)
						(arc
							(start 0.1778 -0.5715)
							(mid 0.321484 -0.511984)
							(end 0.381 -0.3683)
						)
						(arc
							(start 0.381 0.3683)
							(mid 0.321484 0.511984)
							(end 0.1778 0.5715)
						)
					)
					(width 0)
					(fill yes)
				)
			)
		)
		(pad "G" smd custom
			(at -0.98425 0.9525 180)
			(size 0.1905 0.1905)
			(layers "F.Cu" "F.Mask" "F.Paste")
			(net "DRIVE_B_7_FLT_LED")
			(options
				(clearance outline)
				(anchor circle)
			)
			(primitives
				(gr_poly
					(pts
						(arc
							(start -0.1778 0.5715)
							(mid -0.321484 0.511984)
							(end -0.381 0.3683)
						)
						(arc
							(start -0.381 -0.3683)
							(mid -0.321484 -0.511984)
							(end -0.1778 -0.5715)
						)
						(arc
							(start 0.1778 -0.5715)
							(mid 0.321484 -0.511984)
							(end 0.381 -0.3683)
						)
						(arc
							(start 0.381 0.3683)
							(mid 0.321484 0.511984)
							(end 0.1778 0.5715)
						)
					)
					(width 0)
					(fill yes)
				)
			)
		)
		(pad "S" smd custom
			(at 0.98425 0.9525 180)
			(size 0.1905 0.1905)
			(layers "F.Cu" "F.Mask" "F.Paste")
			(net "GND")
			(options
				(clearance outline)
				(anchor circle)
			)
			(primitives
				(gr_poly
					(pts
						(arc
							(start -0.1778 0.5715)
							(mid -0.321484 0.511984)
							(end -0.381 0.3683)
						)
						(arc
							(start -0.381 -0.3683)
							(mid -0.321484 -0.511984)
							(end -0.1778 -0.5715)
						)
						(arc
							(start 0.1778 -0.5715)
							(mid 0.321484 -0.511984)
							(end 0.381 -0.3683)
						)
						(arc
							(start 0.381 0.3683)
							(mid 0.321484 0.511984)
							(end 0.1778 0.5715)
						)
					)
					(width 0)
					(fill yes)
				)
			)
		)
	)
	(footprint ""
		(layer "F.Cu")
		(at 463.423 -248.793 90)
		(property "Reference" "D10"
			(at 0 0 90)
			(layer "F.SilkS")
			(hide yes)
			(effects
				(font
					(size 1.27 1.27)
				)
			)
		)
		(property "Value" "RB551V30-GP"
			(at 0 -6.7818 90)
			(unlocked yes)
			(layer "F.Fab")
			(hide yes)
			(effects
				(font
					(size 1.016 1.016)
					(thickness 0.1524)
				)
			)
		)
		(property "Device Type" "SOD323AKH38"
			(at 0 -8.6868 90)
			(unlocked yes)
			(layer "F.Fab")
			(hide yes)
			(effects
				(font
					(size 1.016 1.016)
					(thickness 0.1524)
				)
			)
		)
		(duplicate_pad_numbers_are_jumpers no)
		(fp_line
			(start 0.889 -1.9304)
			(end 0.889 2.159)
			(stroke
				(width 0.1524)
				(type default)
			)
			(layer "F.SilkS")
		)
		(fp_line
			(start -0.889 -1.9304)
			(end 0.889 -1.9304)
			(stroke
				(width 0.1524)
				(type default)
			)
			(layer "F.SilkS")
		)
		(fp_line
			(start 0.762 2.0574)
			(end -0.762 2.0574)
			(stroke
				(width 0.508)
				(type default)
			)
			(layer "F.SilkS")
		)
		(fp_line
			(start 0.889 2.159)
			(end -0.889 2.159)
			(stroke
				(width 0.1524)
				(type default)
			)
			(layer "F.SilkS")
		)
		(fp_line
			(start -0.889 2.159)
			(end -0.889 -1.9304)
			(stroke
				(width 0.1524)
				(type default)
			)
			(layer "F.SilkS")
		)
		(fp_rect
			(start -1.016 2.3114)
			(end 1.016 -2.0066)
			(stroke
				(width 0)
				(type default)
			)
			(fill no)
			(layer "F.CrtYd")
		)
		(fp_poly
			(pts
				(xy -1.016 -2.0066) (xy 1.016 -2.0066) (xy 1.016 2.3114) (xy -1.016 2.3114)
			)
			(stroke
				(width 0)
				(type default)
			)
			(fill no)
			(layer "F.Fab")
		)
		(pad "A" smd rect
			(at 0 -1.143 90)
			(size 0.5588 1.016)
			(layers "F.Cu" "F.Mask" "F.Paste")
			(net "SW_HDD_R10")
		)
		(pad "K" smd rect
			(at 0 1.143 90)
			(size 0.5588 1.016)
			(layers "F.Cu" "F.Mask" "F.Paste")
			(net "SW_HDD_N10")
		)
	)
	(footprint ""
		(layer "F.Cu")
		(at 221.996 -224.282 90)
		(property "Reference" "R21"
			(at 0 0 90)
			(layer "F.SilkS")
			(hide yes)
			(effects
				(font
					(size 1.27 1.27)
				)
			)
		)
		(property "Value" "0R2J-2-GP"
			(at 0.064008 -3.993896 90)
			(unlocked yes)
			(layer "F.Fab")
			(hide yes)
			(effects
				(font
					(size 1.016 1.016)
					(thickness 0.1524)
				)
			)
		)
		(property "Device Type" "R402H16"
			(at 0.064008 -5.517896 90)
			(unlocked yes)
			(layer "F.Fab")
			(hide yes)
			(effects
				(font
					(size 1.016 1.016)
					(thickness 0.1524)
				)
			)
		)
		(duplicate_pad_numbers_are_jumpers no)
		(fp_line
			(start 0.508 -0.9398)
			(end -0.508 -0.9398)
			(stroke
				(width 0.1524)
				(type default)
			)
			(layer "F.SilkS")
		)
		(fp_line
			(start -0.508 -0.9398)
			(end -0.508 0.9398)
			(stroke
				(width 0.1524)
				(type default)
			)
			(layer "F.SilkS")
		)
		(fp_rect
			(start -0.508 0.9398)
			(end 0.508 -0.9398)
			(stroke
				(width 0)
				(type default)
			)
			(fill no)
			(layer "F.CrtYd")
		)
		(fp_rect
			(start -0.508 0.9398)
			(end 0.508 -0.9398)
			(stroke
				(width 0)
				(type default)
			)
			(fill no)
			(layer "F.Fab")
		)
		(pad "1" smd custom
			(at 0 -0.4445 90)
			(size 0.1397 0.1397)
			(layers "F.Cu" "F.Mask" "F.Paste")
			(net "IO_EXP1_LED_SDA")
			(options
				(clearance outline)
				(anchor circle)
			)
			(primitives
				(gr_poly
					(pts
						(arc
							(start -0.1778 -0.2794)
							(mid -0.249642 -0.249642)
							(end -0.2794 -0.1778)
						)
						(arc
							(start -0.2794 0.1778)
							(mid -0.249642 0.249642)
							(end -0.1778 0.2794)
						)
						(arc
							(start 0.1778 0.2794)
							(mid 0.249642 0.249642)
							(end 0.2794 0.1778)
						)
						(arc
							(start 0.2794 -0.1778)
							(mid 0.249642 -0.249642)
							(end 0.1778 -0.2794)
						)
					)
					(width 0)
					(fill yes)
				)
			)
		)
		(pad "2" smd custom
			(at 0 0.4445 90)
			(size 0.1397 0.1397)
			(layers "F.Cu" "F.Mask" "F.Paste")
			(net "I2C_DRIVE_B_FLT_LED_SDA")
			(options
				(clearance outline)
				(anchor circle)
			)
			(primitives
				(gr_poly
					(pts
						(arc
							(start -0.1778 -0.2794)
							(mid -0.249642 -0.249642)
							(end -0.2794 -0.1778)
						)
						(arc
							(start -0.2794 0.1778)
							(mid -0.249642 0.249642)
							(end -0.1778 0.2794)
						)
						(arc
							(start 0.1778 0.2794)
							(mid 0.249642 0.249642)
							(end 0.2794 0.1778)
						)
						(arc
							(start 0.2794 -0.1778)
							(mid 0.249642 -0.249642)
							(end 0.1778 -0.2794)
						)
					)
					(width 0)
					(fill yes)
				)
			)
		)
	)
	(footprint ""
		(layer "F.Cu")
		(at 79.883 -253.111 90)
		(property "Reference" "R195"
			(at 0 0 90)
			(layer "F.SilkS")
			(hide yes)
			(effects
				(font
					(size 1.27 1.27)
				)
			)
		)
		(property "Value" "4K7R2J-2-GP"
			(at 0.064008 -3.993896 90)
			(unlocked yes)
			(layer "F.Fab")
			(hide yes)
			(effects
				(font
					(size 1.016 1.016)
					(thickness 0.1524)
				)
			)
		)
		(property "Device Type" "R402H16"
			(at 0.064008 -5.517896 90)
			(unlocked yes)
			(layer "F.Fab")
			(hide yes)
			(effects
				(font
					(size 1.016 1.016)
					(thickness 0.1524)
				)
			)
		)
		(duplicate_pad_numbers_are_jumpers no)
		(fp_line
			(start 0.508 -0.9398)
			(end -0.508 -0.9398)
			(stroke
				(width 0.1524)
				(type default)
			)
			(layer "F.SilkS")
		)
		(fp_line
			(start -0.508 -0.9398)
			(end -0.508 0.9398)
			(stroke
				(width 0.1524)
				(type default)
			)
			(layer "F.SilkS")
		)
		(fp_rect
			(start -0.508 0.9398)
			(end 0.508 -0.9398)
			(stroke
				(width 0)
				(type default)
			)
			(fill no)
			(layer "F.CrtYd")
		)
		(fp_rect
			(start -0.508 0.9398)
			(end 0.508 -0.9398)
			(stroke
				(width 0)
				(type default)
			)
			(fill no)
			(layer "F.Fab")
		)
		(pad "1" smd custom
			(at 0 -0.4445 90)
			(size 0.1397 0.1397)
			(layers "F.Cu" "F.Mask" "F.Paste")
			(net "P12V_B")
			(options
				(clearance outline)
				(anchor circle)
			)
			(primitives
				(gr_poly
					(pts
						(arc
							(start -0.1778 -0.2794)
							(mid -0.249642 -0.249642)
							(end -0.2794 -0.1778)
						)
						(arc
							(start -0.2794 0.1778)
							(mid -0.249642 0.249642)
							(end -0.1778 0.2794)
						)
						(arc
							(start 0.1778 0.2794)
							(mid 0.249642 0.249642)
							(end 0.2794 0.1778)
						)
						(arc
							(start 0.2794 -0.1778)
							(mid 0.249642 -0.249642)
							(end 0.1778 -0.2794)
						)
					)
					(width 0)
					(fill yes)
				)
			)
		)
		(pad "2" smd custom
			(at 0 0.4445 90)
			(size 0.1397 0.1397)
			(layers "F.Cu" "F.Mask" "F.Paste")
			(net "SW_HDD_P2")
			(options
				(clearance outline)
				(anchor circle)
			)
			(primitives
				(gr_poly
					(pts
						(arc
							(start -0.1778 -0.2794)
							(mid -0.249642 -0.249642)
							(end -0.2794 -0.1778)
						)
						(arc
							(start -0.2794 0.1778)
							(mid -0.249642 0.249642)
							(end -0.1778 0.2794)
						)
						(arc
							(start 0.1778 0.2794)
							(mid 0.249642 0.249642)
							(end 0.2794 0.1778)
						)
						(arc
							(start 0.2794 -0.1778)
							(mid 0.249642 -0.249642)
							(end 0.1778 -0.2794)
						)
					)
					(width 0)
					(fill yes)
				)
			)
		)
	)
	(footprint ""
		(layer "F.Cu")
		(at 448.538854 -102.184454 -90)
		(property "Reference" "R482"
			(at 0 0 270)
			(layer "F.SilkS")
			(hide yes)
			(effects
				(font
					(size 1.27 1.27)
				)
			)
		)
		(property "Value" "4K7R2F-GP"
			(at 0.064008 -3.993896 270)
			(unlocked yes)
			(layer "F.Fab")
			(hide yes)
			(effects
				(font
					(size 1.016 1.016)
					(thickness 0.1524)
				)
			)
		)
		(property "Device Type" "R402H16"
			(at 0.064008 -5.517896 270)
			(unlocked yes)
			(layer "F.Fab")
			(hide yes)
			(effects
				(font
					(size 1.016 1.016)
					(thickness 0.1524)
				)
			)
		)
		(duplicate_pad_numbers_are_jumpers no)
		(fp_line
			(start -0.508 -0.9398)
			(end -0.508 0.9398)
			(stroke
				(width 0.1524)
				(type default)
			)
			(layer "F.SilkS")
		)
		(fp_line
			(start 0.508 -0.9398)
			(end -0.508 -0.9398)
			(stroke
				(width 0.1524)
				(type default)
			)
			(layer "F.SilkS")
		)
		(fp_rect
			(start -0.508 0.9398)
			(end 0.508 -0.9398)
			(stroke
				(width 0)
				(type default)
			)
			(fill no)
			(layer "F.CrtYd")
		)
		(fp_rect
			(start -0.508 0.9398)
			(end 0.508 -0.9398)
			(stroke
				(width 0)
				(type default)
			)
			(fill no)
			(layer "F.Fab")
		)
		(pad "1" smd custom
			(at 0 -0.4445 270)
			(size 0.1397 0.1397)
			(layers "F.Cu" "F.Mask" "F.Paste")
			(net "DRIVE_B_22_FLT_LED")
			(options
				(clearance outline)
				(anchor circle)
			)
			(primitives
				(gr_poly
					(pts
						(arc
							(start -0.1778 -0.2794)
							(mid -0.249642 -0.249642)
							(end -0.2794 -0.1778)
						)
						(arc
							(start -0.2794 0.1778)
							(mid -0.249642 0.249642)
							(end -0.1778 0.2794)
						)
						(arc
							(start 0.1778 0.2794)
							(mid 0.249642 0.249642)
							(end 0.2794 0.1778)
						)
						(arc
							(start 0.2794 -0.1778)
							(mid 0.249642 -0.249642)
							(end 0.1778 -0.2794)
						)
					)
					(width 0)
					(fill yes)
				)
			)
		)
		(pad "2" smd custom
			(at 0 0.4445 270)
			(size 0.1397 0.1397)
			(layers "F.Cu" "F.Mask" "F.Paste")
			(net "GND")
			(options
				(clearance outline)
				(anchor circle)
			)
			(primitives
				(gr_poly
					(pts
						(arc
							(start -0.1778 -0.2794)
							(mid -0.249642 -0.249642)
							(end -0.2794 -0.1778)
						)
						(arc
							(start -0.2794 0.1778)
							(mid -0.249642 0.249642)
							(end -0.1778 0.2794)
						)
						(arc
							(start 0.1778 0.2794)
							(mid 0.249642 0.249642)
							(end 0.2794 0.1778)
						)
						(arc
							(start 0.2794 -0.1778)
							(mid 0.249642 -0.249642)
							(end 0.1778 -0.2794)
						)
					)
					(width 0)
					(fill yes)
				)
			)
		)
	)
	(footprint ""
		(layer "F.Cu")
		(at 476.325692 -17.506188 -90)
		(property "Reference" "R879"
			(at 0 0 270)
			(layer "F.SilkS")
			(hide yes)
			(effects
				(font
					(size 1.27 1.27)
				)
			)
		)
		(property "Value" "220R3F-1-GP"
			(at -0.0254 -2.5146 270)
			(unlocked yes)
			(layer "F.Fab")
			(hide yes)
			(effects
				(font
					(size 1.016 1.016)
					(thickness 0.1524)
				)
			)
		)
		(property "Device Type" "R603H22"
			(at -0.0254 -4.0386 270)
			(unlocked yes)
			(layer "F.Fab")
			(hide yes)
			(effects
				(font
					(size 1.016 1.016)
					(thickness 0.1524)
				)
			)
		)
		(duplicate_pad_numbers_are_jumpers no)
		(fp_line
			(start -0.4826 0)
			(end -0.2032 0)
			(stroke
				(width 0.2032)
				(type default)
			)
			(layer "F.SilkS")
		)
		(fp_line
			(start 0.2032 0)
			(end 0.4826 0)
			(stroke
				(width 0.2032)
				(type default)
			)
			(layer "F.SilkS")
		)
		(fp_rect
			(start -0.5842 1.3335)
			(end 0.5842 -1.3335)
			(stroke
				(width 0)
				(type default)
			)
			(fill no)
			(layer "F.CrtYd")
		)
		(fp_rect
			(start -0.5842 1.3335)
			(end 0.5842 -1.3335)
			(stroke
				(width 0)
				(type default)
			)
			(fill no)
			(layer "F.Fab")
		)
		(pad "1" smd custom
			(at 0 -0.762 270)
			(size 0.2159 0.2159)
			(layers "F.Cu" "F.Mask" "F.Paste")
			(net "HDD_PRSNT_35")
			(options
				(clearance outline)
				(anchor circle)
			)
			(primitives
				(gr_poly
					(pts
						(arc
							(start -0.3302 -0.4318)
							(mid -0.402042 -0.402042)
							(end -0.4318 -0.3302)
						)
						(arc
							(start -0.4318 0.3302)
							(mid -0.402042 0.402042)
							(end -0.3302 0.4318)
						)
						(arc
							(start 0.3302 0.4318)
							(mid 0.402042 0.402042)
							(end 0.4318 0.3302)
						)
						(arc
							(start 0.4318 -0.3302)
							(mid 0.402042 -0.402042)
							(end 0.3302 -0.4318)
						)
					)
					(width 0)
					(fill yes)
				)
			)
		)
		(pad "2" smd custom
			(at 0 0.762 270)
			(size 0.2159 0.2159)
			(layers "F.Cu" "F.Mask" "F.Paste")
			(net "DRIVE_B_35_INS")
			(options
				(clearance outline)
				(anchor circle)
			)
			(primitives
				(gr_poly
					(pts
						(arc
							(start -0.3302 -0.4318)
							(mid -0.402042 -0.402042)
							(end -0.4318 -0.3302)
						)
						(arc
							(start -0.4318 0.3302)
							(mid -0.402042 0.402042)
							(end -0.3302 0.4318)
						)
						(arc
							(start 0.3302 0.4318)
							(mid 0.402042 0.402042)
							(end 0.4318 0.3302)
						)
						(arc
							(start 0.4318 -0.3302)
							(mid 0.402042 -0.402042)
							(end 0.3302 -0.4318)
						)
					)
					(width 0)
					(fill yes)
				)
			)
		)
	)
	(footprint ""
		(layer "F.Cu")
		(at 26.790396 -374.64619)
		(property "Reference" "R1301"
			(at 0 0 0)
			(layer "F.SilkS")
			(hide yes)
			(effects
				(font
					(size 1.27 1.27)
				)
			)
		)
		(property "Value" "4K7R2F-GP"
			(at 0.064008 -3.993896 0)
			(unlocked yes)
			(layer "F.Fab")
			(hide yes)
			(effects
				(font
					(size 1.016 1.016)
					(thickness 0.1524)
				)
			)
		)
		(property "Device Type" "R402H16"
			(at 0.064008 -5.517896 0)
			(unlocked yes)
			(layer "F.Fab")
			(hide yes)
			(effects
				(font
					(size 1.016 1.016)
					(thickness 0.1524)
				)
			)
		)
		(duplicate_pad_numbers_are_jumpers no)
		(fp_line
			(start -0.508 -0.9398)
			(end -0.508 0.9398)
			(stroke
				(width 0.1524)
				(type default)
			)
			(layer "F.SilkS")
		)
		(fp_line
			(start 0.508 -0.9398)
			(end -0.508 -0.9398)
			(stroke
				(width 0.1524)
				(type default)
			)
			(layer "F.SilkS")
		)
		(fp_rect
			(start -0.508 0.9398)
			(end 0.508 -0.9398)
			(stroke
				(width 0)
				(type default)
			)
			(fill no)
			(layer "F.CrtYd")
		)
		(fp_rect
			(start -0.508 0.9398)
			(end 0.508 -0.9398)
			(stroke
				(width 0)
				(type default)
			)
			(fill no)
			(layer "F.Fab")
		)
		(pad "1" smd custom
			(at 0 -0.4445)
			(size 0.1397 0.1397)
			(layers "F.Cu" "F.Mask" "F.Paste")
			(net "FAN_BLUE_LED0")
			(options
				(clearance outline)
				(anchor circle)
			)
			(primitives
				(gr_poly
					(pts
						(arc
							(start -0.1778 -0.2794)
							(mid -0.249642 -0.249642)
							(end -0.2794 -0.1778)
						)
						(arc
							(start -0.2794 0.1778)
							(mid -0.249642 0.249642)
							(end -0.1778 0.2794)
						)
						(arc
							(start 0.1778 0.2794)
							(mid 0.249642 0.249642)
							(end 0.2794 0.1778)
						)
						(arc
							(start 0.2794 -0.1778)
							(mid 0.249642 -0.249642)
							(end 0.1778 -0.2794)
						)
					)
					(width 0)
					(fill yes)
				)
			)
		)
		(pad "2" smd custom
			(at 0 0.4445)
			(size 0.1397 0.1397)
			(layers "F.Cu" "F.Mask" "F.Paste")
			(net "FAN_LED0_D")
			(options
				(clearance outline)
				(anchor circle)
			)
			(primitives
				(gr_poly
					(pts
						(arc
							(start -0.1778 -0.2794)
							(mid -0.249642 -0.249642)
							(end -0.2794 -0.1778)
						)
						(arc
							(start -0.2794 0.1778)
							(mid -0.249642 0.249642)
							(end -0.1778 0.2794)
						)
						(arc
							(start 0.1778 0.2794)
							(mid 0.249642 0.249642)
							(end 0.2794 0.1778)
						)
						(arc
							(start 0.2794 -0.1778)
							(mid 0.249642 -0.249642)
							(end 0.1778 -0.2794)
						)
					)
					(width 0)
					(fill yes)
				)
			)
		)
	)
	(footprint ""
		(layer "F.Cu")
		(at 219.6084 -197.8914 -90)
		(property "Reference" "C5"
			(at 0 0 270)
			(layer "F.SilkS")
			(hide yes)
			(effects
				(font
					(size 1.27 1.27)
				)
			)
		)
		(property "Value" "SC1U16V3KX-5GP"
			(at 0 -2.8194 270)
			(unlocked yes)
			(layer "F.Fab")
			(hide yes)
			(effects
				(font
					(size 1.016 1.016)
					(thickness 0.1524)
				)
			)
		)
		(property "Device Type" "C603H36"
			(at 0 -4.3434 270)
			(unlocked yes)
			(layer "F.Fab")
			(hide yes)
			(effects
				(font
					(size 1.016 1.016)
					(thickness 0.1524)
				)
			)
		)
		(duplicate_pad_numbers_are_jumpers no)
		(fp_line
			(start 0.508 0)
			(end -0.508 0)
			(stroke
				(width 0.2032)
				(type default)
			)
			(layer "F.SilkS")
		)
		(fp_rect
			(start -0.5842 1.3335)
			(end 0.5842 -1.3335)
			(stroke
				(width 0)
				(type default)
			)
			(fill no)
			(layer "F.CrtYd")
		)
		(fp_rect
			(start -0.5842 1.3335)
			(end 0.5842 -1.3335)
			(stroke
				(width 0)
				(type default)
			)
			(fill no)
			(layer "F.Fab")
		)
		(pad "1" smd custom
			(at 0 -0.762 270)
			(size 0.2159 0.2159)
			(layers "F.Cu" "F.Mask" "F.Paste")
			(net "P3V3_STBY_B")
			(options
				(clearance outline)
				(anchor circle)
			)
			(primitives
				(gr_poly
					(pts
						(arc
							(start -0.3302 -0.4318)
							(mid -0.402042 -0.402042)
							(end -0.4318 -0.3302)
						)
						(arc
							(start -0.4318 0.3302)
							(mid -0.402042 0.402042)
							(end -0.3302 0.4318)
						)
						(arc
							(start 0.3302 0.4318)
							(mid 0.402042 0.402042)
							(end 0.4318 0.3302)
						)
						(arc
							(start 0.4318 -0.3302)
							(mid 0.402042 -0.402042)
							(end 0.3302 -0.4318)
						)
					)
					(width 0)
					(fill yes)
				)
			)
		)
		(pad "2" smd custom
			(at 0 0.762 270)
			(size 0.2159 0.2159)
			(layers "F.Cu" "F.Mask" "F.Paste")
			(net "GND")
			(options
				(clearance outline)
				(anchor circle)
			)
			(primitives
				(gr_poly
					(pts
						(arc
							(start -0.3302 -0.4318)
							(mid -0.402042 -0.402042)
							(end -0.4318 -0.3302)
						)
						(arc
							(start -0.4318 0.3302)
							(mid -0.402042 0.402042)
							(end -0.3302 0.4318)
						)
						(arc
							(start 0.3302 0.4318)
							(mid 0.402042 0.402042)
							(end 0.4318 0.3302)
						)
						(arc
							(start 0.4318 -0.3302)
							(mid 0.402042 -0.402042)
							(end 0.3302 -0.4318)
						)
					)
					(width 0)
					(fill yes)
				)
			)
		)
	)
	(footprint ""
		(layer "F.Cu")
		(at 148.5392 -246.253 -90)
		(property "Reference" "R230"
			(at 0 0 270)
			(layer "F.SilkS")
			(hide yes)
			(effects
				(font
					(size 1.27 1.27)
				)
			)
		)
		(property "Value" "0R2J-2-GP"
			(at 0.064008 -3.993896 270)
			(unlocked yes)
			(layer "F.Fab")
			(hide yes)
			(effects
				(font
					(size 1.016 1.016)
					(thickness 0.1524)
				)
			)
		)
		(property "Device Type" "R402H16"
			(at 0.064008 -5.517896 270)
			(unlocked yes)
			(layer "F.Fab")
			(hide yes)
			(effects
				(font
					(size 1.016 1.016)
					(thickness 0.1524)
				)
			)
		)
		(duplicate_pad_numbers_are_jumpers no)
		(fp_line
			(start -0.508 -0.9398)
			(end -0.508 0.9398)
			(stroke
				(width 0.1524)
				(type default)
			)
			(layer "F.SilkS")
		)
		(fp_line
			(start 0.508 -0.9398)
			(end -0.508 -0.9398)
			(stroke
				(width 0.1524)
				(type default)
			)
			(layer "F.SilkS")
		)
		(fp_rect
			(start -0.508 0.9398)
			(end 0.508 -0.9398)
			(stroke
				(width 0)
				(type default)
			)
			(fill no)
			(layer "F.CrtYd")
		)
		(fp_rect
			(start -0.508 0.9398)
			(end 0.508 -0.9398)
			(stroke
				(width 0)
				(type default)
			)
			(fill no)
			(layer "F.Fab")
		)
		(pad "1" smd custom
			(at 0 -0.4445 270)
			(size 0.1397 0.1397)
			(layers "F.Cu" "F.Mask" "F.Paste")
			(net "DRIVE_B_4_PWR")
			(options
				(clearance outline)
				(anchor circle)
			)
			(primitives
				(gr_poly
					(pts
						(arc
							(start -0.1778 -0.2794)
							(mid -0.249642 -0.249642)
							(end -0.2794 -0.1778)
						)
						(arc
							(start -0.2794 0.1778)
							(mid -0.249642 0.249642)
							(end -0.1778 0.2794)
						)
						(arc
							(start 0.1778 0.2794)
							(mid 0.249642 0.249642)
							(end 0.2794 0.1778)
						)
						(arc
							(start 0.2794 -0.1778)
							(mid 0.249642 -0.249642)
							(end 0.1778 -0.2794)
						)
					)
					(width 0)
					(fill yes)
				)
			)
		)
		(pad "2" smd custom
			(at 0 0.4445 270)
			(size 0.1397 0.1397)
			(layers "F.Cu" "F.Mask" "F.Paste")
			(net "SW_PWR_R_HDD4")
			(options
				(clearance outline)
				(anchor circle)
			)
			(primitives
				(gr_poly
					(pts
						(arc
							(start -0.1778 -0.2794)
							(mid -0.249642 -0.249642)
							(end -0.2794 -0.1778)
						)
						(arc
							(start -0.2794 0.1778)
							(mid -0.249642 0.249642)
							(end -0.1778 0.2794)
						)
						(arc
							(start 0.1778 0.2794)
							(mid 0.249642 0.249642)
							(end 0.2794 0.1778)
						)
						(arc
							(start 0.2794 -0.1778)
							(mid 0.249642 -0.249642)
							(end 0.1778 -0.2794)
						)
					)
					(width 0)
					(fill yes)
				)
			)
		)
	)
	(footprint ""
		(layer "F.Cu")
		(at 242.57 -138.7094 180)
		(property "Reference" "R605"
			(at 0 0 180)
			(layer "F.SilkS")
			(hide yes)
			(effects
				(font
					(size 1.27 1.27)
				)
			)
		)
		(property "Value" "2K2R2F-GP"
			(at 0.064008 -3.993896 180)
			(unlocked yes)
			(layer "F.Fab")
			(hide yes)
			(effects
				(font
					(size 1.016 1.016)
					(thickness 0.1524)
				)
			)
		)
		(property "Device Type" "R402H16"
			(at 0.064008 -5.517896 180)
			(unlocked yes)
			(layer "F.Fab")
			(hide yes)
			(effects
				(font
					(size 1.016 1.016)
					(thickness 0.1524)
				)
			)
		)
		(duplicate_pad_numbers_are_jumpers no)
		(fp_line
			(start 0.508 -0.9398)
			(end -0.508 -0.9398)
			(stroke
				(width 0.1524)
				(type default)
			)
			(layer "F.SilkS")
		)
		(fp_line
			(start -0.508 -0.9398)
			(end -0.508 0.9398)
			(stroke
				(width 0.1524)
				(type default)
			)
			(layer "F.SilkS")
		)
		(fp_rect
			(start -0.508 0.9398)
			(end 0.508 -0.9398)
			(stroke
				(width 0)
				(type default)
			)
			(fill no)
			(layer "F.CrtYd")
		)
		(fp_rect
			(start -0.508 0.9398)
			(end 0.508 -0.9398)
			(stroke
				(width 0)
				(type default)
			)
			(fill no)
			(layer "F.Fab")
		)
		(pad "1" smd custom
			(at 0 -0.4445 180)
			(size 0.1397 0.1397)
			(layers "F.Cu" "F.Mask" "F.Paste")
			(net "P3V3_STBY_B")
			(options
				(clearance outline)
				(anchor circle)
			)
			(primitives
				(gr_poly
					(pts
						(arc
							(start -0.1778 -0.2794)
							(mid -0.249642 -0.249642)
							(end -0.2794 -0.1778)
						)
						(arc
							(start -0.2794 0.1778)
							(mid -0.249642 0.249642)
							(end -0.1778 0.2794)
						)
						(arc
							(start 0.1778 0.2794)
							(mid 0.249642 0.249642)
							(end 0.2794 0.1778)
						)
						(arc
							(start 0.2794 -0.1778)
							(mid 0.249642 -0.249642)
							(end 0.1778 -0.2794)
						)
					)
					(width 0)
					(fill yes)
				)
			)
		)
		(pad "2" smd custom
			(at 0 0.4445 180)
			(size 0.1397 0.1397)
			(layers "F.Cu" "F.Mask" "F.Paste")
			(net "I2C_SCC_B_SCL")
			(options
				(clearance outline)
				(anchor circle)
			)
			(primitives
				(gr_poly
					(pts
						(arc
							(start -0.1778 -0.2794)
							(mid -0.249642 -0.249642)
							(end -0.2794 -0.1778)
						)
						(arc
							(start -0.2794 0.1778)
							(mid -0.249642 0.249642)
							(end -0.1778 0.2794)
						)
						(arc
							(start 0.1778 0.2794)
							(mid 0.249642 0.249642)
							(end 0.2794 0.1778)
						)
						(arc
							(start 0.2794 -0.1778)
							(mid 0.249642 -0.249642)
							(end 0.1778 -0.2794)
						)
					)
					(width 0)
					(fill yes)
				)
			)
		)
	)
	(footprint ""
		(layer "F.Cu")
		(at 401.828 -142.875 -90)
		(property "Reference" "R545"
			(at 0 0 270)
			(layer "F.SilkS")
			(hide yes)
			(effects
				(font
					(size 1.27 1.27)
				)
			)
		)
		(property "Value" "300KR2F-GP"
			(at 0.064008 -3.993896 270)
			(unlocked yes)
			(layer "F.Fab")
			(hide yes)
			(effects
				(font
					(size 1.016 1.016)
					(thickness 0.1524)
				)
			)
		)
		(property "Device Type" "R402H16"
			(at 0.064008 -5.517896 270)
			(unlocked yes)
			(layer "F.Fab")
			(hide yes)
			(effects
				(font
					(size 1.016 1.016)
					(thickness 0.1524)
				)
			)
		)
		(duplicate_pad_numbers_are_jumpers no)
		(fp_line
			(start -0.508 -0.9398)
			(end -0.508 0.9398)
			(stroke
				(width 0.1524)
				(type default)
			)
			(layer "F.SilkS")
		)
		(fp_line
			(start 0.508 -0.9398)
			(end -0.508 -0.9398)
			(stroke
				(width 0.1524)
				(type default)
			)
			(layer "F.SilkS")
		)
		(fp_rect
			(start -0.508 0.9398)
			(end 0.508 -0.9398)
			(stroke
				(width 0)
				(type default)
			)
			(fill no)
			(layer "F.CrtYd")
		)
		(fp_rect
			(start -0.508 0.9398)
			(end 0.508 -0.9398)
			(stroke
				(width 0)
				(type default)
			)
			(fill no)
			(layer "F.Fab")
		)
		(pad "1" smd custom
			(at 0 -0.4445 270)
			(size 0.1397 0.1397)
			(layers "F.Cu" "F.Mask" "F.Paste")
			(net "SW_HDD_N20")
			(options
				(clearance outline)
				(anchor circle)
			)
			(primitives
				(gr_poly
					(pts
						(arc
							(start -0.1778 -0.2794)
							(mid -0.249642 -0.249642)
							(end -0.2794 -0.1778)
						)
						(arc
							(start -0.2794 0.1778)
							(mid -0.249642 0.249642)
							(end -0.1778 0.2794)
						)
						(arc
							(start 0.1778 0.2794)
							(mid 0.249642 0.249642)
							(end 0.2794 0.1778)
						)
						(arc
							(start 0.2794 -0.1778)
							(mid 0.249642 -0.249642)
							(end 0.1778 -0.2794)
						)
					)
					(width 0)
					(fill yes)
				)
			)
		)
		(pad "2" smd custom
			(at 0 0.4445 270)
			(size 0.1397 0.1397)
			(layers "F.Cu" "F.Mask" "F.Paste")
			(net "P12V_B")
			(options
				(clearance outline)
				(anchor circle)
			)
			(primitives
				(gr_poly
					(pts
						(arc
							(start -0.1778 -0.2794)
							(mid -0.249642 -0.249642)
							(end -0.2794 -0.1778)
						)
						(arc
							(start -0.2794 0.1778)
							(mid -0.249642 0.249642)
							(end -0.1778 0.2794)
						)
						(arc
							(start 0.1778 0.2794)
							(mid 0.249642 0.249642)
							(end 0.2794 0.1778)
						)
						(arc
							(start 0.2794 -0.1778)
							(mid 0.249642 -0.249642)
							(end 0.1778 -0.2794)
						)
					)
					(width 0)
					(fill yes)
				)
			)
		)
	)
	(footprint ""
		(layer "F.Cu")
		(at 305.044348 -357.530908 180)
		(property "Reference" "C631"
			(at 0 0 180)
			(layer "F.SilkS")
			(hide yes)
			(effects
				(font
					(size 1.27 1.27)
				)
			)
		)
		(property "Value" "SCD1U16V2KX-3GP"
			(at 1.1811 -2.7051 180)
			(unlocked yes)
			(layer "F.Fab")
			(hide yes)
			(effects
				(font
					(size 1.016 1.016)
					(thickness 0.1524)
				)
			)
		)
		(property "Device Type" "C402H22"
			(at 1.1811 -4.2291 180)
			(unlocked yes)
			(layer "F.Fab")
			(hide yes)
			(effects
				(font
					(size 1.016 1.016)
					(thickness 0.1524)
				)
			)
		)
		(duplicate_pad_numbers_are_jumpers no)
		(fp_rect
			(start -0.4318 0.9525)
			(end 0.4318 -0.9525)
			(stroke
				(width 0)
				(type default)
			)
			(fill no)
			(layer "F.CrtYd")
		)
		(fp_rect
			(start -0.4318 0.9525)
			(end 0.4318 -0.9525)
			(stroke
				(width 0)
				(type default)
			)
			(fill no)
			(layer "F.Fab")
		)
		(pad "1" smd custom
			(at 0 -0.4445 180)
			(size 0.1524 0.1524)
			(layers "F.Cu" "F.Mask" "F.Paste")
			(net "P3V3_IN")
			(options
				(clearance outline)
				(anchor circle)
			)
			(primitives
				(gr_poly
					(pts
						(arc
							(start 0.3048 -0.2032)
							(mid 0.275042 -0.275042)
							(end 0.2032 -0.3048)
						)
						(arc
							(start -0.2032 -0.3048)
							(mid -0.275042 -0.275042)
							(end -0.3048 -0.2032)
						)
						(arc
							(start -0.3048 0.2032)
							(mid -0.275042 0.275042)
							(end -0.2032 0.3048)
						)
						(arc
							(start 0.2032 0.3048)
							(mid 0.275042 0.275042)
							(end 0.3048 0.2032)
						)
					)
					(width 0)
					(fill yes)
				)
			)
		)
		(pad "2" smd custom
			(at 0 0.4445 180)
			(size 0.1524 0.1524)
			(layers "F.Cu" "F.Mask" "F.Paste")
			(net "GND")
			(options
				(clearance outline)
				(anchor circle)
			)
			(primitives
				(gr_poly
					(pts
						(arc
							(start 0.3048 -0.2032)
							(mid 0.275042 -0.275042)
							(end 0.2032 -0.3048)
						)
						(arc
							(start -0.2032 -0.3048)
							(mid -0.275042 -0.275042)
							(end -0.3048 -0.2032)
						)
						(arc
							(start -0.3048 0.2032)
							(mid -0.275042 0.275042)
							(end -0.2032 0.3048)
						)
						(arc
							(start 0.2032 0.3048)
							(mid 0.275042 0.275042)
							(end 0.3048 0.2032)
						)
					)
					(width 0)
					(fill yes)
				)
			)
		)
	)
	(footprint ""
		(layer "F.Cu")
		(at 78.11135 -217.413586 -90)
		(property "Reference" "R171"
			(at 0 0 270)
			(layer "F.SilkS")
			(hide yes)
			(effects
				(font
					(size 1.27 1.27)
				)
			)
		)
		(property "Value" "4K7R2F-GP"
			(at 0.064008 -3.993896 270)
			(unlocked yes)
			(layer "F.Fab")
			(hide yes)
			(effects
				(font
					(size 1.016 1.016)
					(thickness 0.1524)
				)
			)
		)
		(property "Device Type" "R402H16"
			(at 0.064008 -5.517896 270)
			(unlocked yes)
			(layer "F.Fab")
			(hide yes)
			(effects
				(font
					(size 1.016 1.016)
					(thickness 0.1524)
				)
			)
		)
		(duplicate_pad_numbers_are_jumpers no)
		(fp_line
			(start -0.508 -0.9398)
			(end -0.508 0.9398)
			(stroke
				(width 0.1524)
				(type default)
			)
			(layer "F.SilkS")
		)
		(fp_line
			(start 0.508 -0.9398)
			(end -0.508 -0.9398)
			(stroke
				(width 0.1524)
				(type default)
			)
			(layer "F.SilkS")
		)
		(fp_rect
			(start -0.508 0.9398)
			(end 0.508 -0.9398)
			(stroke
				(width 0)
				(type default)
			)
			(fill no)
			(layer "F.CrtYd")
		)
		(fp_rect
			(start -0.508 0.9398)
			(end 0.508 -0.9398)
			(stroke
				(width 0)
				(type default)
			)
			(fill no)
			(layer "F.Fab")
		)
		(pad "1" smd custom
			(at 0 -0.4445 270)
			(size 0.1397 0.1397)
			(layers "F.Cu" "F.Mask" "F.Paste")
			(net "DRIVE_B_2_FLT_LED")
			(options
				(clearance outline)
				(anchor circle)
			)
			(primitives
				(gr_poly
					(pts
						(arc
							(start -0.1778 -0.2794)
							(mid -0.249642 -0.249642)
							(end -0.2794 -0.1778)
						)
						(arc
							(start -0.2794 0.1778)
							(mid -0.249642 0.249642)
							(end -0.1778 0.2794)
						)
						(arc
							(start 0.1778 0.2794)
							(mid 0.249642 0.249642)
							(end 0.2794 0.1778)
						)
						(arc
							(start 0.2794 -0.1778)
							(mid 0.249642 -0.249642)
							(end 0.1778 -0.2794)
						)
					)
					(width 0)
					(fill yes)
				)
			)
		)
		(pad "2" smd custom
			(at 0 0.4445 270)
			(size 0.1397 0.1397)
			(layers "F.Cu" "F.Mask" "F.Paste")
			(net "GND")
			(options
				(clearance outline)
				(anchor circle)
			)
			(primitives
				(gr_poly
					(pts
						(arc
							(start -0.1778 -0.2794)
							(mid -0.249642 -0.249642)
							(end -0.2794 -0.1778)
						)
						(arc
							(start -0.2794 0.1778)
							(mid -0.249642 0.249642)
							(end -0.1778 0.2794)
						)
						(arc
							(start 0.1778 0.2794)
							(mid 0.249642 0.249642)
							(end 0.2794 0.1778)
						)
						(arc
							(start 0.2794 -0.1778)
							(mid 0.249642 -0.249642)
							(end 0.1778 -0.2794)
						)
					)
					(width 0)
					(fill yes)
				)
			)
		)
	)
	(footprint ""
		(layer "F.Cu")
		(at 73.861168 -99.874578 90)
		(property "Reference" "Q257"
			(at 0 0 90)
			(layer "F.SilkS")
			(hide yes)
			(effects
				(font
					(size 1.27 1.27)
				)
			)
		)
		(property "Value" "SSM3K324R-GP"
			(at 0.127 -8.9662 90)
			(unlocked yes)
			(layer "F.Fab")
			(hide yes)
			(effects
				(font
					(size 1.016 1.016)
					(thickness 0.1524)
				)
			)
		)
		(property "Device Type" "SOT23DGS2D4H35"
			(at 0.127 -10.4902 90)
			(unlocked yes)
			(layer "F.Fab")
			(hide yes)
			(effects
				(font
					(size 1.016 1.016)
					(thickness 0.1524)
				)
			)
		)
		(duplicate_pad_numbers_are_jumpers no)
		(fp_line
			(start 1.651 -1.778)
			(end -1.651 -1.778)
			(stroke
				(width 0.1524)
				(type default)
			)
			(layer "F.SilkS")
		)
		(fp_line
			(start -1.651 -1.778)
			(end -1.651 1.778)
			(stroke
				(width 0.1524)
				(type default)
			)
			(layer "F.SilkS")
		)
		(fp_line
			(start 1.651 1.778)
			(end 1.651 -1.778)
			(stroke
				(width 0.1524)
				(type default)
			)
			(layer "F.SilkS")
		)
		(fp_line
			(start -1.651 1.778)
			(end 1.651 1.778)
			(stroke
				(width 0.1524)
				(type default)
			)
			(layer "F.SilkS")
		)
		(fp_poly
			(pts
				(xy -1.778 1.8796) (xy -1.778 -1.8796) (xy 1.778 -1.8796) (xy 1.778 1.8796)
			)
			(stroke
				(width 0)
				(type default)
			)
			(fill no)
			(layer "F.CrtYd")
		)
		(fp_poly
			(pts
				(xy -1.778 1.8796) (xy -1.778 -1.8796) (xy 1.778 -1.8796) (xy 1.778 1.8796)
			)
			(stroke
				(width 0)
				(type default)
			)
			(fill no)
			(layer "F.Fab")
		)
		(pad "D" smd custom
			(at 0 -0.9525 90)
			(size 0.1905 0.1905)
			(layers "F.Cu" "F.Mask" "F.Paste")
			(net "DRV_ACT_14_N")
			(options
				(clearance outline)
				(anchor circle)
			)
			(primitives
				(gr_poly
					(pts
						(arc
							(start -0.1778 0.5715)
							(mid -0.321484 0.511984)
							(end -0.381 0.3683)
						)
						(arc
							(start -0.381 -0.3683)
							(mid -0.321484 -0.511984)
							(end -0.1778 -0.5715)
						)
						(arc
							(start 0.1778 -0.5715)
							(mid 0.321484 -0.511984)
							(end 0.381 -0.3683)
						)
						(arc
							(start 0.381 0.3683)
							(mid 0.321484 0.511984)
							(end 0.1778 0.5715)
						)
					)
					(width 0)
					(fill yes)
				)
			)
		)
		(pad "G" smd custom
			(at -0.98425 0.9525 90)
			(size 0.1905 0.1905)
			(layers "F.Cu" "F.Mask" "F.Paste")
			(net "DRIVE_B_14_ACT")
			(options
				(clearance outline)
				(anchor circle)
			)
			(primitives
				(gr_poly
					(pts
						(arc
							(start -0.1778 0.5715)
							(mid -0.321484 0.511984)
							(end -0.381 0.3683)
						)
						(arc
							(start -0.381 -0.3683)
							(mid -0.321484 -0.511984)
							(end -0.1778 -0.5715)
						)
						(arc
							(start 0.1778 -0.5715)
							(mid 0.321484 -0.511984)
							(end 0.381 -0.3683)
						)
						(arc
							(start 0.381 0.3683)
							(mid 0.321484 0.511984)
							(end 0.1778 0.5715)
						)
					)
					(width 0)
					(fill yes)
				)
			)
		)
		(pad "S" smd custom
			(at 0.98425 0.9525 90)
			(size 0.1905 0.1905)
			(layers "F.Cu" "F.Mask" "F.Paste")
			(net "GND")
			(options
				(clearance outline)
				(anchor circle)
			)
			(primitives
				(gr_poly
					(pts
						(arc
							(start -0.1778 0.5715)
							(mid -0.321484 0.511984)
							(end -0.381 0.3683)
						)
						(arc
							(start -0.381 -0.3683)
							(mid -0.321484 -0.511984)
							(end -0.1778 -0.5715)
						)
						(arc
							(start 0.1778 -0.5715)
							(mid 0.321484 -0.511984)
							(end 0.381 -0.3683)
						)
						(arc
							(start 0.381 0.3683)
							(mid 0.321484 0.511984)
							(end 0.1778 0.5715)
						)
					)
					(width 0)
					(fill yes)
				)
			)
		)
	)
	(footprint ""
		(layer "F.Cu")
		(at 185.950098 -28.910026 -90)
		(property "Reference" "HDDSAS29"
			(at 0 0 270)
			(layer "F.SilkS")
			(hide yes)
			(effects
				(font
					(size 1.27 1.27)
				)
			)
		)
		(property "Value" "SKT-SAS15P-14P-45-GP"
			(at -20.7645 -8.9789 270)
			(unlocked yes)
			(layer "F.Fab")
			(hide yes)
			(effects
				(font
					(size 1.016 1.016)
					(thickness 0.1524)
				)
			)
		)
		(property "Device Type" "10120818-001C-TRLF"
			(at -20.7645 -10.5029 270)
			(unlocked yes)
			(layer "F.Fab")
			(hide yes)
			(effects
				(font
					(size 1.016 1.016)
					(thickness 0.1524)
				)
			)
		)
		(duplicate_pad_numbers_are_jumpers no)
		(fp_line
			(start 1.651 4.2926)
			(end 1.651 3.0099)
			(stroke
				(width 0.1524)
				(type default)
			)
			(layer "F.SilkS")
		)
		(fp_line
			(start 8.509 4.2926)
			(end 1.651 4.2926)
			(stroke
				(width 0.1524)
				(type default)
			)
			(layer "F.SilkS")
		)
		(fp_line
			(start -23.4188 3.0099)
			(end -23.4188 -3.2512)
			(stroke
				(width 0.1524)
				(type default)
			)
			(layer "F.SilkS")
		)
		(fp_line
			(start 1.651 3.0099)
			(end -23.4188 3.0099)
			(stroke
				(width 0.1524)
				(type default)
			)
			(layer "F.SilkS")
		)
		(fp_line
			(start 8.509 3.0099)
			(end 8.509 4.2926)
			(stroke
				(width 0.1524)
				(type default)
			)
			(layer "F.SilkS")
		)
		(fp_line
			(start 23.4188 3.0099)
			(end 8.509 3.0099)
			(stroke
				(width 0.1524)
				(type default)
			)
			(layer "F.SilkS")
		)
		(fp_line
			(start -23.4188 -3.2512)
			(end 23.4188 -3.2512)
			(stroke
				(width 0.1524)
				(type default)
			)
			(layer "F.SilkS")
		)
		(fp_line
			(start 23.4188 -3.2512)
			(end 23.4188 3.0099)
			(stroke
				(width 0.1524)
				(type default)
			)
			(layer "F.SilkS")
		)
		(fp_line
			(start 15.5067 -3.3401)
			(end 16.2687 -3.3401)
			(stroke
				(width 0.3302)
				(type default)
			)
			(layer "F.SilkS")
		)
		(fp_poly
			(pts
				(xy 15.868904 -3.230372) (xy 16.503904 -3.865372) (xy 15.233904 -3.865372)
			)
			(stroke
				(width 0)
				(type default)
			)
			(fill yes)
			(layer "F.SilkS")
		)
		(fp_poly
			(pts
				(xy -22.8727 -2.7559) (xy 22.8727 -2.7559) (xy 22.8727 2.7559) (xy 8.255 2.7559) (xy 8.255 3.5179)
				(xy 1.905 3.5179) (xy 1.905 2.7559) (xy -22.8727 2.7559)
			)
			(stroke
				(width 0)
				(type default)
			)
			(fill no)
			(layer "F.CrtYd")
		)
		(fp_poly
			(pts
				(xy 1.397 4.5466) (xy 1.397 3.2639) (xy -23.6728 3.2639) (xy -23.6728 -3.5052) (xy 23.6728 -3.5052)
				(xy 23.6728 -0.00635) (xy 22.8727 -0.00635) (xy 22.8727 -2.7559) (xy -22.8727 -2.7559) (xy -22.8727 2.7559)
				(xy 1.905 2.7559) (xy 1.905 3.5179) (xy 8.255 3.5179) (xy 8.255 2.7559) (xy 22.8727 2.7559) (xy 22.8727 0.00635)
				(xy 23.6728 0.00635) (xy 23.6728 3.2639) (xy 8.763 3.2639) (xy 8.763 4.5466)
			)
			(stroke
				(width 0)
				(type default)
			)
			(fill no)
			(layer "F.CrtYd")
		)
		(fp_poly
			(pts
				(xy 1.397 4.5466) (xy 1.397 3.2639) (xy -23.6728 3.2639) (xy -23.6728 -3.5052) (xy 23.6728 -3.5052)
				(xy 23.6728 3.2639) (xy 8.763 3.2639) (xy 8.763 4.5466)
			)
			(stroke
				(width 0)
				(type default)
			)
			(fill no)
			(layer "F.Fab")
		)
		(pad "" np_thru_hole circle
			(at -18.874994 0 270)
			(size 0.254 0.254)
			(drill 1.3462)
			(layers "*.Cu" "*.Mask")
			(clearance 0.9017)
			(thermal_gap 0.9017)
		)
		(pad "" np_thru_hole circle
			(at 18.874994 0 270)
			(size 0.254 0.254)
			(drill 0.9398)
			(layers "*.Cu" "*.Mask")
			(clearance 0.6985)
			(thermal_gap 0.6985)
		)
		(pad "G1" smd rect
			(at 21.874988 0 270)
			(size 2.5908 2.5908)
			(layers "F.Cu" "F.Mask" "F.Paste")
			(net "GND")
		)
		(pad "G2" smd rect
			(at -21.874988 0 270)
			(size 2.5908 2.5908)
			(layers "F.Cu" "F.Mask" "F.Paste")
			(net "GND")
		)
		(pad "P1" smd rect
			(at 1.905 -1.82499 270)
			(size 0.6096 2.3622)
			(layers "F.Cu" "F.Mask" "F.Paste")
			(net "Net_1649")
		)
		(pad "P2" smd rect
			(at 0.635 -1.82499 270)
			(size 0.6096 2.3622)
			(layers "F.Cu" "F.Mask" "F.Paste")
			(net "Net_1650")
		)
		(pad "P3" smd rect
			(at -0.635 -1.82499 270)
			(size 0.6096 2.3622)
			(layers "F.Cu" "F.Mask" "F.Paste")
			(net "Net_1651")
		)
		(pad "P4" smd rect
			(at -1.905 -1.82499 270)
			(size 0.6096 2.3622)
			(layers "F.Cu" "F.Mask" "F.Paste")
			(net "GND")
		)
		(pad "P5" smd rect
			(at -3.175 -1.82499 270)
			(size 0.6096 2.3622)
			(layers "F.Cu" "F.Mask" "F.Paste")
			(net "HDD_PRSNT_29")
		)
		(pad "P6" smd rect
			(at -4.445 -1.82499 270)
			(size 0.6096 2.3622)
			(layers "F.Cu" "F.Mask" "F.Paste")
			(net "GND")
		)
		(pad "P7" smd rect
			(at -5.715 -1.82499 270)
			(size 0.6096 2.3622)
			(layers "F.Cu" "F.Mask" "F.Paste")
			(net "5V_PRE_29")
		)
		(pad "P8" smd rect
			(at -6.985 -1.82499 270)
			(size 0.6096 2.3622)
			(layers "F.Cu" "F.Mask" "F.Paste")
			(net "P5V_HDD29")
		)
		(pad "P9" smd rect
			(at -8.255 -1.82499 270)
			(size 0.6096 2.3622)
			(layers "F.Cu" "F.Mask" "F.Paste")
			(net "P5V_HDD29")
		)
		(pad "P10" smd rect
			(at -9.525 -1.82499 270)
			(size 0.6096 2.3622)
			(layers "F.Cu" "F.Mask" "F.Paste")
			(net "GND")
		)
		(pad "P11" smd rect
			(at -10.795 -1.82499 270)
			(size 0.6096 2.3622)
			(layers "F.Cu" "F.Mask" "F.Paste")
			(net "ACT_HDD_29")
		)
		(pad "P12" smd rect
			(at -12.065 -1.82499 270)
			(size 0.6096 2.3622)
			(layers "F.Cu" "F.Mask" "F.Paste")
			(net "GND")
		)
		(pad "P13" smd rect
			(at -13.335 -1.82499 270)
			(size 0.6096 2.3622)
			(layers "F.Cu" "F.Mask" "F.Paste")
			(net "12V_PRE_29")
		)
		(pad "P14" smd rect
			(at -14.605 -1.82499 270)
			(size 0.6096 2.3622)
			(layers "F.Cu" "F.Mask" "F.Paste")
			(net "P12V_HDD29")
		)
		(pad "P15" smd rect
			(at -15.875 -1.82499 270)
			(size 0.6096 2.3622)
			(layers "F.Cu" "F.Mask" "F.Paste")
			(net "P12V_HDD29")
		)
		(pad "S1" smd rect
			(at 15.875 -1.82499 270)
			(size 0.6096 2.3622)
			(layers "F.Cu" "F.Mask" "F.Paste")
			(net "GND")
		)
		(pad "S2" smd rect
			(at 14.605 -1.82499 270)
			(size 0.6096 2.3622)
			(layers "F.Cu" "F.Mask" "F.Paste")
			(net "SAS_HDD_RX_P29")
		)
		(pad "S3" smd rect
			(at 13.335 -1.82499 270)
			(size 0.6096 2.3622)
			(layers "F.Cu" "F.Mask" "F.Paste")
			(net "SAS_HDD_RX_N29")
		)
		(pad "S4" smd rect
			(at 12.065 -1.82499 270)
			(size 0.6096 2.3622)
			(layers "F.Cu" "F.Mask" "F.Paste")
			(net "GND")
		)
		(pad "S5" smd rect
			(at 10.795 -1.82499 270)
			(size 0.6096 2.3622)
			(layers "F.Cu" "F.Mask" "F.Paste")
			(net "PHY_DRV_B_TO_SCC_B_29_DN")
		)
		(pad "S6" smd rect
			(at 9.525 -1.82499 270)
			(size 0.6096 2.3622)
			(layers "F.Cu" "F.Mask" "F.Paste")
			(net "PHY_DRV_B_TO_SCC_B_29_DP")
		)
		(pad "S7" smd rect
			(at 8.255 -1.82499 270)
			(size 0.6096 2.3622)
			(layers "F.Cu" "F.Mask" "F.Paste")
			(net "GND")
		)
		(pad "S8" smd rect
			(at 7.480046 2.845054 270)
			(size 0.508 2.3622)
			(layers "F.Cu" "F.Mask" "F.Paste")
			(net "GND")
		)
		(pad "S9" smd rect
			(at 6.679946 2.845054 270)
			(size 0.508 2.3622)
			(layers "F.Cu" "F.Mask" "F.Paste")
			(net "Net_454")
		)
		(pad "S10" smd rect
			(at 5.8801 2.845054 270)
			(size 0.508 2.3622)
			(layers "F.Cu" "F.Mask" "F.Paste")
			(net "Net_346")
		)
		(pad "S11" smd rect
			(at 5.08 2.845054 270)
			(size 0.508 2.3622)
			(layers "F.Cu" "F.Mask" "F.Paste")
			(net "GND")
		)
		(pad "S12" smd rect
			(at 4.2799 2.845054 270)
			(size 0.508 2.3622)
			(layers "F.Cu" "F.Mask" "F.Paste")
			(net "Net_382")
		)
		(pad "S13" smd rect
			(at 3.480054 2.845054 270)
			(size 0.508 2.3622)
			(layers "F.Cu" "F.Mask" "F.Paste")
			(net "Net_418")
		)
		(pad "S14" smd rect
			(at 2.679954 2.845054 270)
			(size 0.508 2.3622)
			(layers "F.Cu" "F.Mask" "F.Paste")
			(net "GND")
		)
		(zone
			(layer "F.Cu")
			(hatch none 0.5)
			(connect_pads
				(clearance 0)
			)
			(min_thickness 0.25)
			(keepout
				(tracks allowed)
				(vias not_allowed)
				(pads allowed)
				(copperpour not_allowed)
				(footprints allowed)
			)
			(placement
				(enabled no)
				(sheetname "")
			)
			(fill
				(thermal_gap 0.5)
				(thermal_bridge_width 0.5)
				(island_removal_mode 0)
			)
			(polygon
				(pts
					(xy 189.607698 -45.648626) (xy 182.533798 -45.648626) (xy 182.533798 -52.582826) (xy 183.638698 -52.582826)
					(xy 183.638698 -48.468026) (xy 188.261498 -48.468026) (xy 188.261498 -52.582826) (xy 189.607698 -52.582826)
				)
			)
		)
		(zone
			(layer "F.Cu")
			(hatch none 0.5)
			(connect_pads
				(clearance 0)
			)
			(min_thickness 0.25)
			(keepout
				(tracks not_allowed)
				(vias allowed)
				(pads allowed)
				(copperpour not_allowed)
				(footprints allowed)
			)
			(placement
				(enabled no)
				(sheetname "")
			)
			(fill
				(thermal_gap 0.5)
				(thermal_bridge_width 0.5)
				(island_removal_mode 0)
			)
			(polygon
				(pts
					(xy 189.607698 -45.648626) (xy 182.533798 -45.648626) (xy 182.533798 -52.582826) (xy 183.638698 -52.582826)
					(xy 183.638698 -48.468026) (xy 188.261498 -48.468026) (xy 188.261498 -52.582826) (xy 189.607698 -52.582826)
				)
			)
		)
		(zone
			(layer "F.Cu")
			(hatch none 0.5)
			(connect_pads
				(clearance 0)
			)
			(min_thickness 0.25)
			(keepout
				(tracks not_allowed)
				(vias allowed)
				(pads allowed)
				(copperpour not_allowed)
				(footprints allowed)
			)
			(placement
				(enabled no)
				(sheetname "")
			)
			(fill
				(thermal_gap 0.5)
				(thermal_bridge_width 0.5)
				(island_removal_mode 0)
			)
			(polygon
				(pts
					(xy 189.607698 -12.171426) (xy 182.533798 -12.171426) (xy 182.533798 -5.237226) (xy 183.638698 -5.237226)
					(xy 183.638698 -9.352026) (xy 188.261498 -9.352026) (xy 188.261498 -5.237226) (xy 189.607698 -5.237226)
				)
			)
		)
		(zone
			(layer "F.Cu")
			(hatch none 0.5)
			(connect_pads
				(clearance 0)
			)
			(min_thickness 0.25)
			(keepout
				(tracks allowed)
				(vias not_allowed)
				(pads allowed)
				(copperpour not_allowed)
				(footprints allowed)
			)
			(placement
				(enabled no)
				(sheetname "")
			)
			(fill
				(thermal_gap 0.5)
				(thermal_bridge_width 0.5)
				(island_removal_mode 0)
			)
			(polygon
				(pts
					(xy 189.607698 -12.171426) (xy 182.533798 -12.171426) (xy 182.533798 -5.237226) (xy 183.638698 -5.237226)
					(xy 183.638698 -9.352026) (xy 188.261498 -9.352026) (xy 188.261498 -5.237226) (xy 189.607698 -5.237226)
				)
			)
		)
		(zone
			(layers "F.Cu" "B.Cu" "In1.Cu" "In2.Cu" "In3.Cu" "In4.Cu" "In5.Cu" "In6.Cu")
			(hatch none 0.5)
			(connect_pads
				(clearance 0)
			)
			(min_thickness 0.25)
			(keepout
				(tracks not_allowed)
				(vias allowed)
				(pads allowed)
				(copperpour not_allowed)
				(footprints allowed)
			)
			(placement
				(enabled no)
				(sheetname "")
			)
			(fill
				(thermal_gap 0.5)
				(thermal_bridge_width 0.5)
				(island_removal_mode 0)
			)
			(polygon
				(pts
					(arc
						(start 186.724798 -10.035032)
						(mid 185.175398 -10.035032)
						(end 186.724798 -10.035032)
					)
				)
			)
		)
		(zone
			(layers "F.Cu" "B.Cu" "In1.Cu" "In2.Cu" "In3.Cu" "In4.Cu" "In5.Cu" "In6.Cu")
			(hatch none 0.5)
			(connect_pads
				(clearance 0)
			)
			(min_thickness 0.25)
			(keepout
				(tracks not_allowed)
				(vias allowed)
				(pads allowed)
				(copperpour not_allowed)
				(footprints allowed)
			)
			(placement
				(enabled no)
				(sheetname "")
			)
			(fill
				(thermal_gap 0.5)
				(thermal_bridge_width 0.5)
				(island_removal_mode 0)
			)
			(polygon
				(pts
					(arc
						(start 186.927998 -47.78502)
						(mid 184.972198 -47.78502)
						(end 186.927998 -47.78502)
					)
				)
			)
		)
	)
	(footprint ""
		(layer "F.Cu")
		(at 149.987 -148.209)
		(property "Reference" "R437"
			(at 0 0 0)
			(layer "F.SilkS")
			(hide yes)
			(effects
				(font
					(size 1.27 1.27)
				)
			)
		)
		(property "Value" "2R6F-GP"
			(at -0.0508 -4.8514 0)
			(unlocked yes)
			(layer "F.Fab")
			(hide yes)
			(effects
				(font
					(size 1.016 1.016)
					(thickness 0.1524)
				)
			)
		)
		(property "Device Type" "R1206H26"
			(at 0 -6.3754 0)
			(unlocked yes)
			(layer "F.Fab")
			(hide yes)
			(effects
				(font
					(size 1.016 1.016)
					(thickness 0.1524)
				)
			)
		)
		(duplicate_pad_numbers_are_jumpers no)
		(fp_line
			(start -1.016 -2.2352)
			(end 1.016 -2.2352)
			(stroke
				(width 0.1524)
				(type default)
			)
			(layer "F.SilkS")
		)
		(fp_line
			(start -1.016 2.2352)
			(end -1.016 -2.2352)
			(stroke
				(width 0.1524)
				(type default)
			)
			(layer "F.SilkS")
		)
		(fp_line
			(start 1.016 -2.2352)
			(end 1.016 2.2352)
			(stroke
				(width 0.1524)
				(type default)
			)
			(layer "F.SilkS")
		)
		(fp_line
			(start 1.016 2.2352)
			(end -1.016 2.2352)
			(stroke
				(width 0.1524)
				(type default)
			)
			(layer "F.SilkS")
		)
		(fp_rect
			(start -1.0922 2.3114)
			(end 1.0922 -2.3114)
			(stroke
				(width 0)
				(type default)
			)
			(fill no)
			(layer "F.CrtYd")
		)
		(fp_poly
			(pts
				(xy -1.0922 -2.3114) (xy 1.0922 -2.3114) (xy 1.0922 2.3114) (xy -1.0922 2.3114)
			)
			(stroke
				(width 0)
				(type default)
			)
			(fill no)
			(layer "F.Fab")
		)
		(pad "1" smd rect
			(at 0 -1.397)
			(size 1.651 1.27)
			(layers "F.Cu" "F.Mask" "F.Paste")
			(net "P5V_HDD16")
		)
		(pad "2" smd rect
			(at 0 1.397)
			(size 1.651 1.27)
			(layers "F.Cu" "F.Mask" "F.Paste")
			(net "5V_PRE_16")
		)
	)
	(footprint ""
		(layer "F.Cu")
		(at 479.298 -160.401 180)
		(property "Reference" "C336"
			(at 0 0 180)
			(layer "F.SilkS")
			(hide yes)
			(effects
				(font
					(size 1.27 1.27)
				)
			)
		)
		(property "Value" "SC1U25V3KX-GP"
			(at 0 -2.8194 180)
			(unlocked yes)
			(layer "F.Fab")
			(hide yes)
			(effects
				(font
					(size 1.016 1.016)
					(thickness 0.1524)
				)
			)
		)
		(property "Device Type" "C603H36"
			(at 0 -4.3434 180)
			(unlocked yes)
			(layer "F.Fab")
			(hide yes)
			(effects
				(font
					(size 1.016 1.016)
					(thickness 0.1524)
				)
			)
		)
		(duplicate_pad_numbers_are_jumpers no)
		(fp_line
			(start 0.508 0)
			(end -0.508 0)
			(stroke
				(width 0.2032)
				(type default)
			)
			(layer "F.SilkS")
		)
		(fp_rect
			(start -0.5842 1.3335)
			(end 0.5842 -1.3335)
			(stroke
				(width 0)
				(type default)
			)
			(fill no)
			(layer "F.CrtYd")
		)
		(fp_rect
			(start -0.5842 1.3335)
			(end 0.5842 -1.3335)
			(stroke
				(width 0)
				(type default)
			)
			(fill no)
			(layer "F.Fab")
		)
		(pad "1" smd custom
			(at 0 -0.762 180)
			(size 0.2159 0.2159)
			(layers "F.Cu" "F.Mask" "F.Paste")
			(net "P12V_HDD23")
			(options
				(clearance outline)
				(anchor circle)
			)
			(primitives
				(gr_poly
					(pts
						(arc
							(start -0.3302 -0.4318)
							(mid -0.402042 -0.402042)
							(end -0.4318 -0.3302)
						)
						(arc
							(start -0.4318 0.3302)
							(mid -0.402042 0.402042)
							(end -0.3302 0.4318)
						)
						(arc
							(start 0.3302 0.4318)
							(mid 0.402042 0.402042)
							(end 0.4318 0.3302)
						)
						(arc
							(start 0.4318 -0.3302)
							(mid 0.402042 -0.402042)
							(end 0.3302 -0.4318)
						)
					)
					(width 0)
					(fill yes)
				)
			)
		)
		(pad "2" smd custom
			(at 0 0.762 180)
			(size 0.2159 0.2159)
			(layers "F.Cu" "F.Mask" "F.Paste")
			(net "GND")
			(options
				(clearance outline)
				(anchor circle)
			)
			(primitives
				(gr_poly
					(pts
						(arc
							(start -0.3302 -0.4318)
							(mid -0.402042 -0.402042)
							(end -0.4318 -0.3302)
						)
						(arc
							(start -0.4318 0.3302)
							(mid -0.402042 0.402042)
							(end -0.3302 0.4318)
						)
						(arc
							(start 0.3302 0.4318)
							(mid 0.402042 0.402042)
							(end 0.4318 0.3302)
						)
						(arc
							(start 0.4318 -0.3302)
							(mid 0.402042 -0.402042)
							(end 0.3302 -0.4318)
						)
					)
					(width 0)
					(fill yes)
				)
			)
		)
	)
	(footprint ""
		(layer "F.Cu")
		(at 96.393 -31.6484 180)
		(property "Reference" "R668"
			(at 0 0 180)
			(layer "F.SilkS")
			(hide yes)
			(effects
				(font
					(size 1.27 1.27)
				)
			)
		)
		(property "Value" "10KR2F-2-GP"
			(at 0.064008 -3.993896 180)
			(unlocked yes)
			(layer "F.Fab")
			(hide yes)
			(effects
				(font
					(size 1.016 1.016)
					(thickness 0.1524)
				)
			)
		)
		(property "Device Type" "R402H16"
			(at 0.064008 -5.517896 180)
			(unlocked yes)
			(layer "F.Fab")
			(hide yes)
			(effects
				(font
					(size 1.016 1.016)
					(thickness 0.1524)
				)
			)
		)
		(duplicate_pad_numbers_are_jumpers no)
		(fp_line
			(start 0.508 -0.9398)
			(end -0.508 -0.9398)
			(stroke
				(width 0.1524)
				(type default)
			)
			(layer "F.SilkS")
		)
		(fp_line
			(start -0.508 -0.9398)
			(end -0.508 0.9398)
			(stroke
				(width 0.1524)
				(type default)
			)
			(layer "F.SilkS")
		)
		(fp_rect
			(start -0.508 0.9398)
			(end 0.508 -0.9398)
			(stroke
				(width 0)
				(type default)
			)
			(fill no)
			(layer "F.CrtYd")
		)
		(fp_rect
			(start -0.508 0.9398)
			(end 0.508 -0.9398)
			(stroke
				(width 0)
				(type default)
			)
			(fill no)
			(layer "F.Fab")
		)
		(pad "1" smd custom
			(at 0 -0.4445 180)
			(size 0.1397 0.1397)
			(layers "F.Cu" "F.Mask" "F.Paste")
			(net "P3V3_STBY_B")
			(options
				(clearance outline)
				(anchor circle)
			)
			(primitives
				(gr_poly
					(pts
						(arc
							(start -0.1778 -0.2794)
							(mid -0.249642 -0.249642)
							(end -0.2794 -0.1778)
						)
						(arc
							(start -0.2794 0.1778)
							(mid -0.249642 0.249642)
							(end -0.1778 0.2794)
						)
						(arc
							(start 0.1778 0.2794)
							(mid 0.249642 0.249642)
							(end 0.2794 0.1778)
						)
						(arc
							(start 0.2794 -0.1778)
							(mid 0.249642 -0.249642)
							(end 0.1778 -0.2794)
						)
					)
					(width 0)
					(fill yes)
				)
			)
		)
		(pad "2" smd custom
			(at 0 0.4445 180)
			(size 0.1397 0.1397)
			(layers "F.Cu" "F.Mask" "F.Paste")
			(net "HDD_PRSNT_26")
			(options
				(clearance outline)
				(anchor circle)
			)
			(primitives
				(gr_poly
					(pts
						(arc
							(start -0.1778 -0.2794)
							(mid -0.249642 -0.249642)
							(end -0.2794 -0.1778)
						)
						(arc
							(start -0.2794 0.1778)
							(mid -0.249642 0.249642)
							(end -0.1778 0.2794)
						)
						(arc
							(start 0.1778 0.2794)
							(mid 0.249642 0.249642)
							(end 0.2794 0.1778)
						)
						(arc
							(start 0.2794 -0.1778)
							(mid 0.249642 -0.249642)
							(end 0.1778 -0.2794)
						)
					)
					(width 0)
					(fill yes)
				)
			)
		)
	)
	(footprint ""
		(layer "F.Cu")
		(at 477.4692 -250.571)
		(property "Reference" "C176"
			(at 0 0 0)
			(layer "F.SilkS")
			(hide yes)
			(effects
				(font
					(size 1.27 1.27)
				)
			)
		)
		(property "Value" "SCD01U50V2KX-1GP"
			(at 1.1811 -2.7051 0)
			(unlocked yes)
			(layer "F.Fab")
			(hide yes)
			(effects
				(font
					(size 1.016 1.016)
					(thickness 0.1524)
				)
			)
		)
		(property "Device Type" "C402H22"
			(at 1.1811 -4.2291 0)
			(unlocked yes)
			(layer "F.Fab")
			(hide yes)
			(effects
				(font
					(size 1.016 1.016)
					(thickness 0.1524)
				)
			)
		)
		(duplicate_pad_numbers_are_jumpers no)
		(fp_rect
			(start -0.4318 0.9525)
			(end 0.4318 -0.9525)
			(stroke
				(width 0)
				(type default)
			)
			(fill no)
			(layer "F.CrtYd")
		)
		(fp_rect
			(start -0.4318 0.9525)
			(end 0.4318 -0.9525)
			(stroke
				(width 0)
				(type default)
			)
			(fill no)
			(layer "F.Fab")
		)
		(pad "1" smd custom
			(at 0 -0.4445)
			(size 0.1524 0.1524)
			(layers "F.Cu" "F.Mask" "F.Paste")
			(net "HDD_PRSNT_11")
			(options
				(clearance outline)
				(anchor circle)
			)
			(primitives
				(gr_poly
					(pts
						(arc
							(start 0.3048 -0.2032)
							(mid 0.275042 -0.275042)
							(end 0.2032 -0.3048)
						)
						(arc
							(start -0.2032 -0.3048)
							(mid -0.275042 -0.275042)
							(end -0.3048 -0.2032)
						)
						(arc
							(start -0.3048 0.2032)
							(mid -0.275042 0.275042)
							(end -0.2032 0.3048)
						)
						(arc
							(start 0.2032 0.3048)
							(mid 0.275042 0.275042)
							(end 0.3048 0.2032)
						)
					)
					(width 0)
					(fill yes)
				)
			)
		)
		(pad "2" smd custom
			(at 0 0.4445)
			(size 0.1524 0.1524)
			(layers "F.Cu" "F.Mask" "F.Paste")
			(net "GND")
			(options
				(clearance outline)
				(anchor circle)
			)
			(primitives
				(gr_poly
					(pts
						(arc
							(start 0.3048 -0.2032)
							(mid 0.275042 -0.275042)
							(end 0.2032 -0.3048)
						)
						(arc
							(start -0.2032 -0.3048)
							(mid -0.275042 -0.275042)
							(end -0.3048 -0.2032)
						)
						(arc
							(start -0.3048 0.2032)
							(mid -0.275042 0.275042)
							(end -0.2032 0.3048)
						)
						(arc
							(start 0.2032 0.3048)
							(mid 0.275042 0.275042)
							(end 0.3048 0.2032)
						)
					)
					(width 0)
					(fill yes)
				)
			)
		)
	)
	(footprint ""
		(layer "F.Cu")
		(at 28.200096 -143.91005 -90)
		(property "Reference" "HDDSAS12"
			(at 0 0 270)
			(layer "F.SilkS")
			(hide yes)
			(effects
				(font
					(size 1.27 1.27)
				)
			)
		)
		(property "Value" "SKT-SAS15P-14P-45-GP"
			(at -20.7645 -8.9789 270)
			(unlocked yes)
			(layer "F.Fab")
			(hide yes)
			(effects
				(font
					(size 1.016 1.016)
					(thickness 0.1524)
				)
			)
		)
		(property "Device Type" "10120818-001C-TRLF"
			(at -20.7645 -10.5029 270)
			(unlocked yes)
			(layer "F.Fab")
			(hide yes)
			(effects
				(font
					(size 1.016 1.016)
					(thickness 0.1524)
				)
			)
		)
		(duplicate_pad_numbers_are_jumpers no)
		(fp_line
			(start 1.651 4.2926)
			(end 1.651 3.0099)
			(stroke
				(width 0.1524)
				(type default)
			)
			(layer "F.SilkS")
		)
		(fp_line
			(start 8.509 4.2926)
			(end 1.651 4.2926)
			(stroke
				(width 0.1524)
				(type default)
			)
			(layer "F.SilkS")
		)
		(fp_line
			(start -23.4188 3.0099)
			(end -23.4188 -3.2512)
			(stroke
				(width 0.1524)
				(type default)
			)
			(layer "F.SilkS")
		)
		(fp_line
			(start 1.651 3.0099)
			(end -23.4188 3.0099)
			(stroke
				(width 0.1524)
				(type default)
			)
			(layer "F.SilkS")
		)
		(fp_line
			(start 8.509 3.0099)
			(end 8.509 4.2926)
			(stroke
				(width 0.1524)
				(type default)
			)
			(layer "F.SilkS")
		)
		(fp_line
			(start 23.4188 3.0099)
			(end 8.509 3.0099)
			(stroke
				(width 0.1524)
				(type default)
			)
			(layer "F.SilkS")
		)
		(fp_line
			(start -23.4188 -3.2512)
			(end 23.4188 -3.2512)
			(stroke
				(width 0.1524)
				(type default)
			)
			(layer "F.SilkS")
		)
		(fp_line
			(start 23.4188 -3.2512)
			(end 23.4188 3.0099)
			(stroke
				(width 0.1524)
				(type default)
			)
			(layer "F.SilkS")
		)
		(fp_line
			(start 15.5067 -3.3401)
			(end 16.2687 -3.3401)
			(stroke
				(width 0.3302)
				(type default)
			)
			(layer "F.SilkS")
		)
		(fp_poly
			(pts
				(xy 15.868904 -3.230372) (xy 16.503904 -3.865372) (xy 15.233904 -3.865372)
			)
			(stroke
				(width 0)
				(type default)
			)
			(fill yes)
			(layer "F.SilkS")
		)
		(fp_poly
			(pts
				(xy -22.8727 -2.7559) (xy 22.8727 -2.7559) (xy 22.8727 2.7559) (xy 8.255 2.7559) (xy 8.255 3.5179)
				(xy 1.905 3.5179) (xy 1.905 2.7559) (xy -22.8727 2.7559)
			)
			(stroke
				(width 0)
				(type default)
			)
			(fill no)
			(layer "F.CrtYd")
		)
		(fp_poly
			(pts
				(xy 1.397 4.5466) (xy 1.397 3.2639) (xy -23.6728 3.2639) (xy -23.6728 -3.5052) (xy 23.6728 -3.5052)
				(xy 23.6728 -0.00635) (xy 22.8727 -0.00635) (xy 22.8727 -2.7559) (xy -22.8727 -2.7559) (xy -22.8727 2.7559)
				(xy 1.905 2.7559) (xy 1.905 3.5179) (xy 8.255 3.5179) (xy 8.255 2.7559) (xy 22.8727 2.7559) (xy 22.8727 0.00635)
				(xy 23.6728 0.00635) (xy 23.6728 3.2639) (xy 8.763 3.2639) (xy 8.763 4.5466)
			)
			(stroke
				(width 0)
				(type default)
			)
			(fill no)
			(layer "F.CrtYd")
		)
		(fp_poly
			(pts
				(xy 1.397 4.5466) (xy 1.397 3.2639) (xy -23.6728 3.2639) (xy -23.6728 -3.5052) (xy 23.6728 -3.5052)
				(xy 23.6728 3.2639) (xy 8.763 3.2639) (xy 8.763 4.5466)
			)
			(stroke
				(width 0)
				(type default)
			)
			(fill no)
			(layer "F.Fab")
		)
		(pad "" np_thru_hole circle
			(at -18.874994 0 270)
			(size 0.254 0.254)
			(drill 1.3462)
			(layers "*.Cu" "*.Mask")
			(clearance 0.9017)
			(thermal_gap 0.9017)
		)
		(pad "" np_thru_hole circle
			(at 18.874994 0 270)
			(size 0.254 0.254)
			(drill 0.9398)
			(layers "*.Cu" "*.Mask")
			(clearance 0.6985)
			(thermal_gap 0.6985)
		)
		(pad "G1" smd rect
			(at 21.874988 0 270)
			(size 2.5908 2.5908)
			(layers "F.Cu" "F.Mask" "F.Paste")
			(net "GND")
		)
		(pad "G2" smd rect
			(at -21.874988 0 270)
			(size 2.5908 2.5908)
			(layers "F.Cu" "F.Mask" "F.Paste")
			(net "GND")
		)
		(pad "P1" smd rect
			(at 1.905 -1.82499 270)
			(size 0.6096 2.3622)
			(layers "F.Cu" "F.Mask" "F.Paste")
			(net "Net_1744")
		)
		(pad "P2" smd rect
			(at 0.635 -1.82499 270)
			(size 0.6096 2.3622)
			(layers "F.Cu" "F.Mask" "F.Paste")
			(net "Net_1745")
		)
		(pad "P3" smd rect
			(at -0.635 -1.82499 270)
			(size 0.6096 2.3622)
			(layers "F.Cu" "F.Mask" "F.Paste")
			(net "Net_1746")
		)
		(pad "P4" smd rect
			(at -1.905 -1.82499 270)
			(size 0.6096 2.3622)
			(layers "F.Cu" "F.Mask" "F.Paste")
			(net "GND")
		)
		(pad "P5" smd rect
			(at -3.175 -1.82499 270)
			(size 0.6096 2.3622)
			(layers "F.Cu" "F.Mask" "F.Paste")
			(net "HDD_PRSNT_12")
		)
		(pad "P6" smd rect
			(at -4.445 -1.82499 270)
			(size 0.6096 2.3622)
			(layers "F.Cu" "F.Mask" "F.Paste")
			(net "GND")
		)
		(pad "P7" smd rect
			(at -5.715 -1.82499 270)
			(size 0.6096 2.3622)
			(layers "F.Cu" "F.Mask" "F.Paste")
			(net "5V_PRE_12")
		)
		(pad "P8" smd rect
			(at -6.985 -1.82499 270)
			(size 0.6096 2.3622)
			(layers "F.Cu" "F.Mask" "F.Paste")
			(net "P5V_HDD12")
		)
		(pad "P9" smd rect
			(at -8.255 -1.82499 270)
			(size 0.6096 2.3622)
			(layers "F.Cu" "F.Mask" "F.Paste")
			(net "P5V_HDD12")
		)
		(pad "P10" smd rect
			(at -9.525 -1.82499 270)
			(size 0.6096 2.3622)
			(layers "F.Cu" "F.Mask" "F.Paste")
			(net "GND")
		)
		(pad "P11" smd rect
			(at -10.795 -1.82499 270)
			(size 0.6096 2.3622)
			(layers "F.Cu" "F.Mask" "F.Paste")
			(net "ACT_HDD_12")
		)
		(pad "P12" smd rect
			(at -12.065 -1.82499 270)
			(size 0.6096 2.3622)
			(layers "F.Cu" "F.Mask" "F.Paste")
			(net "GND")
		)
		(pad "P13" smd rect
			(at -13.335 -1.82499 270)
			(size 0.6096 2.3622)
			(layers "F.Cu" "F.Mask" "F.Paste")
			(net "12V_PRE_12")
		)
		(pad "P14" smd rect
			(at -14.605 -1.82499 270)
			(size 0.6096 2.3622)
			(layers "F.Cu" "F.Mask" "F.Paste")
			(net "P12V_HDD12")
		)
		(pad "P15" smd rect
			(at -15.875 -1.82499 270)
			(size 0.6096 2.3622)
			(layers "F.Cu" "F.Mask" "F.Paste")
			(net "P12V_HDD12")
		)
		(pad "S1" smd rect
			(at 15.875 -1.82499 270)
			(size 0.6096 2.3622)
			(layers "F.Cu" "F.Mask" "F.Paste")
			(net "GND")
		)
		(pad "S2" smd rect
			(at 14.605 -1.82499 270)
			(size 0.6096 2.3622)
			(layers "F.Cu" "F.Mask" "F.Paste")
			(net "SAS_HDD_RX_P12")
		)
		(pad "S3" smd rect
			(at 13.335 -1.82499 270)
			(size 0.6096 2.3622)
			(layers "F.Cu" "F.Mask" "F.Paste")
			(net "SAS_HDD_RX_N12")
		)
		(pad "S4" smd rect
			(at 12.065 -1.82499 270)
			(size 0.6096 2.3622)
			(layers "F.Cu" "F.Mask" "F.Paste")
			(net "GND")
		)
		(pad "S5" smd rect
			(at 10.795 -1.82499 270)
			(size 0.6096 2.3622)
			(layers "F.Cu" "F.Mask" "F.Paste")
			(net "PHY_DRV_B_TO_SCC_B_12_DN")
		)
		(pad "S6" smd rect
			(at 9.525 -1.82499 270)
			(size 0.6096 2.3622)
			(layers "F.Cu" "F.Mask" "F.Paste")
			(net "PHY_DRV_B_TO_SCC_B_12_DP")
		)
		(pad "S7" smd rect
			(at 8.255 -1.82499 270)
			(size 0.6096 2.3622)
			(layers "F.Cu" "F.Mask" "F.Paste")
			(net "GND")
		)
		(pad "S8" smd rect
			(at 7.480046 2.845054 270)
			(size 0.508 2.3622)
			(layers "F.Cu" "F.Mask" "F.Paste")
			(net "GND")
		)
		(pad "S9" smd rect
			(at 6.679946 2.845054 270)
			(size 0.508 2.3622)
			(layers "F.Cu" "F.Mask" "F.Paste")
			(net "Net_435")
		)
		(pad "S10" smd rect
			(at 5.8801 2.845054 270)
			(size 0.508 2.3622)
			(layers "F.Cu" "F.Mask" "F.Paste")
			(net "Net_327")
		)
		(pad "S11" smd rect
			(at 5.08 2.845054 270)
			(size 0.508 2.3622)
			(layers "F.Cu" "F.Mask" "F.Paste")
			(net "GND")
		)
		(pad "S12" smd rect
			(at 4.2799 2.845054 270)
			(size 0.508 2.3622)
			(layers "F.Cu" "F.Mask" "F.Paste")
			(net "Net_363")
		)
		(pad "S13" smd rect
			(at 3.480054 2.845054 270)
			(size 0.508 2.3622)
			(layers "F.Cu" "F.Mask" "F.Paste")
			(net "Net_399")
		)
		(pad "S14" smd rect
			(at 2.679954 2.845054 270)
			(size 0.508 2.3622)
			(layers "F.Cu" "F.Mask" "F.Paste")
			(net "GND")
		)
		(zone
			(layer "F.Cu")
			(hatch none 0.5)
			(connect_pads
				(clearance 0)
			)
			(min_thickness 0.25)
			(keepout
				(tracks not_allowed)
				(vias allowed)
				(pads allowed)
				(copperpour not_allowed)
				(footprints allowed)
			)
			(placement
				(enabled no)
				(sheetname "")
			)
			(fill
				(thermal_gap 0.5)
				(thermal_bridge_width 0.5)
				(island_removal_mode 0)
			)
			(polygon
				(pts
					(xy 31.857696 -160.64865) (xy 24.783796 -160.64865) (xy 24.783796 -167.58285) (xy 25.888696 -167.58285)
					(xy 25.888696 -163.46805) (xy 30.511496 -163.46805) (xy 30.511496 -167.58285) (xy 31.857696 -167.58285)
				)
			)
		)
		(zone
			(layer "F.Cu")
			(hatch none 0.5)
			(connect_pads
				(clearance 0)
			)
			(min_thickness 0.25)
			(keepout
				(tracks allowed)
				(vias not_allowed)
				(pads allowed)
				(copperpour not_allowed)
				(footprints allowed)
			)
			(placement
				(enabled no)
				(sheetname "")
			)
			(fill
				(thermal_gap 0.5)
				(thermal_bridge_width 0.5)
				(island_removal_mode 0)
			)
			(polygon
				(pts
					(xy 31.857696 -160.64865) (xy 24.783796 -160.64865) (xy 24.783796 -167.58285) (xy 25.888696 -167.58285)
					(xy 25.888696 -163.46805) (xy 30.511496 -163.46805) (xy 30.511496 -167.58285) (xy 31.857696 -167.58285)
				)
			)
		)
		(zone
			(layer "F.Cu")
			(hatch none 0.5)
			(connect_pads
				(clearance 0)
			)
			(min_thickness 0.25)
			(keepout
				(tracks allowed)
				(vias not_allowed)
				(pads allowed)
				(copperpour not_allowed)
				(footprints allowed)
			)
			(placement
				(enabled no)
				(sheetname "")
			)
			(fill
				(thermal_gap 0.5)
				(thermal_bridge_width 0.5)
				(island_removal_mode 0)
			)
			(polygon
				(pts
					(xy 31.857696 -127.17145) (xy 24.783796 -127.17145) (xy 24.783796 -120.23725) (xy 25.888696 -120.23725)
					(xy 25.888696 -124.35205) (xy 30.511496 -124.35205) (xy 30.511496 -120.23725) (xy 31.857696 -120.23725)
				)
			)
		)
		(zone
			(layer "F.Cu")
			(hatch none 0.5)
			(connect_pads
				(clearance 0)
			)
			(min_thickness 0.25)
			(keepout
				(tracks not_allowed)
				(vias allowed)
				(pads allowed)
				(copperpour not_allowed)
				(footprints allowed)
			)
			(placement
				(enabled no)
				(sheetname "")
			)
			(fill
				(thermal_gap 0.5)
				(thermal_bridge_width 0.5)
				(island_removal_mode 0)
			)
			(polygon
				(pts
					(xy 31.857696 -127.17145) (xy 24.783796 -127.17145) (xy 24.783796 -120.23725) (xy 25.888696 -120.23725)
					(xy 25.888696 -124.35205) (xy 30.511496 -124.35205) (xy 30.511496 -120.23725) (xy 31.857696 -120.23725)
				)
			)
		)
		(zone
			(layers "F.Cu" "B.Cu" "In1.Cu" "In2.Cu" "In3.Cu" "In4.Cu" "In5.Cu" "In6.Cu")
			(hatch none 0.5)
			(connect_pads
				(clearance 0)
			)
			(min_thickness 0.25)
			(keepout
				(tracks not_allowed)
				(vias allowed)
				(pads allowed)
				(copperpour not_allowed)
				(footprints allowed)
			)
			(placement
				(enabled no)
				(sheetname "")
			)
			(fill
				(thermal_gap 0.5)
				(thermal_bridge_width 0.5)
				(island_removal_mode 0)
			)
			(polygon
				(pts
					(arc
						(start 28.974796 -125.035056)
						(mid 27.425396 -125.035056)
						(end 28.974796 -125.035056)
					)
				)
			)
		)
		(zone
			(layers "F.Cu" "B.Cu" "In1.Cu" "In2.Cu" "In3.Cu" "In4.Cu" "In5.Cu" "In6.Cu")
			(hatch none 0.5)
			(connect_pads
				(clearance 0)
			)
			(min_thickness 0.25)
			(keepout
				(tracks not_allowed)
				(vias allowed)
				(pads allowed)
				(copperpour not_allowed)
				(footprints allowed)
			)
			(placement
				(enabled no)
				(sheetname "")
			)
			(fill
				(thermal_gap 0.5)
				(thermal_bridge_width 0.5)
				(island_removal_mode 0)
			)
			(polygon
				(pts
					(arc
						(start 29.177996 -162.785044)
						(mid 27.222196 -162.785044)
						(end 29.177996 -162.785044)
					)
				)
			)
		)
	)
	(footprint ""
		(layer "F.Cu")
		(at 22.325838 -228.930454 -90)
		(property "Reference" "R1107"
			(at 0 0 270)
			(layer "F.SilkS")
			(hide yes)
			(effects
				(font
					(size 1.27 1.27)
				)
			)
		)
		(property "Value" "200KR2F-L-GP"
			(at 0.064008 -3.993896 270)
			(unlocked yes)
			(layer "F.Fab")
			(hide yes)
			(effects
				(font
					(size 1.016 1.016)
					(thickness 0.1524)
				)
			)
		)
		(property "Device Type" "R402H16"
			(at 0.064008 -5.517896 270)
			(unlocked yes)
			(layer "F.Fab")
			(hide yes)
			(effects
				(font
					(size 1.016 1.016)
					(thickness 0.1524)
				)
			)
		)
		(duplicate_pad_numbers_are_jumpers no)
		(fp_line
			(start -0.508 -0.9398)
			(end -0.508 0.9398)
			(stroke
				(width 0.1524)
				(type default)
			)
			(layer "F.SilkS")
		)
		(fp_line
			(start 0.508 -0.9398)
			(end -0.508 -0.9398)
			(stroke
				(width 0.1524)
				(type default)
			)
			(layer "F.SilkS")
		)
		(fp_rect
			(start -0.508 0.9398)
			(end 0.508 -0.9398)
			(stroke
				(width 0)
				(type default)
			)
			(fill no)
			(layer "F.CrtYd")
		)
		(fp_rect
			(start -0.508 0.9398)
			(end 0.508 -0.9398)
			(stroke
				(width 0)
				(type default)
			)
			(fill no)
			(layer "F.Fab")
		)
		(pad "1" smd custom
			(at 0 -0.4445 270)
			(size 0.1397 0.1397)
			(layers "F.Cu" "F.Mask" "F.Paste")
			(net "P5V_B_1_MODE")
			(options
				(clearance outline)
				(anchor circle)
			)
			(primitives
				(gr_poly
					(pts
						(arc
							(start -0.1778 -0.2794)
							(mid -0.249642 -0.249642)
							(end -0.2794 -0.1778)
						)
						(arc
							(start -0.2794 0.1778)
							(mid -0.249642 0.249642)
							(end -0.1778 0.2794)
						)
						(arc
							(start 0.1778 0.2794)
							(mid 0.249642 0.249642)
							(end 0.2794 0.1778)
						)
						(arc
							(start 0.2794 -0.1778)
							(mid 0.249642 -0.249642)
							(end 0.1778 -0.2794)
						)
					)
					(width 0)
					(fill yes)
				)
			)
		)
		(pad "2" smd custom
			(at 0 0.4445 270)
			(size 0.1397 0.1397)
			(layers "F.Cu" "F.Mask" "F.Paste")
			(net "P5V_B_1_PGOOD")
			(options
				(clearance outline)
				(anchor circle)
			)
			(primitives
				(gr_poly
					(pts
						(arc
							(start -0.1778 -0.2794)
							(mid -0.249642 -0.249642)
							(end -0.2794 -0.1778)
						)
						(arc
							(start -0.2794 0.1778)
							(mid -0.249642 0.249642)
							(end -0.1778 0.2794)
						)
						(arc
							(start 0.1778 0.2794)
							(mid 0.249642 0.249642)
							(end 0.2794 0.1778)
						)
						(arc
							(start 0.2794 -0.1778)
							(mid 0.249642 -0.249642)
							(end 0.1778 -0.2794)
						)
					)
					(width 0)
					(fill yes)
				)
			)
		)
	)
	(footprint ""
		(layer "F.Cu")
		(at 46.863 -248.158 180)
		(property "Reference" "R186"
			(at 0 0 180)
			(layer "F.SilkS")
			(hide yes)
			(effects
				(font
					(size 1.27 1.27)
				)
			)
		)
		(property "Value" "200KR2F-L-GP"
			(at 0.064008 -3.993896 180)
			(unlocked yes)
			(layer "F.Fab")
			(hide yes)
			(effects
				(font
					(size 1.016 1.016)
					(thickness 0.1524)
				)
			)
		)
		(property "Device Type" "R402H16"
			(at 0.064008 -5.517896 180)
			(unlocked yes)
			(layer "F.Fab")
			(hide yes)
			(effects
				(font
					(size 1.016 1.016)
					(thickness 0.1524)
				)
			)
		)
		(duplicate_pad_numbers_are_jumpers no)
		(fp_line
			(start 0.508 -0.9398)
			(end -0.508 -0.9398)
			(stroke
				(width 0.1524)
				(type default)
			)
			(layer "F.SilkS")
		)
		(fp_line
			(start -0.508 -0.9398)
			(end -0.508 0.9398)
			(stroke
				(width 0.1524)
				(type default)
			)
			(layer "F.SilkS")
		)
		(fp_rect
			(start -0.508 0.9398)
			(end 0.508 -0.9398)
			(stroke
				(width 0)
				(type default)
			)
			(fill no)
			(layer "F.CrtYd")
		)
		(fp_rect
			(start -0.508 0.9398)
			(end 0.508 -0.9398)
			(stroke
				(width 0)
				(type default)
			)
			(fill no)
			(layer "F.Fab")
		)
		(pad "1" smd custom
			(at 0 -0.4445 180)
			(size 0.1397 0.1397)
			(layers "F.Cu" "F.Mask" "F.Paste")
			(net "SW_HDD_R1")
			(options
				(clearance outline)
				(anchor circle)
			)
			(primitives
				(gr_poly
					(pts
						(arc
							(start -0.1778 -0.2794)
							(mid -0.249642 -0.249642)
							(end -0.2794 -0.1778)
						)
						(arc
							(start -0.2794 0.1778)
							(mid -0.249642 0.249642)
							(end -0.1778 0.2794)
						)
						(arc
							(start 0.1778 0.2794)
							(mid 0.249642 0.249642)
							(end 0.2794 0.1778)
						)
						(arc
							(start 0.2794 -0.1778)
							(mid 0.249642 -0.249642)
							(end 0.1778 -0.2794)
						)
					)
					(width 0)
					(fill yes)
				)
			)
		)
		(pad "2" smd custom
			(at 0 0.4445 180)
			(size 0.1397 0.1397)
			(layers "F.Cu" "F.Mask" "F.Paste")
			(net "SW_HDD_N1")
			(options
				(clearance outline)
				(anchor circle)
			)
			(primitives
				(gr_poly
					(pts
						(arc
							(start -0.1778 -0.2794)
							(mid -0.249642 -0.249642)
							(end -0.2794 -0.1778)
						)
						(arc
							(start -0.2794 0.1778)
							(mid -0.249642 0.249642)
							(end -0.1778 0.2794)
						)
						(arc
							(start 0.1778 0.2794)
							(mid 0.249642 0.249642)
							(end 0.2794 0.1778)
						)
						(arc
							(start 0.2794 -0.1778)
							(mid 0.249642 -0.249642)
							(end 0.1778 -0.2794)
						)
					)
					(width 0)
					(fill yes)
				)
			)
		)
	)
	(footprint ""
		(layer "F.Cu")
		(at 220.6752 -192.151 -90)
		(property "Reference" "R26"
			(at 0 0 270)
			(layer "F.SilkS")
			(hide yes)
			(effects
				(font
					(size 1.27 1.27)
				)
			)
		)
		(property "Value" "4K7R2F-GP"
			(at 0.064008 -3.993896 270)
			(unlocked yes)
			(layer "F.Fab")
			(hide yes)
			(effects
				(font
					(size 1.016 1.016)
					(thickness 0.1524)
				)
			)
		)
		(property "Device Type" "R402H16"
			(at 0.064008 -5.517896 270)
			(unlocked yes)
			(layer "F.Fab")
			(hide yes)
			(effects
				(font
					(size 1.016 1.016)
					(thickness 0.1524)
				)
			)
		)
		(duplicate_pad_numbers_are_jumpers no)
		(fp_line
			(start -0.508 -0.9398)
			(end -0.508 0.9398)
			(stroke
				(width 0.1524)
				(type default)
			)
			(layer "F.SilkS")
		)
		(fp_line
			(start 0.508 -0.9398)
			(end -0.508 -0.9398)
			(stroke
				(width 0.1524)
				(type default)
			)
			(layer "F.SilkS")
		)
		(fp_rect
			(start -0.508 0.9398)
			(end 0.508 -0.9398)
			(stroke
				(width 0)
				(type default)
			)
			(fill no)
			(layer "F.CrtYd")
		)
		(fp_rect
			(start -0.508 0.9398)
			(end 0.508 -0.9398)
			(stroke
				(width 0)
				(type default)
			)
			(fill no)
			(layer "F.Fab")
		)
		(pad "1" smd custom
			(at 0 -0.4445 270)
			(size 0.1397 0.1397)
			(layers "F.Cu" "F.Mask" "F.Paste")
			(net "P3V3_STBY_B")
			(options
				(clearance outline)
				(anchor circle)
			)
			(primitives
				(gr_poly
					(pts
						(arc
							(start -0.1778 -0.2794)
							(mid -0.249642 -0.249642)
							(end -0.2794 -0.1778)
						)
						(arc
							(start -0.2794 0.1778)
							(mid -0.249642 0.249642)
							(end -0.1778 0.2794)
						)
						(arc
							(start 0.1778 0.2794)
							(mid 0.249642 0.249642)
							(end 0.2794 0.1778)
						)
						(arc
							(start 0.2794 -0.1778)
							(mid 0.249642 -0.249642)
							(end 0.1778 -0.2794)
						)
					)
					(width 0)
					(fill yes)
				)
			)
		)
		(pad "2" smd custom
			(at 0 0.4445 270)
			(size 0.1397 0.1397)
			(layers "F.Cu" "F.Mask" "F.Paste")
			(net "IO_EXP2_HDD_FAULT_A0")
			(options
				(clearance outline)
				(anchor circle)
			)
			(primitives
				(gr_poly
					(pts
						(arc
							(start -0.1778 -0.2794)
							(mid -0.249642 -0.249642)
							(end -0.2794 -0.1778)
						)
						(arc
							(start -0.2794 0.1778)
							(mid -0.249642 0.249642)
							(end -0.1778 0.2794)
						)
						(arc
							(start 0.1778 0.2794)
							(mid 0.249642 0.249642)
							(end 0.2794 0.1778)
						)
						(arc
							(start 0.2794 -0.1778)
							(mid 0.249642 -0.249642)
							(end 0.1778 -0.2794)
						)
					)
					(width 0)
					(fill yes)
				)
			)
		)
	)
	(footprint ""
		(layer "F.Cu")
		(at 335.788 -243.586 180)
		(property "Reference" "R262"
			(at 0 0 180)
			(layer "F.SilkS")
			(hide yes)
			(effects
				(font
					(size 1.27 1.27)
				)
			)
		)
		(property "Value" "0R2J-2-GP"
			(at 0.064008 -3.993896 180)
			(unlocked yes)
			(layer "F.Fab")
			(hide yes)
			(effects
				(font
					(size 1.016 1.016)
					(thickness 0.1524)
				)
			)
		)
		(property "Device Type" "R402H16"
			(at 0.064008 -5.517896 180)
			(unlocked yes)
			(layer "F.Fab")
			(hide yes)
			(effects
				(font
					(size 1.016 1.016)
					(thickness 0.1524)
				)
			)
		)
		(duplicate_pad_numbers_are_jumpers no)
		(fp_line
			(start 0.508 -0.9398)
			(end -0.508 -0.9398)
			(stroke
				(width 0.1524)
				(type default)
			)
			(layer "F.SilkS")
		)
		(fp_line
			(start -0.508 -0.9398)
			(end -0.508 0.9398)
			(stroke
				(width 0.1524)
				(type default)
			)
			(layer "F.SilkS")
		)
		(fp_rect
			(start -0.508 0.9398)
			(end 0.508 -0.9398)
			(stroke
				(width 0)
				(type default)
			)
			(fill no)
			(layer "F.CrtYd")
		)
		(fp_rect
			(start -0.508 0.9398)
			(end 0.508 -0.9398)
			(stroke
				(width 0)
				(type default)
			)
			(fill no)
			(layer "F.Fab")
		)
		(pad "1" smd custom
			(at 0 -0.4445 180)
			(size 0.1397 0.1397)
			(layers "F.Cu" "F.Mask" "F.Paste")
			(net "DRIVE_B_6_PWR")
			(options
				(clearance outline)
				(anchor circle)
			)
			(primitives
				(gr_poly
					(pts
						(arc
							(start -0.1778 -0.2794)
							(mid -0.249642 -0.249642)
							(end -0.2794 -0.1778)
						)
						(arc
							(start -0.2794 0.1778)
							(mid -0.249642 0.249642)
							(end -0.1778 0.2794)
						)
						(arc
							(start 0.1778 0.2794)
							(mid 0.249642 0.249642)
							(end 0.2794 0.1778)
						)
						(arc
							(start 0.2794 -0.1778)
							(mid 0.249642 -0.249642)
							(end 0.1778 -0.2794)
						)
					)
					(width 0)
					(fill yes)
				)
			)
		)
		(pad "2" smd custom
			(at 0 0.4445 180)
			(size 0.1397 0.1397)
			(layers "F.Cu" "F.Mask" "F.Paste")
			(net "SW_PWR_R_HDD6")
			(options
				(clearance outline)
				(anchor circle)
			)
			(primitives
				(gr_poly
					(pts
						(arc
							(start -0.1778 -0.2794)
							(mid -0.249642 -0.249642)
							(end -0.2794 -0.1778)
						)
						(arc
							(start -0.2794 0.1778)
							(mid -0.249642 0.249642)
							(end -0.1778 0.2794)
						)
						(arc
							(start 0.1778 0.2794)
							(mid 0.249642 0.249642)
							(end 0.2794 0.1778)
						)
						(arc
							(start 0.2794 -0.1778)
							(mid 0.249642 -0.249642)
							(end 0.1778 -0.2794)
						)
					)
					(width 0)
					(fill yes)
				)
			)
		)
	)
	(footprint ""
		(layer "F.Cu")
		(at 127.113284 -130.21945 90)
		(property "Reference" "C223"
			(at 0 0 90)
			(layer "F.SilkS")
			(hide yes)
			(effects
				(font
					(size 1.27 1.27)
				)
			)
		)
		(property "Value" "SCD01U16V1KX-GP"
			(at -2.8321 -1.7399 90)
			(unlocked yes)
			(layer "F.Fab")
			(hide yes)
			(effects
				(font
					(size 1.016 1.016)
					(thickness 0.1524)
				)
			)
		)
		(property "Device Type" "C0201H13"
			(at -2.8321 -3.2639 90)
			(unlocked yes)
			(layer "F.Fab")
			(hide yes)
			(effects
				(font
					(size 1.016 1.016)
					(thickness 0.1524)
				)
			)
		)
		(duplicate_pad_numbers_are_jumpers no)
		(fp_rect
			(start -0.2794 0.6477)
			(end 0.2794 -0.6477)
			(stroke
				(width 0)
				(type default)
			)
			(fill no)
			(layer "F.CrtYd")
		)
		(fp_rect
			(start -0.2794 0.6477)
			(end 0.2794 -0.6477)
			(stroke
				(width 0)
				(type default)
			)
			(fill no)
			(layer "F.Fab")
		)
		(pad "1" smd custom
			(at 0 -0.2794 90)
			(size 0.0762 0.0762)
			(layers "F.Cu" "F.Mask" "F.Paste")
			(net "SAS_HDD_RX_N15")
			(options
				(clearance outline)
				(anchor circle)
			)
			(primitives
				(gr_poly
					(pts
						(arc
							(start 0.1524 -0.127)
							(mid 0.137521 -0.162921)
							(end 0.1016 -0.1778)
						)
						(arc
							(start -0.1016 -0.1778)
							(mid -0.137521 -0.162921)
							(end -0.1524 -0.127)
						)
						(arc
							(start -0.1524 0.127)
							(mid -0.137521 0.162921)
							(end -0.1016 0.1778)
						)
						(arc
							(start 0.1016 0.1778)
							(mid 0.137521 0.162921)
							(end 0.1524 0.127)
						)
					)
					(width 0)
					(fill yes)
				)
			)
		)
		(pad "2" smd custom
			(at 0 0.2794 90)
			(size 0.0762 0.0762)
			(layers "F.Cu" "F.Mask" "F.Paste")
			(net "PHY_SCC_B_TO_DRV_B_15_DN")
			(options
				(clearance outline)
				(anchor circle)
			)
			(primitives
				(gr_poly
					(pts
						(arc
							(start 0.1524 -0.127)
							(mid 0.137521 -0.162921)
							(end 0.1016 -0.1778)
						)
						(arc
							(start -0.1016 -0.1778)
							(mid -0.137521 -0.162921)
							(end -0.1524 -0.127)
						)
						(arc
							(start -0.1524 0.127)
							(mid -0.137521 0.162921)
							(end -0.1016 0.1778)
						)
						(arc
							(start 0.1016 0.1778)
							(mid 0.137521 0.162921)
							(end 0.1524 0.127)
						)
					)
					(width 0)
					(fill yes)
				)
			)
		)
	)
	(footprint ""
		(layer "F.Cu")
		(at 325.550022 -143.91005 -90)
		(property "Reference" "HDDSAS18"
			(at 0 0 270)
			(layer "F.SilkS")
			(hide yes)
			(effects
				(font
					(size 1.27 1.27)
				)
			)
		)
		(property "Value" "SKT-SAS15P-14P-45-GP"
			(at -20.7645 -8.9789 270)
			(unlocked yes)
			(layer "F.Fab")
			(hide yes)
			(effects
				(font
					(size 1.016 1.016)
					(thickness 0.1524)
				)
			)
		)
		(property "Device Type" "10120818-001C-TRLF"
			(at -20.7645 -10.5029 270)
			(unlocked yes)
			(layer "F.Fab")
			(hide yes)
			(effects
				(font
					(size 1.016 1.016)
					(thickness 0.1524)
				)
			)
		)
		(duplicate_pad_numbers_are_jumpers no)
		(fp_line
			(start 1.651 4.2926)
			(end 1.651 3.0099)
			(stroke
				(width 0.1524)
				(type default)
			)
			(layer "F.SilkS")
		)
		(fp_line
			(start 8.509 4.2926)
			(end 1.651 4.2926)
			(stroke
				(width 0.1524)
				(type default)
			)
			(layer "F.SilkS")
		)
		(fp_line
			(start -23.4188 3.0099)
			(end -23.4188 -3.2512)
			(stroke
				(width 0.1524)
				(type default)
			)
			(layer "F.SilkS")
		)
		(fp_line
			(start 1.651 3.0099)
			(end -23.4188 3.0099)
			(stroke
				(width 0.1524)
				(type default)
			)
			(layer "F.SilkS")
		)
		(fp_line
			(start 8.509 3.0099)
			(end 8.509 4.2926)
			(stroke
				(width 0.1524)
				(type default)
			)
			(layer "F.SilkS")
		)
		(fp_line
			(start 23.4188 3.0099)
			(end 8.509 3.0099)
			(stroke
				(width 0.1524)
				(type default)
			)
			(layer "F.SilkS")
		)
		(fp_line
			(start -23.4188 -3.2512)
			(end 23.4188 -3.2512)
			(stroke
				(width 0.1524)
				(type default)
			)
			(layer "F.SilkS")
		)
		(fp_line
			(start 23.4188 -3.2512)
			(end 23.4188 3.0099)
			(stroke
				(width 0.1524)
				(type default)
			)
			(layer "F.SilkS")
		)
		(fp_line
			(start 15.5067 -3.3401)
			(end 16.2687 -3.3401)
			(stroke
				(width 0.3302)
				(type default)
			)
			(layer "F.SilkS")
		)
		(fp_poly
			(pts
				(xy 15.868904 -3.230372) (xy 16.503904 -3.865372) (xy 15.233904 -3.865372)
			)
			(stroke
				(width 0)
				(type default)
			)
			(fill yes)
			(layer "F.SilkS")
		)
		(fp_poly
			(pts
				(xy -22.8727 -2.7559) (xy 22.8727 -2.7559) (xy 22.8727 2.7559) (xy 8.255 2.7559) (xy 8.255 3.5179)
				(xy 1.905 3.5179) (xy 1.905 2.7559) (xy -22.8727 2.7559)
			)
			(stroke
				(width 0)
				(type default)
			)
			(fill no)
			(layer "F.CrtYd")
		)
		(fp_poly
			(pts
				(xy 1.397 4.5466) (xy 1.397 3.2639) (xy -23.6728 3.2639) (xy -23.6728 -3.5052) (xy 23.6728 -3.5052)
				(xy 23.6728 -0.00635) (xy 22.8727 -0.00635) (xy 22.8727 -2.7559) (xy -22.8727 -2.7559) (xy -22.8727 2.7559)
				(xy 1.905 2.7559) (xy 1.905 3.5179) (xy 8.255 3.5179) (xy 8.255 2.7559) (xy 22.8727 2.7559) (xy 22.8727 0.00635)
				(xy 23.6728 0.00635) (xy 23.6728 3.2639) (xy 8.763 3.2639) (xy 8.763 4.5466)
			)
			(stroke
				(width 0)
				(type default)
			)
			(fill no)
			(layer "F.CrtYd")
		)
		(fp_poly
			(pts
				(xy 1.397 4.5466) (xy 1.397 3.2639) (xy -23.6728 3.2639) (xy -23.6728 -3.5052) (xy 23.6728 -3.5052)
				(xy 23.6728 3.2639) (xy 8.763 3.2639) (xy 8.763 4.5466)
			)
			(stroke
				(width 0)
				(type default)
			)
			(fill no)
			(layer "F.Fab")
		)
		(pad "" np_thru_hole circle
			(at -18.874994 0 270)
			(size 0.254 0.254)
			(drill 1.3462)
			(layers "*.Cu" "*.Mask")
			(clearance 0.9017)
			(thermal_gap 0.9017)
		)
		(pad "" np_thru_hole circle
			(at 18.874994 0 270)
			(size 0.254 0.254)
			(drill 0.9398)
			(layers "*.Cu" "*.Mask")
			(clearance 0.6985)
			(thermal_gap 0.6985)
		)
		(pad "G1" smd rect
			(at 21.874988 0 270)
			(size 2.5908 2.5908)
			(layers "F.Cu" "F.Mask" "F.Paste")
			(net "GND")
		)
		(pad "G2" smd rect
			(at -21.874988 0 270)
			(size 2.5908 2.5908)
			(layers "F.Cu" "F.Mask" "F.Paste")
			(net "GND")
		)
		(pad "P1" smd rect
			(at 1.905 -1.82499 270)
			(size 0.6096 2.3622)
			(layers "F.Cu" "F.Mask" "F.Paste")
			(net "Net_1714")
		)
		(pad "P2" smd rect
			(at 0.635 -1.82499 270)
			(size 0.6096 2.3622)
			(layers "F.Cu" "F.Mask" "F.Paste")
			(net "Net_1715")
		)
		(pad "P3" smd rect
			(at -0.635 -1.82499 270)
			(size 0.6096 2.3622)
			(layers "F.Cu" "F.Mask" "F.Paste")
			(net "Net_1716")
		)
		(pad "P4" smd rect
			(at -1.905 -1.82499 270)
			(size 0.6096 2.3622)
			(layers "F.Cu" "F.Mask" "F.Paste")
			(net "GND")
		)
		(pad "P5" smd rect
			(at -3.175 -1.82499 270)
			(size 0.6096 2.3622)
			(layers "F.Cu" "F.Mask" "F.Paste")
			(net "HDD_PRSNT_18")
		)
		(pad "P6" smd rect
			(at -4.445 -1.82499 270)
			(size 0.6096 2.3622)
			(layers "F.Cu" "F.Mask" "F.Paste")
			(net "GND")
		)
		(pad "P7" smd rect
			(at -5.715 -1.82499 270)
			(size 0.6096 2.3622)
			(layers "F.Cu" "F.Mask" "F.Paste")
			(net "5V_PRE_18")
		)
		(pad "P8" smd rect
			(at -6.985 -1.82499 270)
			(size 0.6096 2.3622)
			(layers "F.Cu" "F.Mask" "F.Paste")
			(net "P5V_HDD18")
		)
		(pad "P9" smd rect
			(at -8.255 -1.82499 270)
			(size 0.6096 2.3622)
			(layers "F.Cu" "F.Mask" "F.Paste")
			(net "P5V_HDD18")
		)
		(pad "P10" smd rect
			(at -9.525 -1.82499 270)
			(size 0.6096 2.3622)
			(layers "F.Cu" "F.Mask" "F.Paste")
			(net "GND")
		)
		(pad "P11" smd rect
			(at -10.795 -1.82499 270)
			(size 0.6096 2.3622)
			(layers "F.Cu" "F.Mask" "F.Paste")
			(net "ACT_HDD_18")
		)
		(pad "P12" smd rect
			(at -12.065 -1.82499 270)
			(size 0.6096 2.3622)
			(layers "F.Cu" "F.Mask" "F.Paste")
			(net "GND")
		)
		(pad "P13" smd rect
			(at -13.335 -1.82499 270)
			(size 0.6096 2.3622)
			(layers "F.Cu" "F.Mask" "F.Paste")
			(net "12V_PRE_18")
		)
		(pad "P14" smd rect
			(at -14.605 -1.82499 270)
			(size 0.6096 2.3622)
			(layers "F.Cu" "F.Mask" "F.Paste")
			(net "P12V_HDD18")
		)
		(pad "P15" smd rect
			(at -15.875 -1.82499 270)
			(size 0.6096 2.3622)
			(layers "F.Cu" "F.Mask" "F.Paste")
			(net "P12V_HDD18")
		)
		(pad "S1" smd rect
			(at 15.875 -1.82499 270)
			(size 0.6096 2.3622)
			(layers "F.Cu" "F.Mask" "F.Paste")
			(net "GND")
		)
		(pad "S2" smd rect
			(at 14.605 -1.82499 270)
			(size 0.6096 2.3622)
			(layers "F.Cu" "F.Mask" "F.Paste")
			(net "SAS_HDD_RX_P18")
		)
		(pad "S3" smd rect
			(at 13.335 -1.82499 270)
			(size 0.6096 2.3622)
			(layers "F.Cu" "F.Mask" "F.Paste")
			(net "SAS_HDD_RX_N18")
		)
		(pad "S4" smd rect
			(at 12.065 -1.82499 270)
			(size 0.6096 2.3622)
			(layers "F.Cu" "F.Mask" "F.Paste")
			(net "GND")
		)
		(pad "S5" smd rect
			(at 10.795 -1.82499 270)
			(size 0.6096 2.3622)
			(layers "F.Cu" "F.Mask" "F.Paste")
			(net "PHY_DRV_B_TO_SCC_B_18_DN")
		)
		(pad "S6" smd rect
			(at 9.525 -1.82499 270)
			(size 0.6096 2.3622)
			(layers "F.Cu" "F.Mask" "F.Paste")
			(net "PHY_DRV_B_TO_SCC_B_18_DP")
		)
		(pad "S7" smd rect
			(at 8.255 -1.82499 270)
			(size 0.6096 2.3622)
			(layers "F.Cu" "F.Mask" "F.Paste")
			(net "GND")
		)
		(pad "S8" smd rect
			(at 7.480046 2.845054 270)
			(size 0.508 2.3622)
			(layers "F.Cu" "F.Mask" "F.Paste")
			(net "GND")
		)
		(pad "S9" smd rect
			(at 6.679946 2.845054 270)
			(size 0.508 2.3622)
			(layers "F.Cu" "F.Mask" "F.Paste")
			(net "Net_441")
		)
		(pad "S10" smd rect
			(at 5.8801 2.845054 270)
			(size 0.508 2.3622)
			(layers "F.Cu" "F.Mask" "F.Paste")
			(net "Net_333")
		)
		(pad "S11" smd rect
			(at 5.08 2.845054 270)
			(size 0.508 2.3622)
			(layers "F.Cu" "F.Mask" "F.Paste")
			(net "GND")
		)
		(pad "S12" smd rect
			(at 4.2799 2.845054 270)
			(size 0.508 2.3622)
			(layers "F.Cu" "F.Mask" "F.Paste")
			(net "Net_369")
		)
		(pad "S13" smd rect
			(at 3.480054 2.845054 270)
			(size 0.508 2.3622)
			(layers "F.Cu" "F.Mask" "F.Paste")
			(net "Net_405")
		)
		(pad "S14" smd rect
			(at 2.679954 2.845054 270)
			(size 0.508 2.3622)
			(layers "F.Cu" "F.Mask" "F.Paste")
			(net "GND")
		)
		(zone
			(layer "F.Cu")
			(hatch none 0.5)
			(connect_pads
				(clearance 0)
			)
			(min_thickness 0.25)
			(keepout
				(tracks allowed)
				(vias not_allowed)
				(pads allowed)
				(copperpour not_allowed)
				(footprints allowed)
			)
			(placement
				(enabled no)
				(sheetname "")
			)
			(fill
				(thermal_gap 0.5)
				(thermal_bridge_width 0.5)
				(island_removal_mode 0)
			)
			(polygon
				(pts
					(xy 329.207622 -160.64865) (xy 322.133722 -160.64865) (xy 322.133722 -167.58285) (xy 323.238622 -167.58285)
					(xy 323.238622 -163.46805) (xy 327.861422 -163.46805) (xy 327.861422 -167.58285) (xy 329.207622 -167.58285)
				)
			)
		)
		(zone
			(layer "F.Cu")
			(hatch none 0.5)
			(connect_pads
				(clearance 0)
			)
			(min_thickness 0.25)
			(keepout
				(tracks not_allowed)
				(vias allowed)
				(pads allowed)
				(copperpour not_allowed)
				(footprints allowed)
			)
			(placement
				(enabled no)
				(sheetname "")
			)
			(fill
				(thermal_gap 0.5)
				(thermal_bridge_width 0.5)
				(island_removal_mode 0)
			)
			(polygon
				(pts
					(xy 329.207622 -160.64865) (xy 322.133722 -160.64865) (xy 322.133722 -167.58285) (xy 323.238622 -167.58285)
					(xy 323.238622 -163.46805) (xy 327.861422 -163.46805) (xy 327.861422 -167.58285) (xy 329.207622 -167.58285)
				)
			)
		)
		(zone
			(layer "F.Cu")
			(hatch none 0.5)
			(connect_pads
				(clearance 0)
			)
			(min_thickness 0.25)
			(keepout
				(tracks allowed)
				(vias not_allowed)
				(pads allowed)
				(copperpour not_allowed)
				(footprints allowed)
			)
			(placement
				(enabled no)
				(sheetname "")
			)
			(fill
				(thermal_gap 0.5)
				(thermal_bridge_width 0.5)
				(island_removal_mode 0)
			)
			(polygon
				(pts
					(xy 329.207622 -127.17145) (xy 322.133722 -127.17145) (xy 322.133722 -120.23725) (xy 323.238622 -120.23725)
					(xy 323.238622 -124.35205) (xy 327.861422 -124.35205) (xy 327.861422 -120.23725) (xy 329.207622 -120.23725)
				)
			)
		)
		(zone
			(layer "F.Cu")
			(hatch none 0.5)
			(connect_pads
				(clearance 0)
			)
			(min_thickness 0.25)
			(keepout
				(tracks not_allowed)
				(vias allowed)
				(pads allowed)
				(copperpour not_allowed)
				(footprints allowed)
			)
			(placement
				(enabled no)
				(sheetname "")
			)
			(fill
				(thermal_gap 0.5)
				(thermal_bridge_width 0.5)
				(island_removal_mode 0)
			)
			(polygon
				(pts
					(xy 329.207622 -127.17145) (xy 322.133722 -127.17145) (xy 322.133722 -120.23725) (xy 323.238622 -120.23725)
					(xy 323.238622 -124.35205) (xy 327.861422 -124.35205) (xy 327.861422 -120.23725) (xy 329.207622 -120.23725)
				)
			)
		)
		(zone
			(layers "F.Cu" "B.Cu" "In1.Cu" "In2.Cu" "In3.Cu" "In4.Cu" "In5.Cu" "In6.Cu")
			(hatch none 0.5)
			(connect_pads
				(clearance 0)
			)
			(min_thickness 0.25)
			(keepout
				(tracks not_allowed)
				(vias allowed)
				(pads allowed)
				(copperpour not_allowed)
				(footprints allowed)
			)
			(placement
				(enabled no)
				(sheetname "")
			)
			(fill
				(thermal_gap 0.5)
				(thermal_bridge_width 0.5)
				(island_removal_mode 0)
			)
			(polygon
				(pts
					(arc
						(start 326.324722 -125.035056)
						(mid 324.775322 -125.035056)
						(end 326.324722 -125.035056)
					)
				)
			)
		)
		(zone
			(layers "F.Cu" "B.Cu" "In1.Cu" "In2.Cu" "In3.Cu" "In4.Cu" "In5.Cu" "In6.Cu")
			(hatch none 0.5)
			(connect_pads
				(clearance 0)
			)
			(min_thickness 0.25)
			(keepout
				(tracks not_allowed)
				(vias allowed)
				(pads allowed)
				(copperpour not_allowed)
				(footprints allowed)
			)
			(placement
				(enabled no)
				(sheetname "")
			)
			(fill
				(thermal_gap 0.5)
				(thermal_bridge_width 0.5)
				(island_removal_mode 0)
			)
			(polygon
				(pts
					(arc
						(start 326.527922 -162.785044)
						(mid 324.572122 -162.785044)
						(end 326.527922 -162.785044)
					)
				)
			)
		)
	)
	(footprint ""
		(layer "F.Cu")
		(at 190.213488 -244.660674 90)
		(property "Reference" "C93"
			(at 0 0 90)
			(layer "F.SilkS")
			(hide yes)
			(effects
				(font
					(size 1.27 1.27)
				)
			)
		)
		(property "Value" "SCD01U16V1KX-GP"
			(at -2.8321 -1.7399 90)
			(unlocked yes)
			(layer "F.Fab")
			(hide yes)
			(effects
				(font
					(size 1.016 1.016)
					(thickness 0.1524)
				)
			)
		)
		(property "Device Type" "C0201H13"
			(at -2.8321 -3.2639 90)
			(unlocked yes)
			(layer "F.Fab")
			(hide yes)
			(effects
				(font
					(size 1.016 1.016)
					(thickness 0.1524)
				)
			)
		)
		(duplicate_pad_numbers_are_jumpers no)
		(fp_rect
			(start -0.2794 0.6477)
			(end 0.2794 -0.6477)
			(stroke
				(width 0)
				(type default)
			)
			(fill no)
			(layer "F.CrtYd")
		)
		(fp_rect
			(start -0.2794 0.6477)
			(end 0.2794 -0.6477)
			(stroke
				(width 0)
				(type default)
			)
			(fill no)
			(layer "F.Fab")
		)
		(pad "1" smd custom
			(at 0 -0.2794 90)
			(size 0.0762 0.0762)
			(layers "F.Cu" "F.Mask" "F.Paste")
			(net "SAS_HDD_RX_P5")
			(options
				(clearance outline)
				(anchor circle)
			)
			(primitives
				(gr_poly
					(pts
						(arc
							(start 0.1524 -0.127)
							(mid 0.137521 -0.162921)
							(end 0.1016 -0.1778)
						)
						(arc
							(start -0.1016 -0.1778)
							(mid -0.137521 -0.162921)
							(end -0.1524 -0.127)
						)
						(arc
							(start -0.1524 0.127)
							(mid -0.137521 0.162921)
							(end -0.1016 0.1778)
						)
						(arc
							(start 0.1016 0.1778)
							(mid 0.137521 0.162921)
							(end 0.1524 0.127)
						)
					)
					(width 0)
					(fill yes)
				)
			)
		)
		(pad "2" smd custom
			(at 0 0.2794 90)
			(size 0.0762 0.0762)
			(layers "F.Cu" "F.Mask" "F.Paste")
			(net "PHY_SCC_B_TO_DRV_B_5_DP")
			(options
				(clearance outline)
				(anchor circle)
			)
			(primitives
				(gr_poly
					(pts
						(arc
							(start 0.1524 -0.127)
							(mid 0.137521 -0.162921)
							(end 0.1016 -0.1778)
						)
						(arc
							(start -0.1016 -0.1778)
							(mid -0.137521 -0.162921)
							(end -0.1524 -0.127)
						)
						(arc
							(start -0.1524 0.127)
							(mid -0.137521 0.162921)
							(end -0.1016 0.1778)
						)
						(arc
							(start 0.1016 0.1778)
							(mid 0.137521 0.162921)
							(end 0.1524 0.127)
						)
					)
					(width 0)
					(fill yes)
				)
			)
		)
	)
	(footprint ""
		(layer "F.Cu")
		(at 109.474 -140.462 90)
		(property "Reference" "C234"
			(at 0 0 90)
			(layer "F.SilkS")
			(hide yes)
			(effects
				(font
					(size 1.27 1.27)
				)
			)
		)
		(property "Value" "SCD033U25V2KX-GP"
			(at 1.1811 -2.7051 90)
			(unlocked yes)
			(layer "F.Fab")
			(hide yes)
			(effects
				(font
					(size 1.016 1.016)
					(thickness 0.1524)
				)
			)
		)
		(property "Device Type" "C402H22"
			(at 1.1811 -4.2291 90)
			(unlocked yes)
			(layer "F.Fab")
			(hide yes)
			(effects
				(font
					(size 1.016 1.016)
					(thickness 0.1524)
				)
			)
		)
		(duplicate_pad_numbers_are_jumpers no)
		(fp_rect
			(start -0.4318 0.9525)
			(end 0.4318 -0.9525)
			(stroke
				(width 0)
				(type default)
			)
			(fill no)
			(layer "F.CrtYd")
		)
		(fp_rect
			(start -0.4318 0.9525)
			(end 0.4318 -0.9525)
			(stroke
				(width 0)
				(type default)
			)
			(fill no)
			(layer "F.Fab")
		)
		(pad "1" smd custom
			(at 0 -0.4445 90)
			(size 0.1524 0.1524)
			(layers "F.Cu" "F.Mask" "F.Paste")
			(net "P12V_B")
			(options
				(clearance outline)
				(anchor circle)
			)
			(primitives
				(gr_poly
					(pts
						(arc
							(start 0.3048 -0.2032)
							(mid 0.275042 -0.275042)
							(end 0.2032 -0.3048)
						)
						(arc
							(start -0.2032 -0.3048)
							(mid -0.275042 -0.275042)
							(end -0.3048 -0.2032)
						)
						(arc
							(start -0.3048 0.2032)
							(mid -0.275042 0.275042)
							(end -0.2032 0.3048)
						)
						(arc
							(start 0.2032 0.3048)
							(mid 0.275042 0.275042)
							(end 0.3048 0.2032)
						)
					)
					(width 0)
					(fill yes)
				)
			)
		)
		(pad "2" smd custom
			(at 0 0.4445 90)
			(size 0.1524 0.1524)
			(layers "F.Cu" "F.Mask" "F.Paste")
			(net "SW_HDD_N15")
			(options
				(clearance outline)
				(anchor circle)
			)
			(primitives
				(gr_poly
					(pts
						(arc
							(start 0.3048 -0.2032)
							(mid 0.275042 -0.275042)
							(end 0.2032 -0.3048)
						)
						(arc
							(start -0.2032 -0.3048)
							(mid -0.275042 -0.275042)
							(end -0.3048 -0.2032)
						)
						(arc
							(start -0.3048 0.2032)
							(mid -0.275042 0.275042)
							(end -0.2032 0.3048)
						)
						(arc
							(start 0.2032 0.3048)
							(mid 0.275042 0.275042)
							(end 0.3048 0.2032)
						)
					)
					(width 0)
					(fill yes)
				)
			)
		)
	)
	(footprint ""
		(layer "F.Cu")
		(at 367.284 -246.761 180)
		(property "Reference" "R283"
			(at 0 0 180)
			(layer "F.SilkS")
			(hide yes)
			(effects
				(font
					(size 1.27 1.27)
				)
			)
		)
		(property "Value" "0R2J-2-GP"
			(at 0.064008 -3.993896 180)
			(unlocked yes)
			(layer "F.Fab")
			(hide yes)
			(effects
				(font
					(size 1.016 1.016)
					(thickness 0.1524)
				)
			)
		)
		(property "Device Type" "R402H16"
			(at 0.064008 -5.517896 180)
			(unlocked yes)
			(layer "F.Fab")
			(hide yes)
			(effects
				(font
					(size 1.016 1.016)
					(thickness 0.1524)
				)
			)
		)
		(duplicate_pad_numbers_are_jumpers no)
		(fp_line
			(start 0.508 -0.9398)
			(end -0.508 -0.9398)
			(stroke
				(width 0.1524)
				(type default)
			)
			(layer "F.SilkS")
		)
		(fp_line
			(start -0.508 -0.9398)
			(end -0.508 0.9398)
			(stroke
				(width 0.1524)
				(type default)
			)
			(layer "F.SilkS")
		)
		(fp_rect
			(start -0.508 0.9398)
			(end 0.508 -0.9398)
			(stroke
				(width 0)
				(type default)
			)
			(fill no)
			(layer "F.CrtYd")
		)
		(fp_rect
			(start -0.508 0.9398)
			(end 0.508 -0.9398)
			(stroke
				(width 0)
				(type default)
			)
			(fill no)
			(layer "F.Fab")
		)
		(pad "1" smd custom
			(at 0 -0.4445 180)
			(size 0.1397 0.1397)
			(layers "F.Cu" "F.Mask" "F.Paste")
			(net "SW_HDD_G7")
			(options
				(clearance outline)
				(anchor circle)
			)
			(primitives
				(gr_poly
					(pts
						(arc
							(start -0.1778 -0.2794)
							(mid -0.249642 -0.249642)
							(end -0.2794 -0.1778)
						)
						(arc
							(start -0.2794 0.1778)
							(mid -0.249642 0.249642)
							(end -0.1778 0.2794)
						)
						(arc
							(start 0.1778 0.2794)
							(mid 0.249642 0.249642)
							(end 0.2794 0.1778)
						)
						(arc
							(start 0.2794 -0.1778)
							(mid 0.249642 -0.249642)
							(end 0.1778 -0.2794)
						)
					)
					(width 0)
					(fill yes)
				)
			)
		)
		(pad "2" smd custom
			(at 0 0.4445 180)
			(size 0.1397 0.1397)
			(layers "F.Cu" "F.Mask" "F.Paste")
			(net "SW_HDD_R7")
			(options
				(clearance outline)
				(anchor circle)
			)
			(primitives
				(gr_poly
					(pts
						(arc
							(start -0.1778 -0.2794)
							(mid -0.249642 -0.249642)
							(end -0.2794 -0.1778)
						)
						(arc
							(start -0.2794 0.1778)
							(mid -0.249642 0.249642)
							(end -0.1778 0.2794)
						)
						(arc
							(start 0.1778 0.2794)
							(mid 0.249642 0.249642)
							(end 0.2794 0.1778)
						)
						(arc
							(start 0.2794 -0.1778)
							(mid 0.249642 -0.249642)
							(end 0.1778 -0.2794)
						)
					)
					(width 0)
					(fill yes)
				)
			)
		)
	)
	(footprint ""
		(layer "F.Cu")
		(at 187.866528 -370.137436 -90)
		(property "Reference" "Q216"
			(at 0 0 270)
			(layer "F.SilkS")
			(hide yes)
			(effects
				(font
					(size 1.27 1.27)
				)
			)
		)
		(property "Value" "2N7002KDW-GP"
			(at -2.3622 -8.2042 270)
			(unlocked yes)
			(layer "F.Fab")
			(hide yes)
			(effects
				(font
					(size 1.016 1.016)
					(thickness 0.1524)
				)
			)
		)
		(property "Device Type" "SOT-363H44"
			(at -2.3622 -10.1092 270)
			(unlocked yes)
			(layer "F.Fab")
			(hide yes)
			(effects
				(font
					(size 1.016 1.016)
					(thickness 0.1524)
				)
			)
		)
		(duplicate_pad_numbers_are_jumpers no)
		(fp_line
			(start -1.4478 1.7018)
			(end 1.4478 1.7018)
			(stroke
				(width 0.1524)
				(type default)
			)
			(layer "F.SilkS")
		)
		(fp_line
			(start 1.4478 1.7018)
			(end 1.4478 -1.7018)
			(stroke
				(width 0.1524)
				(type default)
			)
			(layer "F.SilkS")
		)
		(fp_line
			(start -1.27 1.524)
			(end -1.27 0.6604)
			(stroke
				(width 0.4826)
				(type default)
			)
			(layer "F.SilkS")
		)
		(fp_line
			(start -1.4478 -1.7018)
			(end -1.4478 1.7018)
			(stroke
				(width 0.1524)
				(type default)
			)
			(layer "F.SilkS")
		)
		(fp_line
			(start 1.4478 -1.7018)
			(end -1.4478 -1.7018)
			(stroke
				(width 0.1524)
				(type default)
			)
			(layer "F.SilkS")
		)
		(fp_poly
			(pts
				(xy -1.524 -1.778) (xy 1.524 -1.778) (xy 1.524 1.778) (xy -1.524 1.778)
			)
			(stroke
				(width 0)
				(type default)
			)
			(fill no)
			(layer "F.CrtYd")
		)
		(fp_poly
			(pts
				(xy -1.524 -1.778) (xy 1.524 -1.778) (xy 1.524 1.778) (xy -1.524 1.778)
			)
			(stroke
				(width 0)
				(type default)
			)
			(fill no)
			(layer "F.Fab")
		)
		(pad "1" smd rect
			(at -0.65024 0.9398 270)
			(size 0.4064 1.016)
			(layers "F.Cu" "F.Mask" "F.Paste")
			(net "GND")
		)
		(pad "2" smd rect
			(at 0 0.9398 270)
			(size 0.4064 1.016)
			(layers "F.Cu" "F.Mask" "F.Paste")
			(net "FAN_LED1_D")
		)
		(pad "3" smd rect
			(at 0.65024 0.9398 270)
			(size 0.4064 1.016)
			(layers "F.Cu" "F.Mask" "F.Paste")
			(net "FAN_LED1_D")
		)
		(pad "4" smd rect
			(at 0.65024 -0.9398 270)
			(size 0.4064 1.016)
			(layers "F.Cu" "F.Mask" "F.Paste")
			(net "GND")
		)
		(pad "5" smd rect
			(at 0 -0.9398 270)
			(size 0.4064 1.016)
			(layers "F.Cu" "F.Mask" "F.Paste")
			(net "FAN_LED1")
		)
		(pad "6" smd rect
			(at -0.65024 -0.9398 270)
			(size 0.4064 1.016)
			(layers "F.Cu" "F.Mask" "F.Paste")
			(net "FAN_LED1_D2")
		)
	)
	(footprint ""
		(layer "F.Cu")
		(at 430.403 -243.586 180)
		(property "Reference" "R310"
			(at 0 0 180)
			(layer "F.SilkS")
			(hide yes)
			(effects
				(font
					(size 1.27 1.27)
				)
			)
		)
		(property "Value" "0R2J-2-GP"
			(at 0.064008 -3.993896 180)
			(unlocked yes)
			(layer "F.Fab")
			(hide yes)
			(effects
				(font
					(size 1.016 1.016)
					(thickness 0.1524)
				)
			)
		)
		(property "Device Type" "R402H16"
			(at 0.064008 -5.517896 180)
			(unlocked yes)
			(layer "F.Fab")
			(hide yes)
			(effects
				(font
					(size 1.016 1.016)
					(thickness 0.1524)
				)
			)
		)
		(duplicate_pad_numbers_are_jumpers no)
		(fp_line
			(start 0.508 -0.9398)
			(end -0.508 -0.9398)
			(stroke
				(width 0.1524)
				(type default)
			)
			(layer "F.SilkS")
		)
		(fp_line
			(start -0.508 -0.9398)
			(end -0.508 0.9398)
			(stroke
				(width 0.1524)
				(type default)
			)
			(layer "F.SilkS")
		)
		(fp_rect
			(start -0.508 0.9398)
			(end 0.508 -0.9398)
			(stroke
				(width 0)
				(type default)
			)
			(fill no)
			(layer "F.CrtYd")
		)
		(fp_rect
			(start -0.508 0.9398)
			(end 0.508 -0.9398)
			(stroke
				(width 0)
				(type default)
			)
			(fill no)
			(layer "F.Fab")
		)
		(pad "1" smd custom
			(at 0 -0.4445 180)
			(size 0.1397 0.1397)
			(layers "F.Cu" "F.Mask" "F.Paste")
			(net "DRIVE_B_9_PWR")
			(options
				(clearance outline)
				(anchor circle)
			)
			(primitives
				(gr_poly
					(pts
						(arc
							(start -0.1778 -0.2794)
							(mid -0.249642 -0.249642)
							(end -0.2794 -0.1778)
						)
						(arc
							(start -0.2794 0.1778)
							(mid -0.249642 0.249642)
							(end -0.1778 0.2794)
						)
						(arc
							(start 0.1778 0.2794)
							(mid 0.249642 0.249642)
							(end 0.2794 0.1778)
						)
						(arc
							(start 0.2794 -0.1778)
							(mid 0.249642 -0.249642)
							(end 0.1778 -0.2794)
						)
					)
					(width 0)
					(fill yes)
				)
			)
		)
		(pad "2" smd custom
			(at 0 0.4445 180)
			(size 0.1397 0.1397)
			(layers "F.Cu" "F.Mask" "F.Paste")
			(net "SW_PWR_R_HDD9")
			(options
				(clearance outline)
				(anchor circle)
			)
			(primitives
				(gr_poly
					(pts
						(arc
							(start -0.1778 -0.2794)
							(mid -0.249642 -0.249642)
							(end -0.2794 -0.1778)
						)
						(arc
							(start -0.2794 0.1778)
							(mid -0.249642 0.249642)
							(end -0.1778 0.2794)
						)
						(arc
							(start 0.1778 0.2794)
							(mid 0.249642 0.249642)
							(end 0.2794 0.1778)
						)
						(arc
							(start 0.2794 -0.1778)
							(mid 0.249642 -0.249642)
							(end 0.1778 -0.2794)
						)
					)
					(width 0)
					(fill yes)
				)
			)
		)
	)
	(footprint ""
		(layer "F.Cu")
		(at 346.075 -214.376)
		(property "Reference" "R316"
			(at 0 0 0)
			(layer "F.SilkS")
			(hide yes)
			(effects
				(font
					(size 1.27 1.27)
				)
			)
		)
		(property "Value" "130R3F-GP"
			(at -0.0254 -2.5146 0)
			(unlocked yes)
			(layer "F.Fab")
			(hide yes)
			(effects
				(font
					(size 1.016 1.016)
					(thickness 0.1524)
				)
			)
		)
		(property "Device Type" "R603H22"
			(at -0.0254 -4.0386 0)
			(unlocked yes)
			(layer "F.Fab")
			(hide yes)
			(effects
				(font
					(size 1.016 1.016)
					(thickness 0.1524)
				)
			)
		)
		(duplicate_pad_numbers_are_jumpers no)
		(fp_line
			(start -0.4826 0)
			(end -0.2032 0)
			(stroke
				(width 0.2032)
				(type default)
			)
			(layer "F.SilkS")
		)
		(fp_line
			(start 0.2032 0)
			(end 0.4826 0)
			(stroke
				(width 0.2032)
				(type default)
			)
			(layer "F.SilkS")
		)
		(fp_rect
			(start -0.5842 1.3335)
			(end 0.5842 -1.3335)
			(stroke
				(width 0)
				(type default)
			)
			(fill no)
			(layer "F.CrtYd")
		)
		(fp_rect
			(start -0.5842 1.3335)
			(end 0.5842 -1.3335)
			(stroke
				(width 0)
				(type default)
			)
			(fill no)
			(layer "F.Fab")
		)
		(pad "1" smd custom
			(at 0 -0.762)
			(size 0.2159 0.2159)
			(layers "F.Cu" "F.Mask" "F.Paste")
			(net "P5V_B_3")
			(options
				(clearance outline)
				(anchor circle)
			)
			(primitives
				(gr_poly
					(pts
						(arc
							(start -0.3302 -0.4318)
							(mid -0.402042 -0.402042)
							(end -0.4318 -0.3302)
						)
						(arc
							(start -0.4318 0.3302)
							(mid -0.402042 0.402042)
							(end -0.3302 0.4318)
						)
						(arc
							(start 0.3302 0.4318)
							(mid 0.402042 0.402042)
							(end 0.4318 0.3302)
						)
						(arc
							(start 0.4318 -0.3302)
							(mid 0.402042 -0.402042)
							(end 0.3302 -0.4318)
						)
					)
					(width 0)
					(fill yes)
				)
			)
		)
		(pad "2" smd custom
			(at 0 0.762)
			(size 0.2159 0.2159)
			(layers "F.Cu" "F.Mask" "F.Paste")
			(net "FLT_HDD7")
			(options
				(clearance outline)
				(anchor circle)
			)
			(primitives
				(gr_poly
					(pts
						(arc
							(start -0.3302 -0.4318)
							(mid -0.402042 -0.402042)
							(end -0.4318 -0.3302)
						)
						(arc
							(start -0.4318 0.3302)
							(mid -0.402042 0.402042)
							(end -0.3302 0.4318)
						)
						(arc
							(start 0.3302 0.4318)
							(mid 0.402042 0.402042)
							(end 0.4318 0.3302)
						)
						(arc
							(start 0.4318 -0.3302)
							(mid 0.402042 -0.402042)
							(end 0.3302 -0.4318)
						)
					)
					(width 0)
					(fill yes)
				)
			)
		)
	)
	(footprint ""
		(layer "F.Cu")
		(at 33.3248 -63.799974)
		(property "Reference" ""
			(at 0 0 0)
			(layer "F.SilkS")
			(hide yes)
			(effects
				(font
					(size 1.27 1.27)
				)
			)
		)
		(property "Value" "*"
			(at -8.398764 -8.057642 0)
			(unlocked yes)
			(layer "F.Fab")
			(hide yes)
			(effects
				(font
					(size 1.016 1.016)
					(thickness 0.1524)
				)
			)
		)
		(duplicate_pad_numbers_are_jumpers no)
		(fp_poly
			(pts
				(arc
					(start 7.3152 0)
					(mid 0 7.3152)
					(end -7.3152 0)
				)
				(arc
					(start -7.3152 -5.9944)
					(mid 0 -13.3096)
					(end 7.3152 -5.9944)
				)
			)
			(stroke
				(width 0)
				(type default)
			)
			(fill no)
			(layer "B.CrtYd")
		)
		(fp_poly
			(pts
				(arc
					(start 7.3152 0)
					(mid 0 7.3152)
					(end -7.3152 0)
				)
				(arc
					(start -7.3152 -5.9944)
					(mid 0 -13.3096)
					(end 7.3152 -5.9944)
				)
			)
			(stroke
				(width 0)
				(type default)
			)
			(fill no)
			(layer "F.CrtYd")
		)
		(fp_poly
			(pts
				(arc
					(start 7.3152 0)
					(mid 0 7.3152)
					(end -7.3152 0)
				)
				(arc
					(start -7.3152 -5.9944)
					(mid 0 -13.3096)
					(end 7.3152 -5.9944)
				)
			)
			(stroke
				(width 0)
				(type default)
			)
			(fill no)
			(layer "B.Fab")
		)
		(fp_poly
			(pts
				(arc
					(start 7.3152 0)
					(mid 0 7.3152)
					(end -7.3152 0)
				)
				(arc
					(start -7.3152 -5.9944)
					(mid 0 -13.3096)
					(end 7.3152 -5.9944)
				)
			)
			(stroke
				(width 0)
				(type default)
			)
			(fill no)
			(layer "F.Fab")
		)
		(pad "1" thru_hole oval
			(at 0 0)
			(size 14.0208 20.0152)
			(drill 0.0254
				(offset 0 -2.9972)
			)
			(layers "*.Cu" "*.Mask")
			(remove_unused_layers no)
			(net "Net_11")
			(clearance -1.002284)
			(thermal_gap 0.1524)
			(padstack
				(mode front_inner_back)
				(layer "Inner"
					(shape custom)
					(size 2.928012 2.928012)
					(options
						(anchor circle)
					)
					(primitives
						(gr_poly
							(pts
								(arc
									(start 4.571746 -2.084324)
									(mid 0.000333 7.430372)
									(end -4.571492 -2.084324)
								)
								(arc
									(start -4.571492 -2.084324)
									(mid -3.570296 -3.611977)
									(end -2.875026 -5.30098)
								)
								(arc
									(start -2.875026 -5.30098)
									(mid 0.000217 -7.43089)
									(end 2.87528 -5.30098)
								)
								(arc
									(start 2.87528 -5.30098)
									(mid 3.570511 -3.611956)
									(end 4.571746 -2.084324)
								)
							)
							(width 0)
							(fill yes)
						)
					)
					(clearance 0.1524)
				)
				(layer "B.Cu"
					(shape oval)
					(size 14.0208 20.0152)
					(offset 0 -2.9972)
					(clearance -1.002284)
				)
			)
		)
		(zone
			(layers "F.Cu" "B.Cu" "In1.Cu" "In2.Cu" "In3.Cu" "In4.Cu" "In5.Cu" "In6.Cu")
			(hatch none 0.5)
			(connect_pads
				(clearance 0)
			)
			(min_thickness 0.25)
			(keepout
				(tracks not_allowed)
				(vias allowed)
				(pads allowed)
				(copperpour not_allowed)
				(footprints allowed)
			)
			(placement
				(enabled no)
				(sheetname "")
			)
			(fill
				(thermal_gap 0.5)
				(thermal_bridge_width 0.5)
				(island_removal_mode 0)
			)
			(polygon
				(pts
					(arc
						(start 26.3144 -69.794374)
						(mid 33.3248 -76.804774)
						(end 40.3352 -69.794374)
					)
					(arc
						(start 40.3352 -63.799974)
						(mid 33.3248 -56.789574)
						(end 26.3144 -63.799974)
					)
				)
			)
		)
	)
	(footprint ""
		(layer "F.Cu")
		(at 445.415924 -154.70505)
		(property "Reference" "TP131"
			(at 0 0 0)
			(layer "F.SilkS")
			(hide yes)
			(effects
				(font
					(size 1.27 1.27)
				)
			)
		)
		(property "Value" "*"
			(at -0.0508 -1.6764 0)
			(unlocked yes)
			(layer "F.Fab")
			(hide yes)
			(effects
				(font
					(size 1.016 1.016)
					(thickness 0.1524)
				)
			)
		)
		(property "Device Type" "TPAD32"
			(at -0.0508 -3.2004 0)
			(unlocked yes)
			(layer "F.Fab")
			(hide yes)
			(effects
				(font
					(size 1.016 1.016)
					(thickness 0.1524)
				)
			)
		)
		(duplicate_pad_numbers_are_jumpers no)
		(fp_poly
			(pts
				(arc
					(start 0.4064 0)
					(mid -0.4064 0)
					(end 0.4064 0)
				)
			)
			(stroke
				(width 0)
				(type default)
			)
			(fill no)
			(layer "F.CrtYd")
		)
		(fp_poly
			(pts
				(arc
					(start 0.7112 0)
					(mid -0.7112 0)
					(end 0.7112 0)
				)
			)
			(stroke
				(width 0)
				(type default)
			)
			(fill no)
			(layer "F.Fab")
		)
		(pad "1" smd circle
			(at 0 0)
			(size 0.8128 0.8128)
			(layers "F.Cu" "F.Mask" "F.Paste")
			(net "ACT_HDD_22")
		)
	)
	(footprint ""
		(layer "F.Cu")
		(at 150.114 -272.288)
		(property "Reference" "C87"
			(at 0 0 0)
			(layer "F.SilkS")
			(hide yes)
			(effects
				(font
					(size 1.27 1.27)
				)
			)
		)
		(property "Value" "SC4D7U25V5KX-1-GP"
			(at -0.0762 -6.1214 0)
			(unlocked yes)
			(layer "F.Fab")
			(hide yes)
			(effects
				(font
					(size 1.016 1.016)
					(thickness 0.1524)
				)
			)
		)
		(property "Device Type" "C805H58"
			(at -0.0762 -8.1534 0)
			(unlocked yes)
			(layer "F.Fab")
			(hide yes)
			(effects
				(font
					(size 1.016 1.016)
					(thickness 0.1524)
				)
			)
		)
		(duplicate_pad_numbers_are_jumpers no)
		(fp_line
			(start 0.635 0)
			(end -0.635 0)
			(stroke
				(width 0.508)
				(type default)
			)
			(layer "F.SilkS")
		)
		(fp_rect
			(start -0.9652 1.778)
			(end 0.9652 -1.778)
			(stroke
				(width 0)
				(type default)
			)
			(fill no)
			(layer "F.CrtYd")
		)
		(fp_poly
			(pts
				(xy -0.9652 -1.778) (xy 0.9652 -1.778) (xy 0.9652 1.778) (xy -0.9652 1.778)
			)
			(stroke
				(width 0)
				(type default)
			)
			(fill no)
			(layer "F.Fab")
		)
		(pad "1" smd rect
			(at 0 -0.9652)
			(size 1.397 1.143)
			(layers "F.Cu" "F.Mask" "F.Paste")
			(net "P12V_HDD4")
		)
		(pad "2" smd rect
			(at 0 0.9652)
			(size 1.397 1.143)
			(layers "F.Cu" "F.Mask" "F.Paste")
			(net "GND")
		)
	)
	(footprint ""
		(layer "F.Cu")
		(at 349.7834 -146.3548)
		(property "Reference" "R511"
			(at 0 0 0)
			(layer "F.SilkS")
			(hide yes)
			(effects
				(font
					(size 1.27 1.27)
				)
			)
		)
		(property "Value" "220R3F-1-GP"
			(at -0.0254 -2.5146 0)
			(unlocked yes)
			(layer "F.Fab")
			(hide yes)
			(effects
				(font
					(size 1.016 1.016)
					(thickness 0.1524)
				)
			)
		)
		(property "Device Type" "R603H22"
			(at -0.0254 -4.0386 0)
			(unlocked yes)
			(layer "F.Fab")
			(hide yes)
			(effects
				(font
					(size 1.016 1.016)
					(thickness 0.1524)
				)
			)
		)
		(duplicate_pad_numbers_are_jumpers no)
		(fp_line
			(start -0.4826 0)
			(end -0.2032 0)
			(stroke
				(width 0.2032)
				(type default)
			)
			(layer "F.SilkS")
		)
		(fp_line
			(start 0.2032 0)
			(end 0.4826 0)
			(stroke
				(width 0.2032)
				(type default)
			)
			(layer "F.SilkS")
		)
		(fp_rect
			(start -0.5842 1.3335)
			(end 0.5842 -1.3335)
			(stroke
				(width 0)
				(type default)
			)
			(fill no)
			(layer "F.CrtYd")
		)
		(fp_rect
			(start -0.5842 1.3335)
			(end 0.5842 -1.3335)
			(stroke
				(width 0)
				(type default)
			)
			(fill no)
			(layer "F.Fab")
		)
		(pad "1" smd custom
			(at 0 -0.762)
			(size 0.2159 0.2159)
			(layers "F.Cu" "F.Mask" "F.Paste")
			(net "HDD_PRSNT_19")
			(options
				(clearance outline)
				(anchor circle)
			)
			(primitives
				(gr_poly
					(pts
						(arc
							(start -0.3302 -0.4318)
							(mid -0.402042 -0.402042)
							(end -0.4318 -0.3302)
						)
						(arc
							(start -0.4318 0.3302)
							(mid -0.402042 0.402042)
							(end -0.3302 0.4318)
						)
						(arc
							(start 0.3302 0.4318)
							(mid 0.402042 0.402042)
							(end 0.4318 0.3302)
						)
						(arc
							(start 0.4318 -0.3302)
							(mid 0.402042 -0.402042)
							(end 0.3302 -0.4318)
						)
					)
					(width 0)
					(fill yes)
				)
			)
		)
		(pad "2" smd custom
			(at 0 0.762)
			(size 0.2159 0.2159)
			(layers "F.Cu" "F.Mask" "F.Paste")
			(net "DRIVE_B_19_INS")
			(options
				(clearance outline)
				(anchor circle)
			)
			(primitives
				(gr_poly
					(pts
						(arc
							(start -0.3302 -0.4318)
							(mid -0.402042 -0.402042)
							(end -0.4318 -0.3302)
						)
						(arc
							(start -0.4318 0.3302)
							(mid -0.402042 0.402042)
							(end -0.3302 0.4318)
						)
						(arc
							(start 0.3302 0.4318)
							(mid 0.402042 0.402042)
							(end 0.4318 0.3302)
						)
						(arc
							(start 0.4318 -0.3302)
							(mid 0.402042 -0.402042)
							(end 0.3302 -0.4318)
						)
					)
					(width 0)
					(fill yes)
				)
			)
		)
	)
	(footprint ""
		(layer "F.Cu")
		(at 48.387 -132.588 180)
		(property "Reference" "D13"
			(at 0 0 180)
			(layer "F.SilkS")
			(hide yes)
			(effects
				(font
					(size 1.27 1.27)
				)
			)
		)
		(property "Value" "RB551V30-GP"
			(at 0 -6.7818 180)
			(unlocked yes)
			(layer "F.Fab")
			(hide yes)
			(effects
				(font
					(size 1.016 1.016)
					(thickness 0.1524)
				)
			)
		)
		(property "Device Type" "SOD323AKH38"
			(at 0 -8.6868 180)
			(unlocked yes)
			(layer "F.Fab")
			(hide yes)
			(effects
				(font
					(size 1.016 1.016)
					(thickness 0.1524)
				)
			)
		)
		(duplicate_pad_numbers_are_jumpers no)
		(fp_line
			(start 0.889 2.159)
			(end -0.889 2.159)
			(stroke
				(width 0.1524)
				(type default)
			)
			(layer "F.SilkS")
		)
		(fp_line
			(start 0.889 -1.9304)
			(end 0.889 2.159)
			(stroke
				(width 0.1524)
				(type default)
			)
			(layer "F.SilkS")
		)
		(fp_line
			(start 0.762 2.0574)
			(end -0.762 2.0574)
			(stroke
				(width 0.508)
				(type default)
			)
			(layer "F.SilkS")
		)
		(fp_line
			(start -0.889 2.159)
			(end -0.889 -1.9304)
			(stroke
				(width 0.1524)
				(type default)
			)
			(layer "F.SilkS")
		)
		(fp_line
			(start -0.889 -1.9304)
			(end 0.889 -1.9304)
			(stroke
				(width 0.1524)
				(type default)
			)
			(layer "F.SilkS")
		)
		(fp_rect
			(start -1.016 2.3114)
			(end 1.016 -2.0066)
			(stroke
				(width 0)
				(type default)
			)
			(fill no)
			(layer "F.CrtYd")
		)
		(fp_poly
			(pts
				(xy -1.016 -2.0066) (xy 1.016 -2.0066) (xy 1.016 2.3114) (xy -1.016 2.3114)
			)
			(stroke
				(width 0)
				(type default)
			)
			(fill no)
			(layer "F.Fab")
		)
		(pad "A" smd rect
			(at 0 -1.143 180)
			(size 0.5588 1.016)
			(layers "F.Cu" "F.Mask" "F.Paste")
			(net "SW_HDD_R13")
		)
		(pad "K" smd rect
			(at 0 1.143 180)
			(size 0.5588 1.016)
			(layers "F.Cu" "F.Mask" "F.Paste")
			(net "SW_HDD_N13")
		)
	)
	(footprint ""
		(layer "F.Cu")
		(at 20.500086 -377.219972 180)
		(property "Reference" "FLED1"
			(at 0 0 180)
			(layer "F.SilkS")
			(hide yes)
			(effects
				(font
					(size 1.27 1.27)
				)
			)
		)
		(property "Value" "LED-BY-14-GP"
			(at -4.7752 -2.1844 180)
			(unlocked yes)
			(layer "F.Fab")
			(hide yes)
			(effects
				(font
					(size 1.016 1.016)
					(thickness 0.1524)
				)
			)
		)
		(property "Device Type" "LED-100-3PH206"
			(at -4.7752 -3.7084 180)
			(unlocked yes)
			(layer "F.Fab")
			(hide yes)
			(effects
				(font
					(size 1.016 1.016)
					(thickness 0.1524)
				)
			)
		)
		(duplicate_pad_numbers_are_jumpers no)
		(fp_line
			(start 3.7592 8.0264)
			(end -3.7592 8.0264)
			(stroke
				(width 0.1524)
				(type default)
			)
			(layer "F.SilkS")
		)
		(fp_line
			(start 3.7592 -1.524)
			(end 3.7592 8.0264)
			(stroke
				(width 0.1524)
				(type default)
			)
			(layer "F.SilkS")
		)
		(fp_line
			(start 1.87833 3.63474)
			(end 0.58293 2.33934)
			(stroke
				(width 0.1524)
				(type default)
			)
			(layer "F.SilkS")
		)
		(fp_line
			(start 1.87833 2.33934)
			(end 2.81813 2.33934)
			(stroke
				(width 0.1524)
				(type default)
			)
			(layer "F.SilkS")
		)
		(fp_line
			(start 1.87833 1.04394)
			(end 1.87833 3.63474)
			(stroke
				(width 0.1524)
				(type default)
			)
			(layer "F.SilkS")
		)
		(fp_line
			(start 0.58293 3.05054)
			(end 0.58293 1.42494)
			(stroke
				(width 0.1524)
				(type default)
			)
			(layer "F.SilkS")
		)
		(fp_line
			(start 0.58293 2.33934)
			(end 1.87833 1.04394)
			(stroke
				(width 0.1524)
				(type default)
			)
			(layer "F.SilkS")
		)
		(fp_line
			(start -0.45847 3.05054)
			(end -0.45847 1.42494)
			(stroke
				(width 0.1524)
				(type default)
			)
			(layer "F.SilkS")
		)
		(fp_line
			(start -0.45847 2.33934)
			(end 0.58293 2.33934)
			(stroke
				(width 0.1524)
				(type default)
			)
			(layer "F.SilkS")
		)
		(fp_line
			(start -0.45847 2.33934)
			(end -1.75387 1.04394)
			(stroke
				(width 0.1524)
				(type default)
			)
			(layer "F.SilkS")
		)
		(fp_line
			(start -1.75387 3.63474)
			(end -0.45847 2.33934)
			(stroke
				(width 0.1524)
				(type default)
			)
			(layer "F.SilkS")
		)
		(fp_line
			(start -1.75387 2.33934)
			(end -3.45567 2.33934)
			(stroke
				(width 0.1524)
				(type default)
			)
			(layer "F.SilkS")
		)
		(fp_line
			(start -1.75387 1.04394)
			(end -1.75387 3.63474)
			(stroke
				(width 0.1524)
				(type default)
			)
			(layer "F.SilkS")
		)
		(fp_line
			(start -3.7592 8.0264)
			(end -3.7592 -1.524)
			(stroke
				(width 0.1524)
				(type default)
			)
			(layer "F.SilkS")
		)
		(fp_line
			(start -3.7592 -1.524)
			(end 3.7592 -1.524)
			(stroke
				(width 0.1524)
				(type default)
			)
			(layer "F.SilkS")
		)
		(fp_circle
			(center 2.54 0)
			(end 1.5494 0)
			(stroke
				(width 0.3048)
				(type default)
			)
			(fill no)
			(layer "F.SilkS")
		)
		(fp_circle
			(center 0 0)
			(end -0.9906 0)
			(stroke
				(width 0.3048)
				(type default)
			)
			(fill no)
			(layer "F.SilkS")
		)
		(fp_circle
			(center -2.54 0)
			(end -3.5306 0)
			(stroke
				(width 0.3048)
				(type default)
			)
			(fill no)
			(layer "F.SilkS")
		)
		(fp_rect
			(start -3.5052 7.7724)
			(end 3.5052 -1.27)
			(stroke
				(width 0)
				(type default)
			)
			(fill no)
			(layer "F.CrtYd")
		)
		(fp_poly
			(pts
				(xy -4.0132 8.2804) (xy -4.0132 -1.778) (xy -3.5052 -1.778) (xy -3.5052 7.7724) (xy 3.5052 7.7724)
				(xy 3.5052 -1.27) (xy -3.50012 -1.27) (xy -3.50012 -1.778) (xy 4.0132 -1.778) (xy 4.0132 8.2804)
			)
			(stroke
				(width 0)
				(type default)
			)
			(fill no)
			(layer "F.CrtYd")
		)
		(fp_rect
			(start -4.0132 8.2804)
			(end 4.0132 -1.778)
			(stroke
				(width 0)
				(type default)
			)
			(fill no)
			(layer "F.Fab")
		)
		(pad "1" thru_hole circle
			(at -2.54 0 180)
			(size 1.27 1.27)
			(drill 0.889)
			(layers "*.Cu" "*.Mask")
			(remove_unused_layers no)
			(net "FAN_LED_BLUE0")
			(clearance 0.1651)
			(thermal_gap 0.1651)
		)
		(pad "2" thru_hole circle
			(at 0 0 180)
			(size 1.27 1.27)
			(drill 0.889)
			(layers "*.Cu" "*.Mask")
			(remove_unused_layers no)
			(net "GND")
			(clearance 0.1651)
			(thermal_gap 0.1651)
		)
		(pad "3" thru_hole circle
			(at 2.54 0 180)
			(size 1.27 1.27)
			(drill 0.889)
			(layers "*.Cu" "*.Mask")
			(remove_unused_layers no)
			(net "FAN_LED_YELLOW_0")
			(clearance 0.1651)
			(thermal_gap 0.1651)
		)
	)
	(footprint ""
		(layer "F.Cu")
		(at 117.5766 -248.412 -90)
		(property "Reference" "R212"
			(at 0 0 270)
			(layer "F.SilkS")
			(hide yes)
			(effects
				(font
					(size 1.27 1.27)
				)
			)
		)
		(property "Value" "1KR2F-3-GP"
			(at 0.064008 -3.993896 270)
			(unlocked yes)
			(layer "F.Fab")
			(hide yes)
			(effects
				(font
					(size 1.016 1.016)
					(thickness 0.1524)
				)
			)
		)
		(property "Device Type" "R402H16"
			(at 0.064008 -5.517896 270)
			(unlocked yes)
			(layer "F.Fab")
			(hide yes)
			(effects
				(font
					(size 1.016 1.016)
					(thickness 0.1524)
				)
			)
		)
		(duplicate_pad_numbers_are_jumpers no)
		(fp_line
			(start -0.508 -0.9398)
			(end -0.508 0.9398)
			(stroke
				(width 0.1524)
				(type default)
			)
			(layer "F.SilkS")
		)
		(fp_line
			(start 0.508 -0.9398)
			(end -0.508 -0.9398)
			(stroke
				(width 0.1524)
				(type default)
			)
			(layer "F.SilkS")
		)
		(fp_rect
			(start -0.508 0.9398)
			(end 0.508 -0.9398)
			(stroke
				(width 0)
				(type default)
			)
			(fill no)
			(layer "F.CrtYd")
		)
		(fp_rect
			(start -0.508 0.9398)
			(end 0.508 -0.9398)
			(stroke
				(width 0)
				(type default)
			)
			(fill no)
			(layer "F.Fab")
		)
		(pad "1" smd custom
			(at 0 -0.4445 270)
			(size 0.1397 0.1397)
			(layers "F.Cu" "F.Mask" "F.Paste")
			(net "P3V3_STBY_B")
			(options
				(clearance outline)
				(anchor circle)
			)
			(primitives
				(gr_poly
					(pts
						(arc
							(start -0.1778 -0.2794)
							(mid -0.249642 -0.249642)
							(end -0.2794 -0.1778)
						)
						(arc
							(start -0.2794 0.1778)
							(mid -0.249642 0.249642)
							(end -0.1778 0.2794)
						)
						(arc
							(start 0.1778 0.2794)
							(mid 0.249642 0.249642)
							(end 0.2794 0.1778)
						)
						(arc
							(start 0.2794 -0.1778)
							(mid 0.249642 -0.249642)
							(end 0.1778 -0.2794)
						)
					)
					(width 0)
					(fill yes)
				)
			)
		)
		(pad "2" smd custom
			(at 0 0.4445 270)
			(size 0.1397 0.1397)
			(layers "F.Cu" "F.Mask" "F.Paste")
			(net "SW_PWR_R_HDD3")
			(options
				(clearance outline)
				(anchor circle)
			)
			(primitives
				(gr_poly
					(pts
						(arc
							(start -0.1778 -0.2794)
							(mid -0.249642 -0.249642)
							(end -0.2794 -0.1778)
						)
						(arc
							(start -0.2794 0.1778)
							(mid -0.249642 0.249642)
							(end -0.1778 0.2794)
						)
						(arc
							(start 0.1778 0.2794)
							(mid 0.249642 0.249642)
							(end 0.2794 0.1778)
						)
						(arc
							(start 0.2794 -0.1778)
							(mid 0.249642 -0.249642)
							(end 0.1778 -0.2794)
						)
					)
					(width 0)
					(fill yes)
				)
			)
		)
	)
	(footprint ""
		(layer "F.Cu")
		(at 255.8796 -286.8422 90)
		(property "Reference" "R1173"
			(at 0 0 90)
			(layer "F.SilkS")
			(hide yes)
			(effects
				(font
					(size 1.27 1.27)
				)
			)
		)
		(property "Value" "2D2R3-1-U-GP"
			(at -0.0254 -2.5146 90)
			(unlocked yes)
			(layer "F.Fab")
			(hide yes)
			(effects
				(font
					(size 1.016 1.016)
					(thickness 0.1524)
				)
			)
		)
		(property "Device Type" "R603H22"
			(at -0.0254 -4.0386 90)
			(unlocked yes)
			(layer "F.Fab")
			(hide yes)
			(effects
				(font
					(size 1.016 1.016)
					(thickness 0.1524)
				)
			)
		)
		(duplicate_pad_numbers_are_jumpers no)
		(fp_line
			(start 0.2032 0)
			(end 0.4826 0)
			(stroke
				(width 0.2032)
				(type default)
			)
			(layer "F.SilkS")
		)
		(fp_line
			(start -0.4826 0)
			(end -0.2032 0)
			(stroke
				(width 0.2032)
				(type default)
			)
			(layer "F.SilkS")
		)
		(fp_rect
			(start -0.5842 1.3335)
			(end 0.5842 -1.3335)
			(stroke
				(width 0)
				(type default)
			)
			(fill no)
			(layer "F.CrtYd")
		)
		(fp_rect
			(start -0.5842 1.3335)
			(end 0.5842 -1.3335)
			(stroke
				(width 0)
				(type default)
			)
			(fill no)
			(layer "F.Fab")
		)
		(pad "1" smd custom
			(at 0 -0.762 90)
			(size 0.2159 0.2159)
			(layers "F.Cu" "F.Mask" "F.Paste")
			(net "P3V3_STBY_VCC")
			(options
				(clearance outline)
				(anchor circle)
			)
			(primitives
				(gr_poly
					(pts
						(arc
							(start -0.3302 -0.4318)
							(mid -0.402042 -0.402042)
							(end -0.4318 -0.3302)
						)
						(arc
							(start -0.4318 0.3302)
							(mid -0.402042 0.402042)
							(end -0.3302 0.4318)
						)
						(arc
							(start 0.3302 0.4318)
							(mid 0.402042 0.402042)
							(end 0.4318 0.3302)
						)
						(arc
							(start 0.4318 -0.3302)
							(mid 0.402042 -0.402042)
							(end 0.3302 -0.4318)
						)
					)
					(width 0)
					(fill yes)
				)
			)
		)
		(pad "2" smd custom
			(at 0 0.762 90)
			(size 0.2159 0.2159)
			(layers "F.Cu" "F.Mask" "F.Paste")
			(net "P12V_B")
			(options
				(clearance outline)
				(anchor circle)
			)
			(primitives
				(gr_poly
					(pts
						(arc
							(start -0.3302 -0.4318)
							(mid -0.402042 -0.402042)
							(end -0.4318 -0.3302)
						)
						(arc
							(start -0.4318 0.3302)
							(mid -0.402042 0.402042)
							(end -0.3302 0.4318)
						)
						(arc
							(start 0.3302 0.4318)
							(mid 0.402042 0.402042)
							(end 0.4318 0.3302)
						)
						(arc
							(start 0.4318 -0.3302)
							(mid 0.402042 -0.402042)
							(end 0.3302 -0.4318)
						)
					)
					(width 0)
					(fill yes)
				)
			)
		)
	)
	(footprint ""
		(layer "F.Cu")
		(at 473.583 -19.812 -90)
		(property "Reference" "R882"
			(at 0 0 270)
			(layer "F.SilkS")
			(hide yes)
			(effects
				(font
					(size 1.27 1.27)
				)
			)
		)
		(property "Value" "4K7R2J-2-GP"
			(at 0.064008 -3.993896 270)
			(unlocked yes)
			(layer "F.Fab")
			(hide yes)
			(effects
				(font
					(size 1.016 1.016)
					(thickness 0.1524)
				)
			)
		)
		(property "Device Type" "R402H16"
			(at 0.064008 -5.517896 270)
			(unlocked yes)
			(layer "F.Fab")
			(hide yes)
			(effects
				(font
					(size 1.016 1.016)
					(thickness 0.1524)
				)
			)
		)
		(duplicate_pad_numbers_are_jumpers no)
		(fp_line
			(start -0.508 -0.9398)
			(end -0.508 0.9398)
			(stroke
				(width 0.1524)
				(type default)
			)
			(layer "F.SilkS")
		)
		(fp_line
			(start 0.508 -0.9398)
			(end -0.508 -0.9398)
			(stroke
				(width 0.1524)
				(type default)
			)
			(layer "F.SilkS")
		)
		(fp_rect
			(start -0.508 0.9398)
			(end 0.508 -0.9398)
			(stroke
				(width 0)
				(type default)
			)
			(fill no)
			(layer "F.CrtYd")
		)
		(fp_rect
			(start -0.508 0.9398)
			(end 0.508 -0.9398)
			(stroke
				(width 0)
				(type default)
			)
			(fill no)
			(layer "F.Fab")
		)
		(pad "1" smd custom
			(at 0 -0.4445 270)
			(size 0.1397 0.1397)
			(layers "F.Cu" "F.Mask" "F.Paste")
			(net "P12V_B")
			(options
				(clearance outline)
				(anchor circle)
			)
			(primitives
				(gr_poly
					(pts
						(arc
							(start -0.1778 -0.2794)
							(mid -0.249642 -0.249642)
							(end -0.2794 -0.1778)
						)
						(arc
							(start -0.2794 0.1778)
							(mid -0.249642 0.249642)
							(end -0.1778 0.2794)
						)
						(arc
							(start 0.1778 0.2794)
							(mid 0.249642 0.249642)
							(end 0.2794 0.1778)
						)
						(arc
							(start 0.2794 -0.1778)
							(mid 0.249642 -0.249642)
							(end 0.1778 -0.2794)
						)
					)
					(width 0)
					(fill yes)
				)
			)
		)
		(pad "2" smd custom
			(at 0 0.4445 270)
			(size 0.1397 0.1397)
			(layers "F.Cu" "F.Mask" "F.Paste")
			(net "SW_HDD_P35")
			(options
				(clearance outline)
				(anchor circle)
			)
			(primitives
				(gr_poly
					(pts
						(arc
							(start -0.1778 -0.2794)
							(mid -0.249642 -0.249642)
							(end -0.2794 -0.1778)
						)
						(arc
							(start -0.2794 0.1778)
							(mid -0.249642 0.249642)
							(end -0.1778 0.2794)
						)
						(arc
							(start 0.1778 0.2794)
							(mid 0.249642 0.249642)
							(end 0.2794 0.1778)
						)
						(arc
							(start 0.2794 -0.1778)
							(mid 0.249642 -0.249642)
							(end 0.1778 -0.2794)
						)
					)
					(width 0)
					(fill yes)
				)
			)
		)
	)
	(footprint ""
		(layer "F.Cu")
		(at 384.734562 -245.219474 -90)
		(property "Reference" "C132"
			(at 0 0 270)
			(layer "F.SilkS")
			(hide yes)
			(effects
				(font
					(size 1.27 1.27)
				)
			)
		)
		(property "Value" "SCD01U16V1KX-GP"
			(at -2.8321 -1.7399 270)
			(unlocked yes)
			(layer "F.Fab")
			(hide yes)
			(effects
				(font
					(size 1.016 1.016)
					(thickness 0.1524)
				)
			)
		)
		(property "Device Type" "C0201H13"
			(at -2.8321 -3.2639 270)
			(unlocked yes)
			(layer "F.Fab")
			(hide yes)
			(effects
				(font
					(size 1.016 1.016)
					(thickness 0.1524)
				)
			)
		)
		(duplicate_pad_numbers_are_jumpers no)
		(fp_rect
			(start -0.2794 0.6477)
			(end 0.2794 -0.6477)
			(stroke
				(width 0)
				(type default)
			)
			(fill no)
			(layer "F.CrtYd")
		)
		(fp_rect
			(start -0.2794 0.6477)
			(end 0.2794 -0.6477)
			(stroke
				(width 0)
				(type default)
			)
			(fill no)
			(layer "F.Fab")
		)
		(pad "1" smd custom
			(at 0 -0.2794 270)
			(size 0.0762 0.0762)
			(layers "F.Cu" "F.Mask" "F.Paste")
			(net "SAS_HDD_RX_N8")
			(options
				(clearance outline)
				(anchor circle)
			)
			(primitives
				(gr_poly
					(pts
						(arc
							(start 0.1524 -0.127)
							(mid 0.137521 -0.162921)
							(end 0.1016 -0.1778)
						)
						(arc
							(start -0.1016 -0.1778)
							(mid -0.137521 -0.162921)
							(end -0.1524 -0.127)
						)
						(arc
							(start -0.1524 0.127)
							(mid -0.137521 0.162921)
							(end -0.1016 0.1778)
						)
						(arc
							(start 0.1016 0.1778)
							(mid 0.137521 0.162921)
							(end 0.1524 0.127)
						)
					)
					(width 0)
					(fill yes)
				)
			)
		)
		(pad "2" smd custom
			(at 0 0.2794 270)
			(size 0.0762 0.0762)
			(layers "F.Cu" "F.Mask" "F.Paste")
			(net "PHY_SCC_B_TO_DRV_B_8_DN")
			(options
				(clearance outline)
				(anchor circle)
			)
			(primitives
				(gr_poly
					(pts
						(arc
							(start 0.1524 -0.127)
							(mid 0.137521 -0.162921)
							(end 0.1016 -0.1778)
						)
						(arc
							(start -0.1016 -0.1778)
							(mid -0.137521 -0.162921)
							(end -0.1524 -0.127)
						)
						(arc
							(start -0.1524 0.127)
							(mid -0.137521 0.162921)
							(end -0.1016 0.1778)
						)
						(arc
							(start 0.1016 0.1778)
							(mid 0.137521 0.162921)
							(end 0.1524 0.127)
						)
					)
					(width 0)
					(fill yes)
				)
			)
		)
	)
	(footprint ""
		(layer "F.Cu")
		(at 22.987 -134.493 90)
		(property "Reference" "R359"
			(at 0 0 90)
			(layer "F.SilkS")
			(hide yes)
			(effects
				(font
					(size 1.27 1.27)
				)
			)
		)
		(property "Value" "4K7R2F-GP"
			(at 0.064008 -3.993896 90)
			(unlocked yes)
			(layer "F.Fab")
			(hide yes)
			(effects
				(font
					(size 1.016 1.016)
					(thickness 0.1524)
				)
			)
		)
		(property "Device Type" "R402H16"
			(at 0.064008 -5.517896 90)
			(unlocked yes)
			(layer "F.Fab")
			(hide yes)
			(effects
				(font
					(size 1.016 1.016)
					(thickness 0.1524)
				)
			)
		)
		(duplicate_pad_numbers_are_jumpers no)
		(fp_line
			(start 0.508 -0.9398)
			(end -0.508 -0.9398)
			(stroke
				(width 0.1524)
				(type default)
			)
			(layer "F.SilkS")
		)
		(fp_line
			(start -0.508 -0.9398)
			(end -0.508 0.9398)
			(stroke
				(width 0.1524)
				(type default)
			)
			(layer "F.SilkS")
		)
		(fp_rect
			(start -0.508 0.9398)
			(end 0.508 -0.9398)
			(stroke
				(width 0)
				(type default)
			)
			(fill no)
			(layer "F.CrtYd")
		)
		(fp_rect
			(start -0.508 0.9398)
			(end 0.508 -0.9398)
			(stroke
				(width 0)
				(type default)
			)
			(fill no)
			(layer "F.Fab")
		)
		(pad "1" smd custom
			(at 0 -0.4445 90)
			(size 0.1397 0.1397)
			(layers "F.Cu" "F.Mask" "F.Paste")
			(net "SW_PWR_R_HDD12")
			(options
				(clearance outline)
				(anchor circle)
			)
			(primitives
				(gr_poly
					(pts
						(arc
							(start -0.1778 -0.2794)
							(mid -0.249642 -0.249642)
							(end -0.2794 -0.1778)
						)
						(arc
							(start -0.2794 0.1778)
							(mid -0.249642 0.249642)
							(end -0.1778 0.2794)
						)
						(arc
							(start 0.1778 0.2794)
							(mid 0.249642 0.249642)
							(end 0.2794 0.1778)
						)
						(arc
							(start 0.2794 -0.1778)
							(mid 0.249642 -0.249642)
							(end 0.1778 -0.2794)
						)
					)
					(width 0)
					(fill yes)
				)
			)
		)
		(pad "2" smd custom
			(at 0 0.4445 90)
			(size 0.1397 0.1397)
			(layers "F.Cu" "F.Mask" "F.Paste")
			(net "GND")
			(options
				(clearance outline)
				(anchor circle)
			)
			(primitives
				(gr_poly
					(pts
						(arc
							(start -0.1778 -0.2794)
							(mid -0.249642 -0.249642)
							(end -0.2794 -0.1778)
						)
						(arc
							(start -0.2794 0.1778)
							(mid -0.249642 0.249642)
							(end -0.1778 0.2794)
						)
						(arc
							(start 0.1778 0.2794)
							(mid 0.249642 0.249642)
							(end 0.2794 0.1778)
						)
						(arc
							(start 0.2794 -0.1778)
							(mid 0.249642 -0.249642)
							(end 0.1778 -0.2794)
						)
					)
					(width 0)
					(fill yes)
				)
			)
		)
	)
	(footprint ""
		(layer "F.Cu")
		(at 167.7162 -370.205 90)
		(property "Reference" "R1058"
			(at 0 0 90)
			(layer "F.SilkS")
			(hide yes)
			(effects
				(font
					(size 1.27 1.27)
				)
			)
		)
		(property "Value" "10R2F-L-GP"
			(at 0.064008 -3.993896 90)
			(unlocked yes)
			(layer "F.Fab")
			(hide yes)
			(effects
				(font
					(size 1.016 1.016)
					(thickness 0.1524)
				)
			)
		)
		(property "Device Type" "R402H14"
			(at 0.064008 -5.517896 90)
			(unlocked yes)
			(layer "F.Fab")
			(hide yes)
			(effects
				(font
					(size 1.016 1.016)
					(thickness 0.1524)
				)
			)
		)
		(duplicate_pad_numbers_are_jumpers no)
		(fp_line
			(start 0.508 -0.9398)
			(end -0.508 -0.9398)
			(stroke
				(width 0.1524)
				(type default)
			)
			(layer "F.SilkS")
		)
		(fp_line
			(start -0.508 -0.9398)
			(end -0.508 0.9398)
			(stroke
				(width 0.1524)
				(type default)
			)
			(layer "F.SilkS")
		)
		(fp_rect
			(start -0.508 0.9398)
			(end 0.508 -0.9398)
			(stroke
				(width 0)
				(type default)
			)
			(fill no)
			(layer "F.CrtYd")
		)
		(fp_rect
			(start -0.508 0.9398)
			(end 0.508 -0.9398)
			(stroke
				(width 0)
				(type default)
			)
			(fill no)
			(layer "F.Fab")
		)
		(pad "1" smd custom
			(at 0 -0.4445 90)
			(size 0.1397 0.1397)
			(layers "F.Cu" "F.Mask" "F.Paste")
			(net "MB0_CM_SENSE_R2_N")
			(options
				(clearance outline)
				(anchor circle)
			)
			(primitives
				(gr_poly
					(pts
						(arc
							(start -0.1778 -0.2794)
							(mid -0.249642 -0.249642)
							(end -0.2794 -0.1778)
						)
						(arc
							(start -0.2794 0.1778)
							(mid -0.249642 0.249642)
							(end -0.1778 0.2794)
						)
						(arc
							(start 0.1778 0.2794)
							(mid 0.249642 0.249642)
							(end 0.2794 0.1778)
						)
						(arc
							(start 0.2794 -0.1778)
							(mid 0.249642 -0.249642)
							(end 0.1778 -0.2794)
						)
					)
					(width 0)
					(fill yes)
				)
			)
		)
		(pad "2" smd custom
			(at 0 0.4445 90)
			(size 0.1397 0.1397)
			(layers "F.Cu" "F.Mask" "F.Paste")
			(net "MB0_HS_SENSE_N")
			(options
				(clearance outline)
				(anchor circle)
			)
			(primitives
				(gr_poly
					(pts
						(arc
							(start -0.1778 -0.2794)
							(mid -0.249642 -0.249642)
							(end -0.2794 -0.1778)
						)
						(arc
							(start -0.2794 0.1778)
							(mid -0.249642 0.249642)
							(end -0.1778 0.2794)
						)
						(arc
							(start 0.1778 0.2794)
							(mid 0.249642 0.249642)
							(end 0.2794 0.1778)
						)
						(arc
							(start 0.2794 -0.1778)
							(mid 0.249642 -0.249642)
							(end 0.1778 -0.2794)
						)
					)
					(width 0)
					(fill yes)
				)
			)
		)
	)
	(footprint ""
		(layer "F.Cu")
		(at 396.6972 -155.6004 -90)
		(property "Reference" "R531"
			(at 0 0 270)
			(layer "F.SilkS")
			(hide yes)
			(effects
				(font
					(size 1.27 1.27)
				)
			)
		)
		(property "Value" "2R6F-GP"
			(at -0.0508 -4.8514 270)
			(unlocked yes)
			(layer "F.Fab")
			(hide yes)
			(effects
				(font
					(size 1.016 1.016)
					(thickness 0.1524)
				)
			)
		)
		(property "Device Type" "R1206H26"
			(at 0 -6.3754 270)
			(unlocked yes)
			(layer "F.Fab")
			(hide yes)
			(effects
				(font
					(size 1.016 1.016)
					(thickness 0.1524)
				)
			)
		)
		(duplicate_pad_numbers_are_jumpers no)
		(fp_line
			(start -1.016 2.2352)
			(end -1.016 -2.2352)
			(stroke
				(width 0.1524)
				(type default)
			)
			(layer "F.SilkS")
		)
		(fp_line
			(start 1.016 2.2352)
			(end -1.016 2.2352)
			(stroke
				(width 0.1524)
				(type default)
			)
			(layer "F.SilkS")
		)
		(fp_line
			(start -1.016 -2.2352)
			(end 1.016 -2.2352)
			(stroke
				(width 0.1524)
				(type default)
			)
			(layer "F.SilkS")
		)
		(fp_line
			(start 1.016 -2.2352)
			(end 1.016 2.2352)
			(stroke
				(width 0.1524)
				(type default)
			)
			(layer "F.SilkS")
		)
		(fp_rect
			(start -1.0922 2.3114)
			(end 1.0922 -2.3114)
			(stroke
				(width 0)
				(type default)
			)
			(fill no)
			(layer "F.CrtYd")
		)
		(fp_poly
			(pts
				(xy -1.0922 -2.3114) (xy 1.0922 -2.3114) (xy 1.0922 2.3114) (xy -1.0922 2.3114)
			)
			(stroke
				(width 0)
				(type default)
			)
			(fill no)
			(layer "F.Fab")
		)
		(pad "1" smd rect
			(at 0 -1.397 270)
			(size 1.651 1.27)
			(layers "F.Cu" "F.Mask" "F.Paste")
			(net "P12V_HDD20")
		)
		(pad "2" smd rect
			(at 0 1.397 270)
			(size 1.651 1.27)
			(layers "F.Cu" "F.Mask" "F.Paste")
			(net "12V_PRE_20")
		)
	)
	(footprint ""
		(layer "F.Cu")
		(at 181.6862 -157.226)
		(property "Reference" "C255"
			(at 0 0 0)
			(layer "F.SilkS")
			(hide yes)
			(effects
				(font
					(size 1.27 1.27)
				)
			)
		)
		(property "Value" "SC4D7U25V5KX-1-GP"
			(at -0.0762 -6.1214 0)
			(unlocked yes)
			(layer "F.Fab")
			(hide yes)
			(effects
				(font
					(size 1.016 1.016)
					(thickness 0.1524)
				)
			)
		)
		(property "Device Type" "C805H58"
			(at -0.0762 -8.1534 0)
			(unlocked yes)
			(layer "F.Fab")
			(hide yes)
			(effects
				(font
					(size 1.016 1.016)
					(thickness 0.1524)
				)
			)
		)
		(duplicate_pad_numbers_are_jumpers no)
		(fp_line
			(start 0.635 0)
			(end -0.635 0)
			(stroke
				(width 0.508)
				(type default)
			)
			(layer "F.SilkS")
		)
		(fp_rect
			(start -0.9652 1.778)
			(end 0.9652 -1.778)
			(stroke
				(width 0)
				(type default)
			)
			(fill no)
			(layer "F.CrtYd")
		)
		(fp_poly
			(pts
				(xy -0.9652 -1.778) (xy 0.9652 -1.778) (xy 0.9652 1.778) (xy -0.9652 1.778)
			)
			(stroke
				(width 0)
				(type default)
			)
			(fill no)
			(layer "F.Fab")
		)
		(pad "1" smd rect
			(at 0 -0.9652)
			(size 1.397 1.143)
			(layers "F.Cu" "F.Mask" "F.Paste")
			(net "P12V_HDD17")
		)
		(pad "2" smd rect
			(at 0 0.9652)
			(size 1.397 1.143)
			(layers "F.Cu" "F.Mask" "F.Paste")
			(net "GND")
		)
	)
	(footprint ""
		(layer "F.Cu")
		(at 14.859 -254.508 -90)
		(property "Reference" "R913"
			(at 0 0 270)
			(layer "F.SilkS")
			(hide yes)
			(effects
				(font
					(size 1.27 1.27)
				)
			)
		)
		(property "Value" "300KR2F-GP"
			(at 0.064008 -3.993896 270)
			(unlocked yes)
			(layer "F.Fab")
			(hide yes)
			(effects
				(font
					(size 1.016 1.016)
					(thickness 0.1524)
				)
			)
		)
		(property "Device Type" "R402H16"
			(at 0.064008 -5.517896 270)
			(unlocked yes)
			(layer "F.Fab")
			(hide yes)
			(effects
				(font
					(size 1.016 1.016)
					(thickness 0.1524)
				)
			)
		)
		(duplicate_pad_numbers_are_jumpers no)
		(fp_line
			(start -0.508 -0.9398)
			(end -0.508 0.9398)
			(stroke
				(width 0.1524)
				(type default)
			)
			(layer "F.SilkS")
		)
		(fp_line
			(start 0.508 -0.9398)
			(end -0.508 -0.9398)
			(stroke
				(width 0.1524)
				(type default)
			)
			(layer "F.SilkS")
		)
		(fp_rect
			(start -0.508 0.9398)
			(end 0.508 -0.9398)
			(stroke
				(width 0)
				(type default)
			)
			(fill no)
			(layer "F.CrtYd")
		)
		(fp_rect
			(start -0.508 0.9398)
			(end 0.508 -0.9398)
			(stroke
				(width 0)
				(type default)
			)
			(fill no)
			(layer "F.Fab")
		)
		(pad "1" smd custom
			(at 0 -0.4445 270)
			(size 0.1397 0.1397)
			(layers "F.Cu" "F.Mask" "F.Paste")
			(net "SW_HDD_N0")
			(options
				(clearance outline)
				(anchor circle)
			)
			(primitives
				(gr_poly
					(pts
						(arc
							(start -0.1778 -0.2794)
							(mid -0.249642 -0.249642)
							(end -0.2794 -0.1778)
						)
						(arc
							(start -0.2794 0.1778)
							(mid -0.249642 0.249642)
							(end -0.1778 0.2794)
						)
						(arc
							(start 0.1778 0.2794)
							(mid 0.249642 0.249642)
							(end 0.2794 0.1778)
						)
						(arc
							(start 0.2794 -0.1778)
							(mid 0.249642 -0.249642)
							(end 0.1778 -0.2794)
						)
					)
					(width 0)
					(fill yes)
				)
			)
		)
		(pad "2" smd custom
			(at 0 0.4445 270)
			(size 0.1397 0.1397)
			(layers "F.Cu" "F.Mask" "F.Paste")
			(net "P12V_B")
			(options
				(clearance outline)
				(anchor circle)
			)
			(primitives
				(gr_poly
					(pts
						(arc
							(start -0.1778 -0.2794)
							(mid -0.249642 -0.249642)
							(end -0.2794 -0.1778)
						)
						(arc
							(start -0.2794 0.1778)
							(mid -0.249642 0.249642)
							(end -0.1778 0.2794)
						)
						(arc
							(start 0.1778 0.2794)
							(mid 0.249642 0.249642)
							(end 0.2794 0.1778)
						)
						(arc
							(start 0.2794 -0.1778)
							(mid 0.249642 -0.249642)
							(end 0.1778 -0.2794)
						)
					)
					(width 0)
					(fill yes)
				)
			)
		)
	)
	(footprint ""
		(layer "F.Cu")
		(at 80.01 -132.588 180)
		(property "Reference" "D14"
			(at 0 0 180)
			(layer "F.SilkS")
			(hide yes)
			(effects
				(font
					(size 1.27 1.27)
				)
			)
		)
		(property "Value" "RB551V30-GP"
			(at 0 -6.7818 180)
			(unlocked yes)
			(layer "F.Fab")
			(hide yes)
			(effects
				(font
					(size 1.016 1.016)
					(thickness 0.1524)
				)
			)
		)
		(property "Device Type" "SOD323AKH38"
			(at 0 -8.6868 180)
			(unlocked yes)
			(layer "F.Fab")
			(hide yes)
			(effects
				(font
					(size 1.016 1.016)
					(thickness 0.1524)
				)
			)
		)
		(duplicate_pad_numbers_are_jumpers no)
		(fp_line
			(start 0.889 2.159)
			(end -0.889 2.159)
			(stroke
				(width 0.1524)
				(type default)
			)
			(layer "F.SilkS")
		)
		(fp_line
			(start 0.889 -1.9304)
			(end 0.889 2.159)
			(stroke
				(width 0.1524)
				(type default)
			)
			(layer "F.SilkS")
		)
		(fp_line
			(start 0.762 2.0574)
			(end -0.762 2.0574)
			(stroke
				(width 0.508)
				(type default)
			)
			(layer "F.SilkS")
		)
		(fp_line
			(start -0.889 2.159)
			(end -0.889 -1.9304)
			(stroke
				(width 0.1524)
				(type default)
			)
			(layer "F.SilkS")
		)
		(fp_line
			(start -0.889 -1.9304)
			(end 0.889 -1.9304)
			(stroke
				(width 0.1524)
				(type default)
			)
			(layer "F.SilkS")
		)
		(fp_rect
			(start -1.016 2.3114)
			(end 1.016 -2.0066)
			(stroke
				(width 0)
				(type default)
			)
			(fill no)
			(layer "F.CrtYd")
		)
		(fp_poly
			(pts
				(xy -1.016 -2.0066) (xy 1.016 -2.0066) (xy 1.016 2.3114) (xy -1.016 2.3114)
			)
			(stroke
				(width 0)
				(type default)
			)
			(fill no)
			(layer "F.Fab")
		)
		(pad "A" smd rect
			(at 0 -1.143 180)
			(size 0.5588 1.016)
			(layers "F.Cu" "F.Mask" "F.Paste")
			(net "SW_HDD_R14")
		)
		(pad "K" smd rect
			(at 0 1.143 180)
			(size 0.5588 1.016)
			(layers "F.Cu" "F.Mask" "F.Paste")
			(net "SW_HDD_N14")
		)
	)
	(footprint ""
		(layer "F.Cu")
		(at 210.93938 -235.18622)
		(property "Reference" "R39"
			(at 0 0 0)
			(layer "F.SilkS")
			(hide yes)
			(effects
				(font
					(size 1.27 1.27)
				)
			)
		)
		(property "Value" "0R2J-2-GP"
			(at 0.064008 -3.993896 0)
			(unlocked yes)
			(layer "F.Fab")
			(hide yes)
			(effects
				(font
					(size 1.016 1.016)
					(thickness 0.1524)
				)
			)
		)
		(property "Device Type" "R402H16"
			(at 0.064008 -5.517896 0)
			(unlocked yes)
			(layer "F.Fab")
			(hide yes)
			(effects
				(font
					(size 1.016 1.016)
					(thickness 0.1524)
				)
			)
		)
		(duplicate_pad_numbers_are_jumpers no)
		(fp_line
			(start -0.508 -0.9398)
			(end -0.508 0.9398)
			(stroke
				(width 0.1524)
				(type default)
			)
			(layer "F.SilkS")
		)
		(fp_line
			(start 0.508 -0.9398)
			(end -0.508 -0.9398)
			(stroke
				(width 0.1524)
				(type default)
			)
			(layer "F.SilkS")
		)
		(fp_rect
			(start -0.508 0.9398)
			(end 0.508 -0.9398)
			(stroke
				(width 0)
				(type default)
			)
			(fill no)
			(layer "F.CrtYd")
		)
		(fp_rect
			(start -0.508 0.9398)
			(end 0.508 -0.9398)
			(stroke
				(width 0)
				(type default)
			)
			(fill no)
			(layer "F.Fab")
		)
		(pad "1" smd custom
			(at 0 -0.4445)
			(size 0.1397 0.1397)
			(layers "F.Cu" "F.Mask" "F.Paste")
			(net "IO_EXP4_SDA")
			(options
				(clearance outline)
				(anchor circle)
			)
			(primitives
				(gr_poly
					(pts
						(arc
							(start -0.1778 -0.2794)
							(mid -0.249642 -0.249642)
							(end -0.2794 -0.1778)
						)
						(arc
							(start -0.2794 0.1778)
							(mid -0.249642 0.249642)
							(end -0.1778 0.2794)
						)
						(arc
							(start 0.1778 0.2794)
							(mid 0.249642 0.249642)
							(end 0.2794 0.1778)
						)
						(arc
							(start 0.2794 -0.1778)
							(mid 0.249642 -0.249642)
							(end 0.1778 -0.2794)
						)
					)
					(width 0)
					(fill yes)
				)
			)
		)
		(pad "2" smd custom
			(at 0 0.4445)
			(size 0.1397 0.1397)
			(layers "F.Cu" "F.Mask" "F.Paste")
			(net "I2C_DRIVE_B_INS_SDA")
			(options
				(clearance outline)
				(anchor circle)
			)
			(primitives
				(gr_poly
					(pts
						(arc
							(start -0.1778 -0.2794)
							(mid -0.249642 -0.249642)
							(end -0.2794 -0.1778)
						)
						(arc
							(start -0.2794 0.1778)
							(mid -0.249642 0.249642)
							(end -0.1778 0.2794)
						)
						(arc
							(start 0.1778 0.2794)
							(mid 0.249642 0.249642)
							(end 0.2794 0.1778)
						)
						(arc
							(start 0.2794 -0.1778)
							(mid 0.249642 -0.249642)
							(end 0.1778 -0.2794)
						)
					)
					(width 0)
					(fill yes)
				)
			)
		)
	)
	(footprint ""
		(layer "F.Cu")
		(at 308.193694 -214.860378 90)
		(property "Reference" "Q249"
			(at 0 0 90)
			(layer "F.SilkS")
			(hide yes)
			(effects
				(font
					(size 1.27 1.27)
				)
			)
		)
		(property "Value" "SSM3K324R-GP"
			(at 0.127 -8.9662 90)
			(unlocked yes)
			(layer "F.Fab")
			(hide yes)
			(effects
				(font
					(size 1.016 1.016)
					(thickness 0.1524)
				)
			)
		)
		(property "Device Type" "SOT23DGS2D4H35"
			(at 0.127 -10.4902 90)
			(unlocked yes)
			(layer "F.Fab")
			(hide yes)
			(effects
				(font
					(size 1.016 1.016)
					(thickness 0.1524)
				)
			)
		)
		(duplicate_pad_numbers_are_jumpers no)
		(fp_line
			(start 1.651 -1.778)
			(end -1.651 -1.778)
			(stroke
				(width 0.1524)
				(type default)
			)
			(layer "F.SilkS")
		)
		(fp_line
			(start -1.651 -1.778)
			(end -1.651 1.778)
			(stroke
				(width 0.1524)
				(type default)
			)
			(layer "F.SilkS")
		)
		(fp_line
			(start 1.651 1.778)
			(end 1.651 -1.778)
			(stroke
				(width 0.1524)
				(type default)
			)
			(layer "F.SilkS")
		)
		(fp_line
			(start -1.651 1.778)
			(end 1.651 1.778)
			(stroke
				(width 0.1524)
				(type default)
			)
			(layer "F.SilkS")
		)
		(fp_poly
			(pts
				(xy -1.778 1.8796) (xy -1.778 -1.8796) (xy 1.778 -1.8796) (xy 1.778 1.8796)
			)
			(stroke
				(width 0)
				(type default)
			)
			(fill no)
			(layer "F.CrtYd")
		)
		(fp_poly
			(pts
				(xy -1.778 1.8796) (xy -1.778 -1.8796) (xy 1.778 -1.8796) (xy 1.778 1.8796)
			)
			(stroke
				(width 0)
				(type default)
			)
			(fill no)
			(layer "F.Fab")
		)
		(pad "D" smd custom
			(at 0 -0.9525 90)
			(size 0.1905 0.1905)
			(layers "F.Cu" "F.Mask" "F.Paste")
			(net "DRV_ACT_6_N")
			(options
				(clearance outline)
				(anchor circle)
			)
			(primitives
				(gr_poly
					(pts
						(arc
							(start -0.1778 0.5715)
							(mid -0.321484 0.511984)
							(end -0.381 0.3683)
						)
						(arc
							(start -0.381 -0.3683)
							(mid -0.321484 -0.511984)
							(end -0.1778 -0.5715)
						)
						(arc
							(start 0.1778 -0.5715)
							(mid 0.321484 -0.511984)
							(end 0.381 -0.3683)
						)
						(arc
							(start 0.381 0.3683)
							(mid 0.321484 0.511984)
							(end 0.1778 0.5715)
						)
					)
					(width 0)
					(fill yes)
				)
			)
		)
		(pad "G" smd custom
			(at -0.98425 0.9525 90)
			(size 0.1905 0.1905)
			(layers "F.Cu" "F.Mask" "F.Paste")
			(net "DRIVE_B_6_ACT")
			(options
				(clearance outline)
				(anchor circle)
			)
			(primitives
				(gr_poly
					(pts
						(arc
							(start -0.1778 0.5715)
							(mid -0.321484 0.511984)
							(end -0.381 0.3683)
						)
						(arc
							(start -0.381 -0.3683)
							(mid -0.321484 -0.511984)
							(end -0.1778 -0.5715)
						)
						(arc
							(start 0.1778 -0.5715)
							(mid 0.321484 -0.511984)
							(end 0.381 -0.3683)
						)
						(arc
							(start 0.381 0.3683)
							(mid 0.321484 0.511984)
							(end 0.1778 0.5715)
						)
					)
					(width 0)
					(fill yes)
				)
			)
		)
		(pad "S" smd custom
			(at 0.98425 0.9525 90)
			(size 0.1905 0.1905)
			(layers "F.Cu" "F.Mask" "F.Paste")
			(net "GND")
			(options
				(clearance outline)
				(anchor circle)
			)
			(primitives
				(gr_poly
					(pts
						(arc
							(start -0.1778 0.5715)
							(mid -0.321484 0.511984)
							(end -0.381 0.3683)
						)
						(arc
							(start -0.381 -0.3683)
							(mid -0.321484 -0.511984)
							(end -0.1778 -0.5715)
						)
						(arc
							(start 0.1778 -0.5715)
							(mid 0.321484 -0.511984)
							(end 0.381 -0.3683)
						)
						(arc
							(start 0.381 0.3683)
							(mid 0.321484 0.511984)
							(end 0.1778 0.5715)
						)
					)
					(width 0)
					(fill yes)
				)
			)
		)
	)
	(footprint ""
		(layer "F.Cu")
		(at 259.089906 -227.82911 90)
		(property "Reference" "R167"
			(at 0 0 90)
			(layer "F.SilkS")
			(hide yes)
			(effects
				(font
					(size 1.27 1.27)
				)
			)
		)
		(property "Value" "10KR2F-2-GP"
			(at 0.064008 -3.993896 90)
			(unlocked yes)
			(layer "F.Fab")
			(hide yes)
			(effects
				(font
					(size 1.016 1.016)
					(thickness 0.1524)
				)
			)
		)
		(property "Device Type" "R402H16"
			(at 0.064008 -5.517896 90)
			(unlocked yes)
			(layer "F.Fab")
			(hide yes)
			(effects
				(font
					(size 1.016 1.016)
					(thickness 0.1524)
				)
			)
		)
		(duplicate_pad_numbers_are_jumpers no)
		(fp_line
			(start 0.508 -0.9398)
			(end -0.508 -0.9398)
			(stroke
				(width 0.1524)
				(type default)
			)
			(layer "F.SilkS")
		)
		(fp_line
			(start -0.508 -0.9398)
			(end -0.508 0.9398)
			(stroke
				(width 0.1524)
				(type default)
			)
			(layer "F.SilkS")
		)
		(fp_rect
			(start -0.508 0.9398)
			(end 0.508 -0.9398)
			(stroke
				(width 0)
				(type default)
			)
			(fill no)
			(layer "F.CrtYd")
		)
		(fp_rect
			(start -0.508 0.9398)
			(end 0.508 -0.9398)
			(stroke
				(width 0)
				(type default)
			)
			(fill no)
			(layer "F.Fab")
		)
		(pad "1" smd custom
			(at 0 -0.4445 90)
			(size 0.1397 0.1397)
			(layers "F.Cu" "F.Mask" "F.Paste")
			(net "P5V_B_3_SENSE")
			(options
				(clearance outline)
				(anchor circle)
			)
			(primitives
				(gr_poly
					(pts
						(arc
							(start -0.1778 -0.2794)
							(mid -0.249642 -0.249642)
							(end -0.2794 -0.1778)
						)
						(arc
							(start -0.2794 0.1778)
							(mid -0.249642 0.249642)
							(end -0.1778 0.2794)
						)
						(arc
							(start 0.1778 0.2794)
							(mid 0.249642 0.249642)
							(end 0.2794 0.1778)
						)
						(arc
							(start 0.2794 -0.1778)
							(mid 0.249642 -0.249642)
							(end 0.1778 -0.2794)
						)
					)
					(width 0)
					(fill yes)
				)
			)
		)
		(pad "2" smd custom
			(at 0 0.4445 90)
			(size 0.1397 0.1397)
			(layers "F.Cu" "F.Mask" "F.Paste")
			(net "GND")
			(options
				(clearance outline)
				(anchor circle)
			)
			(primitives
				(gr_poly
					(pts
						(arc
							(start -0.1778 -0.2794)
							(mid -0.249642 -0.249642)
							(end -0.2794 -0.1778)
						)
						(arc
							(start -0.2794 0.1778)
							(mid -0.249642 0.249642)
							(end -0.1778 0.2794)
						)
						(arc
							(start 0.1778 0.2794)
							(mid 0.249642 0.249642)
							(end 0.2794 0.1778)
						)
						(arc
							(start 0.2794 -0.1778)
							(mid 0.249642 -0.249642)
							(end 0.1778 -0.2794)
						)
					)
					(width 0)
					(fill yes)
				)
			)
		)
	)
	(footprint ""
		(layer "F.Cu")
		(at 141.097 -24.511 -90)
		(property "Reference" "R729"
			(at 0 0 270)
			(layer "F.SilkS")
			(hide yes)
			(effects
				(font
					(size 1.27 1.27)
				)
			)
		)
		(property "Value" "300KR2F-GP"
			(at 0.064008 -3.993896 270)
			(unlocked yes)
			(layer "F.Fab")
			(hide yes)
			(effects
				(font
					(size 1.016 1.016)
					(thickness 0.1524)
				)
			)
		)
		(property "Device Type" "R402H16"
			(at 0.064008 -5.517896 270)
			(unlocked yes)
			(layer "F.Fab")
			(hide yes)
			(effects
				(font
					(size 1.016 1.016)
					(thickness 0.1524)
				)
			)
		)
		(duplicate_pad_numbers_are_jumpers no)
		(fp_line
			(start -0.508 -0.9398)
			(end -0.508 0.9398)
			(stroke
				(width 0.1524)
				(type default)
			)
			(layer "F.SilkS")
		)
		(fp_line
			(start 0.508 -0.9398)
			(end -0.508 -0.9398)
			(stroke
				(width 0.1524)
				(type default)
			)
			(layer "F.SilkS")
		)
		(fp_rect
			(start -0.508 0.9398)
			(end 0.508 -0.9398)
			(stroke
				(width 0)
				(type default)
			)
			(fill no)
			(layer "F.CrtYd")
		)
		(fp_rect
			(start -0.508 0.9398)
			(end 0.508 -0.9398)
			(stroke
				(width 0)
				(type default)
			)
			(fill no)
			(layer "F.Fab")
		)
		(pad "1" smd custom
			(at 0 -0.4445 270)
			(size 0.1397 0.1397)
			(layers "F.Cu" "F.Mask" "F.Paste")
			(net "SW_HDD_N28")
			(options
				(clearance outline)
				(anchor circle)
			)
			(primitives
				(gr_poly
					(pts
						(arc
							(start -0.1778 -0.2794)
							(mid -0.249642 -0.249642)
							(end -0.2794 -0.1778)
						)
						(arc
							(start -0.2794 0.1778)
							(mid -0.249642 0.249642)
							(end -0.1778 0.2794)
						)
						(arc
							(start 0.1778 0.2794)
							(mid 0.249642 0.249642)
							(end 0.2794 0.1778)
						)
						(arc
							(start 0.2794 -0.1778)
							(mid 0.249642 -0.249642)
							(end 0.1778 -0.2794)
						)
					)
					(width 0)
					(fill yes)
				)
			)
		)
		(pad "2" smd custom
			(at 0 0.4445 270)
			(size 0.1397 0.1397)
			(layers "F.Cu" "F.Mask" "F.Paste")
			(net "P12V_B")
			(options
				(clearance outline)
				(anchor circle)
			)
			(primitives
				(gr_poly
					(pts
						(arc
							(start -0.1778 -0.2794)
							(mid -0.249642 -0.249642)
							(end -0.2794 -0.1778)
						)
						(arc
							(start -0.2794 0.1778)
							(mid -0.249642 0.249642)
							(end -0.1778 0.2794)
						)
						(arc
							(start 0.1778 0.2794)
							(mid 0.249642 0.249642)
							(end 0.2794 0.1778)
						)
						(arc
							(start 0.2794 -0.1778)
							(mid 0.249642 -0.249642)
							(end 0.1778 -0.2794)
						)
					)
					(width 0)
					(fill yes)
				)
			)
		)
	)
	(footprint ""
		(layer "F.Cu")
		(at 477.536002 -128.627124 180)
		(property "Reference" "VIA47"
			(at 0 0 180)
			(layer "F.SilkS")
			(hide yes)
			(effects
				(font
					(size 1.27 1.27)
				)
			)
		)
		(property "Value" "100OHM-8L-2D36MM-L18-GP"
			(at 3.8989 0.5715 180)
			(unlocked yes)
			(layer "F.Fab")
			(hide yes)
			(effects
				(font
					(size 1.016 1.016)
					(thickness 0.1524)
				)
			)
		)
		(property "Device Type" "VIA-PCIE-4P-414097"
			(at 3.8989 -0.9525 180)
			(unlocked yes)
			(layer "F.Fab")
			(hide yes)
			(effects
				(font
					(size 1.016 1.016)
					(thickness 0.1524)
				)
			)
		)
		(duplicate_pad_numbers_are_jumpers no)
		(fp_rect
			(start -2.0701 0.4826)
			(end 2.0701 -0.4826)
			(stroke
				(width 0)
				(type default)
			)
			(fill no)
			(layer "F.CrtYd")
		)
		(fp_rect
			(start -2.0701 0.4826)
			(end 2.0701 -0.4826)
			(stroke
				(width 0)
				(type default)
			)
			(fill no)
			(layer "F.Fab")
		)
		(pad "1" thru_hole circle
			(at -1.5875 0 180)
			(size 0.508 0.508)
			(drill 0.254)
			(layers "*.Cu" "*.Mask")
			(remove_unused_layers no)
			(net "GND")
			(clearance 0.2286)
			(thermal_gap 0.2286)
		)
		(pad "2" thru_hole circle
			(at -0.5715 0 180)
			(size 0.508 0.508)
			(drill 0.254)
			(layers "*.Cu" "*.Mask")
			(remove_unused_layers no)
			(net "PHY_SCC_B_TO_DRV_B_23_DP")
			(clearance 0.2286)
			(thermal_gap 0.2286)
		)
		(pad "3" thru_hole circle
			(at 0.5715 0 180)
			(size 0.508 0.508)
			(drill 0.254)
			(layers "*.Cu" "*.Mask")
			(remove_unused_layers no)
			(net "PHY_SCC_B_TO_DRV_B_23_DN")
			(clearance 0.2286)
			(thermal_gap 0.2286)
		)
		(pad "4" thru_hole circle
			(at 1.5875 0 180)
			(size 0.508 0.508)
			(drill 0.254)
			(layers "*.Cu" "*.Mask")
			(remove_unused_layers no)
			(net "GND")
			(clearance 0.2286)
			(thermal_gap 0.2286)
		)
	)
	(footprint ""
		(layer "F.Cu")
		(at 428.117 -274.955 180)
		(property "Reference" "C152"
			(at 0 0 180)
			(layer "F.SilkS")
			(hide yes)
			(effects
				(font
					(size 1.27 1.27)
				)
			)
		)
		(property "Value" "SC4D7U25V5KX-1-GP"
			(at -0.0762 -6.1214 180)
			(unlocked yes)
			(layer "F.Fab")
			(hide yes)
			(effects
				(font
					(size 1.016 1.016)
					(thickness 0.1524)
				)
			)
		)
		(property "Device Type" "C805H58"
			(at -0.0762 -8.1534 180)
			(unlocked yes)
			(layer "F.Fab")
			(hide yes)
			(effects
				(font
					(size 1.016 1.016)
					(thickness 0.1524)
				)
			)
		)
		(duplicate_pad_numbers_are_jumpers no)
		(fp_line
			(start 0.635 0)
			(end -0.635 0)
			(stroke
				(width 0.508)
				(type default)
			)
			(layer "F.SilkS")
		)
		(fp_rect
			(start -0.9652 1.778)
			(end 0.9652 -1.778)
			(stroke
				(width 0)
				(type default)
			)
			(fill no)
			(layer "F.CrtYd")
		)
		(fp_poly
			(pts
				(xy -0.9652 -1.778) (xy 0.9652 -1.778) (xy 0.9652 1.778) (xy -0.9652 1.778)
			)
			(stroke
				(width 0)
				(type default)
			)
			(fill no)
			(layer "F.Fab")
		)
		(pad "1" smd rect
			(at 0 -0.9652 180)
			(size 1.397 1.143)
			(layers "F.Cu" "F.Mask" "F.Paste")
			(net "P12V_HDD9")
		)
		(pad "2" smd rect
			(at 0 0.9652 180)
			(size 1.397 1.143)
			(layers "F.Cu" "F.Mask" "F.Paste")
			(net "GND")
		)
	)
	(footprint ""
		(layer "F.Cu")
		(at 97.385632 -14.990826 90)
		(property "Reference" "VIA53"
			(at 0 0 90)
			(layer "F.SilkS")
			(hide yes)
			(effects
				(font
					(size 1.27 1.27)
				)
			)
		)
		(property "Value" "100OHM-8L-2D36MM-L18-GP"
			(at 3.8989 0.5715 90)
			(unlocked yes)
			(layer "F.Fab")
			(hide yes)
			(effects
				(font
					(size 1.016 1.016)
					(thickness 0.1524)
				)
			)
		)
		(property "Device Type" "VIA-PCIE-4P-414097"
			(at 3.8989 -0.9525 90)
			(unlocked yes)
			(layer "F.Fab")
			(hide yes)
			(effects
				(font
					(size 1.016 1.016)
					(thickness 0.1524)
				)
			)
		)
		(duplicate_pad_numbers_are_jumpers no)
		(fp_rect
			(start -2.0701 0.4826)
			(end 2.0701 -0.4826)
			(stroke
				(width 0)
				(type default)
			)
			(fill no)
			(layer "F.CrtYd")
		)
		(fp_rect
			(start -2.0701 0.4826)
			(end 2.0701 -0.4826)
			(stroke
				(width 0)
				(type default)
			)
			(fill no)
			(layer "F.Fab")
		)
		(pad "1" thru_hole circle
			(at -1.5875 0 90)
			(size 0.508 0.508)
			(drill 0.254)
			(layers "*.Cu" "*.Mask")
			(remove_unused_layers no)
			(net "GND")
			(clearance 0.2286)
			(thermal_gap 0.2286)
		)
		(pad "2" thru_hole circle
			(at -0.5715 0 90)
			(size 0.508 0.508)
			(drill 0.254)
			(layers "*.Cu" "*.Mask")
			(remove_unused_layers no)
			(net "PHY_SCC_B_TO_DRV_B_26_DP")
			(clearance 0.2286)
			(thermal_gap 0.2286)
		)
		(pad "3" thru_hole circle
			(at 0.5715 0 90)
			(size 0.508 0.508)
			(drill 0.254)
			(layers "*.Cu" "*.Mask")
			(remove_unused_layers no)
			(net "PHY_SCC_B_TO_DRV_B_26_DN")
			(clearance 0.2286)
			(thermal_gap 0.2286)
		)
		(pad "4" thru_hole circle
			(at 1.5875 0 90)
			(size 0.508 0.508)
			(drill 0.254)
			(layers "*.Cu" "*.Mask")
			(remove_unused_layers no)
			(net "GND")
			(clearance 0.2286)
			(thermal_gap 0.2286)
		)
	)
	(footprint ""
		(layer "F.Cu")
		(at 98.425 -147.066 90)
		(property "Reference" "C218"
			(at 0 0 90)
			(layer "F.SilkS")
			(hide yes)
			(effects
				(font
					(size 1.27 1.27)
				)
			)
		)
		(property "Value" "SCD01U50V2KX-1GP"
			(at 1.1811 -2.7051 90)
			(unlocked yes)
			(layer "F.Fab")
			(hide yes)
			(effects
				(font
					(size 1.016 1.016)
					(thickness 0.1524)
				)
			)
		)
		(property "Device Type" "C402H22"
			(at 1.1811 -4.2291 90)
			(unlocked yes)
			(layer "F.Fab")
			(hide yes)
			(effects
				(font
					(size 1.016 1.016)
					(thickness 0.1524)
				)
			)
		)
		(duplicate_pad_numbers_are_jumpers no)
		(fp_rect
			(start -0.4318 0.9525)
			(end 0.4318 -0.9525)
			(stroke
				(width 0)
				(type default)
			)
			(fill no)
			(layer "F.CrtYd")
		)
		(fp_rect
			(start -0.4318 0.9525)
			(end 0.4318 -0.9525)
			(stroke
				(width 0)
				(type default)
			)
			(fill no)
			(layer "F.Fab")
		)
		(pad "1" smd custom
			(at 0 -0.4445 90)
			(size 0.1524 0.1524)
			(layers "F.Cu" "F.Mask" "F.Paste")
			(net "HDD_PRSNT_14")
			(options
				(clearance outline)
				(anchor circle)
			)
			(primitives
				(gr_poly
					(pts
						(arc
							(start 0.3048 -0.2032)
							(mid 0.275042 -0.275042)
							(end 0.2032 -0.3048)
						)
						(arc
							(start -0.2032 -0.3048)
							(mid -0.275042 -0.275042)
							(end -0.3048 -0.2032)
						)
						(arc
							(start -0.3048 0.2032)
							(mid -0.275042 0.275042)
							(end -0.2032 0.3048)
						)
						(arc
							(start 0.2032 0.3048)
							(mid 0.275042 0.275042)
							(end 0.3048 0.2032)
						)
					)
					(width 0)
					(fill yes)
				)
			)
		)
		(pad "2" smd custom
			(at 0 0.4445 90)
			(size 0.1524 0.1524)
			(layers "F.Cu" "F.Mask" "F.Paste")
			(net "GND")
			(options
				(clearance outline)
				(anchor circle)
			)
			(primitives
				(gr_poly
					(pts
						(arc
							(start 0.3048 -0.2032)
							(mid 0.275042 -0.275042)
							(end 0.2032 -0.3048)
						)
						(arc
							(start -0.2032 -0.3048)
							(mid -0.275042 -0.275042)
							(end -0.3048 -0.2032)
						)
						(arc
							(start -0.3048 0.2032)
							(mid -0.275042 0.275042)
							(end -0.2032 0.3048)
						)
						(arc
							(start 0.2032 0.3048)
							(mid 0.275042 0.275042)
							(end 0.3048 0.2032)
						)
					)
					(width 0)
					(fill yes)
				)
			)
		)
	)
	(footprint ""
		(layer "F.Cu")
		(at 252.333252 -131.428998 -90)
		(property "Reference" "R401"
			(at 0 0 270)
			(layer "F.SilkS")
			(hide yes)
			(effects
				(font
					(size 1.27 1.27)
				)
			)
		)
		(property "Value" "10KR2F-2-GP"
			(at 0.064008 -3.993896 270)
			(unlocked yes)
			(layer "F.Fab")
			(hide yes)
			(effects
				(font
					(size 1.016 1.016)
					(thickness 0.1524)
				)
			)
		)
		(property "Device Type" "R402H16"
			(at 0.064008 -5.517896 270)
			(unlocked yes)
			(layer "F.Fab")
			(hide yes)
			(effects
				(font
					(size 1.016 1.016)
					(thickness 0.1524)
				)
			)
		)
		(duplicate_pad_numbers_are_jumpers no)
		(fp_line
			(start -0.508 -0.9398)
			(end -0.508 0.9398)
			(stroke
				(width 0.1524)
				(type default)
			)
			(layer "F.SilkS")
		)
		(fp_line
			(start 0.508 -0.9398)
			(end -0.508 -0.9398)
			(stroke
				(width 0.1524)
				(type default)
			)
			(layer "F.SilkS")
		)
		(fp_rect
			(start -0.508 0.9398)
			(end 0.508 -0.9398)
			(stroke
				(width 0)
				(type default)
			)
			(fill no)
			(layer "F.CrtYd")
		)
		(fp_rect
			(start -0.508 0.9398)
			(end 0.508 -0.9398)
			(stroke
				(width 0)
				(type default)
			)
			(fill no)
			(layer "F.Fab")
		)
		(pad "1" smd custom
			(at 0 -0.4445 270)
			(size 0.1397 0.1397)
			(layers "F.Cu" "F.Mask" "F.Paste")
			(net "P3V3_STBY_B")
			(options
				(clearance outline)
				(anchor circle)
			)
			(primitives
				(gr_poly
					(pts
						(arc
							(start -0.1778 -0.2794)
							(mid -0.249642 -0.249642)
							(end -0.2794 -0.1778)
						)
						(arc
							(start -0.2794 0.1778)
							(mid -0.249642 0.249642)
							(end -0.1778 0.2794)
						)
						(arc
							(start 0.1778 0.2794)
							(mid 0.249642 0.249642)
							(end 0.2794 0.1778)
						)
						(arc
							(start 0.2794 -0.1778)
							(mid 0.249642 -0.249642)
							(end 0.1778 -0.2794)
						)
					)
					(width 0)
					(fill yes)
				)
			)
		)
		(pad "2" smd custom
			(at 0 0.4445 270)
			(size 0.1397 0.1397)
			(layers "F.Cu" "F.Mask" "F.Paste")
			(net "I2C_DPB_BUFF_READY")
			(options
				(clearance outline)
				(anchor circle)
			)
			(primitives
				(gr_poly
					(pts
						(arc
							(start -0.1778 -0.2794)
							(mid -0.249642 -0.249642)
							(end -0.2794 -0.1778)
						)
						(arc
							(start -0.2794 0.1778)
							(mid -0.249642 0.249642)
							(end -0.1778 0.2794)
						)
						(arc
							(start 0.1778 0.2794)
							(mid 0.249642 0.249642)
							(end 0.2794 0.1778)
						)
						(arc
							(start 0.2794 -0.1778)
							(mid 0.249642 -0.249642)
							(end 0.1778 -0.2794)
						)
					)
					(width 0)
					(fill yes)
				)
			)
		)
	)
	(footprint ""
		(layer "F.Cu")
		(at 192.035684 -14.990826 90)
		(property "Reference" "VIA59"
			(at 0 0 90)
			(layer "F.SilkS")
			(hide yes)
			(effects
				(font
					(size 1.27 1.27)
				)
			)
		)
		(property "Value" "100OHM-8L-2D36MM-L18-GP"
			(at 3.8989 0.5715 90)
			(unlocked yes)
			(layer "F.Fab")
			(hide yes)
			(effects
				(font
					(size 1.016 1.016)
					(thickness 0.1524)
				)
			)
		)
		(property "Device Type" "VIA-PCIE-4P-414097"
			(at 3.8989 -0.9525 90)
			(unlocked yes)
			(layer "F.Fab")
			(hide yes)
			(effects
				(font
					(size 1.016 1.016)
					(thickness 0.1524)
				)
			)
		)
		(duplicate_pad_numbers_are_jumpers no)
		(fp_rect
			(start -2.0701 0.4826)
			(end 2.0701 -0.4826)
			(stroke
				(width 0)
				(type default)
			)
			(fill no)
			(layer "F.CrtYd")
		)
		(fp_rect
			(start -2.0701 0.4826)
			(end 2.0701 -0.4826)
			(stroke
				(width 0)
				(type default)
			)
			(fill no)
			(layer "F.Fab")
		)
		(pad "1" thru_hole circle
			(at -1.5875 0 90)
			(size 0.508 0.508)
			(drill 0.254)
			(layers "*.Cu" "*.Mask")
			(remove_unused_layers no)
			(net "GND")
			(clearance 0.2286)
			(thermal_gap 0.2286)
		)
		(pad "2" thru_hole circle
			(at -0.5715 0 90)
			(size 0.508 0.508)
			(drill 0.254)
			(layers "*.Cu" "*.Mask")
			(remove_unused_layers no)
			(net "PHY_SCC_B_TO_DRV_B_29_DP")
			(clearance 0.2286)
			(thermal_gap 0.2286)
		)
		(pad "3" thru_hole circle
			(at 0.5715 0 90)
			(size 0.508 0.508)
			(drill 0.254)
			(layers "*.Cu" "*.Mask")
			(remove_unused_layers no)
			(net "PHY_SCC_B_TO_DRV_B_29_DN")
			(clearance 0.2286)
			(thermal_gap 0.2286)
		)
		(pad "4" thru_hole circle
			(at 1.5875 0 90)
			(size 0.508 0.508)
			(drill 0.254)
			(layers "*.Cu" "*.Mask")
			(remove_unused_layers no)
			(net "GND")
			(clearance 0.2286)
			(thermal_gap 0.2286)
		)
	)
	(footprint ""
		(layer "F.Cu")
		(at 191.135 -150.114 180)
		(property "Reference" "R465"
			(at 0 0 180)
			(layer "F.SilkS")
			(hide yes)
			(effects
				(font
					(size 1.27 1.27)
				)
			)
		)
		(property "Value" "220R3F-1-GP"
			(at -0.0254 -2.5146 180)
			(unlocked yes)
			(layer "F.Fab")
			(hide yes)
			(effects
				(font
					(size 1.016 1.016)
					(thickness 0.1524)
				)
			)
		)
		(property "Device Type" "R603H22"
			(at -0.0254 -4.0386 180)
			(unlocked yes)
			(layer "F.Fab")
			(hide yes)
			(effects
				(font
					(size 1.016 1.016)
					(thickness 0.1524)
				)
			)
		)
		(duplicate_pad_numbers_are_jumpers no)
		(fp_line
			(start 0.2032 0)
			(end 0.4826 0)
			(stroke
				(width 0.2032)
				(type default)
			)
			(layer "F.SilkS")
		)
		(fp_line
			(start -0.4826 0)
			(end -0.2032 0)
			(stroke
				(width 0.2032)
				(type default)
			)
			(layer "F.SilkS")
		)
		(fp_rect
			(start -0.5842 1.3335)
			(end 0.5842 -1.3335)
			(stroke
				(width 0)
				(type default)
			)
			(fill no)
			(layer "F.CrtYd")
		)
		(fp_rect
			(start -0.5842 1.3335)
			(end 0.5842 -1.3335)
			(stroke
				(width 0)
				(type default)
			)
			(fill no)
			(layer "F.Fab")
		)
		(pad "1" smd custom
			(at 0 -0.762 180)
			(size 0.2159 0.2159)
			(layers "F.Cu" "F.Mask" "F.Paste")
			(net "HDD_PRSNT_17")
			(options
				(clearance outline)
				(anchor circle)
			)
			(primitives
				(gr_poly
					(pts
						(arc
							(start -0.3302 -0.4318)
							(mid -0.402042 -0.402042)
							(end -0.4318 -0.3302)
						)
						(arc
							(start -0.4318 0.3302)
							(mid -0.402042 0.402042)
							(end -0.3302 0.4318)
						)
						(arc
							(start 0.3302 0.4318)
							(mid 0.402042 0.402042)
							(end 0.4318 0.3302)
						)
						(arc
							(start 0.4318 -0.3302)
							(mid 0.402042 -0.402042)
							(end 0.3302 -0.4318)
						)
					)
					(width 0)
					(fill yes)
				)
			)
		)
		(pad "2" smd custom
			(at 0 0.762 180)
			(size 0.2159 0.2159)
			(layers "F.Cu" "F.Mask" "F.Paste")
			(net "DRIVE_B_17_INS")
			(options
				(clearance outline)
				(anchor circle)
			)
			(primitives
				(gr_poly
					(pts
						(arc
							(start -0.3302 -0.4318)
							(mid -0.402042 -0.402042)
							(end -0.4318 -0.3302)
						)
						(arc
							(start -0.4318 0.3302)
							(mid -0.402042 0.402042)
							(end -0.3302 0.4318)
						)
						(arc
							(start 0.3302 0.4318)
							(mid 0.402042 0.402042)
							(end 0.4318 0.3302)
						)
						(arc
							(start 0.4318 -0.3302)
							(mid 0.402042 -0.402042)
							(end 0.3302 -0.4318)
						)
					)
					(width 0)
					(fill yes)
				)
			)
		)
	)
	(footprint ""
		(layer "F.Cu")
		(at 17.399 -214.249)
		(property "Reference" "R205"
			(at 0 0 0)
			(layer "F.SilkS")
			(hide yes)
			(effects
				(font
					(size 1.27 1.27)
				)
			)
		)
		(property "Value" "130R3F-GP"
			(at -0.0254 -2.5146 0)
			(unlocked yes)
			(layer "F.Fab")
			(hide yes)
			(effects
				(font
					(size 1.016 1.016)
					(thickness 0.1524)
				)
			)
		)
		(property "Device Type" "R603H22"
			(at -0.0254 -4.0386 0)
			(unlocked yes)
			(layer "F.Fab")
			(hide yes)
			(effects
				(font
					(size 1.016 1.016)
					(thickness 0.1524)
				)
			)
		)
		(duplicate_pad_numbers_are_jumpers no)
		(fp_line
			(start -0.4826 0)
			(end -0.2032 0)
			(stroke
				(width 0.2032)
				(type default)
			)
			(layer "F.SilkS")
		)
		(fp_line
			(start 0.2032 0)
			(end 0.4826 0)
			(stroke
				(width 0.2032)
				(type default)
			)
			(layer "F.SilkS")
		)
		(fp_rect
			(start -0.5842 1.3335)
			(end 0.5842 -1.3335)
			(stroke
				(width 0)
				(type default)
			)
			(fill no)
			(layer "F.CrtYd")
		)
		(fp_rect
			(start -0.5842 1.3335)
			(end 0.5842 -1.3335)
			(stroke
				(width 0)
				(type default)
			)
			(fill no)
			(layer "F.Fab")
		)
		(pad "1" smd custom
			(at 0 -0.762)
			(size 0.2159 0.2159)
			(layers "F.Cu" "F.Mask" "F.Paste")
			(net "P5V_B_1")
			(options
				(clearance outline)
				(anchor circle)
			)
			(primitives
				(gr_poly
					(pts
						(arc
							(start -0.3302 -0.4318)
							(mid -0.402042 -0.402042)
							(end -0.4318 -0.3302)
						)
						(arc
							(start -0.4318 0.3302)
							(mid -0.402042 0.402042)
							(end -0.3302 0.4318)
						)
						(arc
							(start 0.3302 0.4318)
							(mid 0.402042 0.402042)
							(end 0.4318 0.3302)
						)
						(arc
							(start 0.4318 -0.3302)
							(mid 0.402042 -0.402042)
							(end 0.3302 -0.4318)
						)
					)
					(width 0)
					(fill yes)
				)
			)
		)
		(pad "2" smd custom
			(at 0 0.762)
			(size 0.2159 0.2159)
			(layers "F.Cu" "F.Mask" "F.Paste")
			(net "FLT_HDD0")
			(options
				(clearance outline)
				(anchor circle)
			)
			(primitives
				(gr_poly
					(pts
						(arc
							(start -0.3302 -0.4318)
							(mid -0.402042 -0.402042)
							(end -0.4318 -0.3302)
						)
						(arc
							(start -0.4318 0.3302)
							(mid -0.402042 0.402042)
							(end -0.3302 0.4318)
						)
						(arc
							(start 0.3302 0.4318)
							(mid 0.402042 0.402042)
							(end 0.4318 0.3302)
						)
						(arc
							(start 0.4318 -0.3302)
							(mid 0.402042 -0.402042)
							(end 0.3302 -0.4318)
						)
					)
					(width 0)
					(fill yes)
				)
			)
		)
	)
	(footprint ""
		(layer "F.Cu")
		(at 163.4998 -331.0382 180)
		(property "Reference" "R1012"
			(at 0 0 180)
			(layer "F.SilkS")
			(hide yes)
			(effects
				(font
					(size 1.27 1.27)
				)
			)
		)
		(property "Value" "D0003R4026F-GP"
			(at -6.737858 -1.79959 180)
			(unlocked yes)
			(layer "F.Fab")
			(hide yes)
			(effects
				(font
					(size 1.016 1.016)
					(thickness 0.1524)
				)
			)
		)
		(property "Device Type" "RL4026-4PH149"
			(at -6.737858 -3.32359 180)
			(unlocked yes)
			(layer "F.Fab")
			(hide yes)
			(effects
				(font
					(size 1.016 1.016)
					(thickness 0.1524)
				)
			)
		)
		(duplicate_pad_numbers_are_jumpers no)
		(fp_line
			(start 5.588 3.937)
			(end -5.588 3.937)
			(stroke
				(width 0.1524)
				(type default)
			)
			(layer "F.SilkS")
		)
		(fp_line
			(start 5.588 -3.937)
			(end 5.588 3.937)
			(stroke
				(width 0.1524)
				(type default)
			)
			(layer "F.SilkS")
		)
		(fp_line
			(start -5.588 3.937)
			(end -5.588 -3.937)
			(stroke
				(width 0.1524)
				(type default)
			)
			(layer "F.SilkS")
		)
		(fp_line
			(start -5.588 -3.937)
			(end 5.588 -3.937)
			(stroke
				(width 0.1524)
				(type default)
			)
			(layer "F.SilkS")
		)
		(fp_line
			(start -5.6769 4.0259)
			(end -4.1402 4.0259)
			(stroke
				(width 0.3302)
				(type default)
			)
			(layer "F.SilkS")
		)
		(fp_line
			(start -5.6769 2.4765)
			(end -5.6769 4.0259)
			(stroke
				(width 0.3302)
				(type default)
			)
			(layer "F.SilkS")
		)
		(fp_poly
			(pts
				(xy -4.703572 3.998468) (xy -5.289804 4.5847) (xy -4.11734 4.5847)
			)
			(stroke
				(width 0)
				(type default)
			)
			(fill yes)
			(layer "F.SilkS")
		)
		(fp_rect
			(start -5.0546 3.302)
			(end 5.0546 -3.302)
			(stroke
				(width 0)
				(type default)
			)
			(fill no)
			(layer "F.CrtYd")
		)
		(fp_poly
			(pts
				(xy -5.842 4.191) (xy -5.842 -4.191) (xy 5.842 -4.191) (xy 5.842 -0.00635) (xy 5.0546 -0.00635)
				(xy 5.0546 -3.302) (xy -5.0546 -3.302) (xy -5.0546 3.302) (xy 5.0546 3.302) (xy 5.0546 0.00635)
				(xy 5.842 0.00635) (xy 5.842 4.191)
			)
			(stroke
				(width 0)
				(type default)
			)
			(fill no)
			(layer "F.CrtYd")
		)
		(fp_rect
			(start -5.842 4.191)
			(end 5.842 -4.191)
			(stroke
				(width 0)
				(type default)
			)
			(fill no)
			(layer "F.Fab")
		)
		(pad "1" smd rect
			(at -4.115054 0.890016 180)
			(size 2.4384 5.588)
			(layers "F.Cu" "F.Mask" "F.Paste")
			(net "MB0_P12V_IN_R")
		)
		(pad "2" smd rect
			(at 4.115054 0.890016 180)
			(size 2.4384 5.588)
			(layers "F.Cu" "F.Mask" "F.Paste")
			(net "P12V_CLIP")
		)
		(pad "3" smd rect
			(at -4.115054 -3.245104 180)
			(size 2.4384 0.889)
			(layers "F.Cu" "F.Mask" "F.Paste")
			(net "MB0_CM_SENSE_R2_N")
		)
		(pad "4" smd rect
			(at 4.115054 -3.245104 180)
			(size 2.4384 0.889)
			(layers "F.Cu" "F.Mask" "F.Paste")
			(net "MB0_CM_SENSE_R2_P")
		)
		(zone
			(layer "F.Cu")
			(hatch none 0.5)
			(connect_pads
				(clearance 0)
			)
			(min_thickness 0.25)
			(keepout
				(tracks not_allowed)
				(vias allowed)
				(pads allowed)
				(copperpour not_allowed)
				(footprints allowed)
			)
			(placement
				(enabled no)
				(sheetname "")
			)
			(fill
				(thermal_gap 0.5)
				(thermal_bridge_width 0.5)
				(island_removal_mode 0)
			)
			(polygon
				(pts
					(xy 160.603946 -329.134216) (xy 158.165546 -329.134216) (xy 158.165546 -328.237596) (xy 160.603946 -328.237596)
				)
			)
		)
		(zone
			(layer "F.Cu")
			(hatch none 0.5)
			(connect_pads
				(clearance 0)
			)
			(min_thickness 0.25)
			(keepout
				(tracks allowed)
				(vias not_allowed)
				(pads allowed)
				(copperpour not_allowed)
				(footprints allowed)
			)
			(placement
				(enabled no)
				(sheetname "")
			)
			(fill
				(thermal_gap 0.5)
				(thermal_bridge_width 0.5)
				(island_removal_mode 0)
			)
			(polygon
				(pts
					(xy 160.603946 -328.237596) (xy 160.603946 -329.134216) (xy 158.165546 -329.134216) (xy 158.165546 -328.237596)
				)
			)
		)
		(zone
			(layer "F.Cu")
			(hatch none 0.5)
			(connect_pads
				(clearance 0)
			)
			(min_thickness 0.25)
			(keepout
				(tracks not_allowed)
				(vias allowed)
				(pads allowed)
				(copperpour not_allowed)
				(footprints allowed)
			)
			(placement
				(enabled no)
				(sheetname "")
			)
			(fill
				(thermal_gap 0.5)
				(thermal_bridge_width 0.5)
				(island_removal_mode 0)
			)
			(polygon
				(pts
					(xy 168.834054 -329.134216) (xy 166.395654 -329.134216) (xy 166.395654 -328.237596) (xy 168.834054 -328.237596)
				)
			)
		)
		(zone
			(layer "F.Cu")
			(hatch none 0.5)
			(connect_pads
				(clearance 0)
			)
			(min_thickness 0.25)
			(keepout
				(tracks allowed)
				(vias not_allowed)
				(pads allowed)
				(copperpour not_allowed)
				(footprints allowed)
			)
			(placement
				(enabled no)
				(sheetname "")
			)
			(fill
				(thermal_gap 0.5)
				(thermal_bridge_width 0.5)
				(island_removal_mode 0)
			)
			(polygon
				(pts
					(xy 168.834054 -328.237596) (xy 168.834054 -329.134216) (xy 166.395654 -329.134216) (xy 166.395654 -328.237596)
				)
			)
		)
	)
	(footprint ""
		(layer "F.Cu")
		(at 165.862 -376.682)
		(property "Reference" "R983"
			(at 0 0 0)
			(layer "F.SilkS")
			(hide yes)
			(effects
				(font
					(size 1.27 1.27)
				)
			)
		)
		(property "Value" "100R2D-GP"
			(at 0.064008 -3.993896 0)
			(unlocked yes)
			(layer "F.Fab")
			(hide yes)
			(effects
				(font
					(size 1.016 1.016)
					(thickness 0.1524)
				)
			)
		)
		(property "Device Type" "R402H14"
			(at 0.064008 -5.517896 0)
			(unlocked yes)
			(layer "F.Fab")
			(hide yes)
			(effects
				(font
					(size 1.016 1.016)
					(thickness 0.1524)
				)
			)
		)
		(duplicate_pad_numbers_are_jumpers no)
		(fp_line
			(start -0.508 -0.9398)
			(end -0.508 0.9398)
			(stroke
				(width 0.1524)
				(type default)
			)
			(layer "F.SilkS")
		)
		(fp_line
			(start 0.508 -0.9398)
			(end -0.508 -0.9398)
			(stroke
				(width 0.1524)
				(type default)
			)
			(layer "F.SilkS")
		)
		(fp_rect
			(start -0.508 0.9398)
			(end 0.508 -0.9398)
			(stroke
				(width 0)
				(type default)
			)
			(fill no)
			(layer "F.CrtYd")
		)
		(fp_rect
			(start -0.508 0.9398)
			(end 0.508 -0.9398)
			(stroke
				(width 0)
				(type default)
			)
			(fill no)
			(layer "F.Fab")
		)
		(pad "1" smd custom
			(at 0 -0.4445)
			(size 0.1397 0.1397)
			(layers "F.Cu" "F.Mask" "F.Paste")
			(net "GND")
			(options
				(clearance outline)
				(anchor circle)
			)
			(primitives
				(gr_poly
					(pts
						(arc
							(start -0.1778 -0.2794)
							(mid -0.249642 -0.249642)
							(end -0.2794 -0.1778)
						)
						(arc
							(start -0.2794 0.1778)
							(mid -0.249642 0.249642)
							(end -0.1778 0.2794)
						)
						(arc
							(start 0.1778 0.2794)
							(mid 0.249642 0.249642)
							(end 0.2794 0.1778)
						)
						(arc
							(start 0.2794 -0.1778)
							(mid 0.249642 -0.249642)
							(end 0.1778 -0.2794)
						)
					)
					(width 0)
					(fill yes)
				)
			)
		)
		(pad "2" smd custom
			(at 0 0.4445)
			(size 0.1397 0.1397)
			(layers "F.Cu" "F.Mask" "F.Paste")
			(net "MB0_TEMP_E")
			(options
				(clearance outline)
				(anchor circle)
			)
			(primitives
				(gr_poly
					(pts
						(arc
							(start -0.1778 -0.2794)
							(mid -0.249642 -0.249642)
							(end -0.2794 -0.1778)
						)
						(arc
							(start -0.2794 0.1778)
							(mid -0.249642 0.249642)
							(end -0.1778 0.2794)
						)
						(arc
							(start 0.1778 0.2794)
							(mid 0.249642 0.249642)
							(end 0.2794 0.1778)
						)
						(arc
							(start 0.2794 -0.1778)
							(mid 0.249642 -0.249642)
							(end 0.1778 -0.2794)
						)
					)
					(width 0)
					(fill yes)
				)
			)
		)
	)
	(footprint ""
		(layer "F.Cu")
		(at 382.315974 -39.705026)
		(property "Reference" "TP181"
			(at 0 0 0)
			(layer "F.SilkS")
			(hide yes)
			(effects
				(font
					(size 1.27 1.27)
				)
			)
		)
		(property "Value" "*"
			(at -0.0508 -1.6764 0)
			(unlocked yes)
			(layer "F.Fab")
			(hide yes)
			(effects
				(font
					(size 1.016 1.016)
					(thickness 0.1524)
				)
			)
		)
		(property "Device Type" "TPAD32"
			(at -0.0508 -3.2004 0)
			(unlocked yes)
			(layer "F.Fab")
			(hide yes)
			(effects
				(font
					(size 1.016 1.016)
					(thickness 0.1524)
				)
			)
		)
		(duplicate_pad_numbers_are_jumpers no)
		(fp_poly
			(pts
				(arc
					(start 0.4064 0)
					(mid -0.4064 0)
					(end 0.4064 0)
				)
			)
			(stroke
				(width 0)
				(type default)
			)
			(fill no)
			(layer "F.CrtYd")
		)
		(fp_poly
			(pts
				(arc
					(start 0.7112 0)
					(mid -0.7112 0)
					(end 0.7112 0)
				)
			)
			(stroke
				(width 0)
				(type default)
			)
			(fill no)
			(layer "F.Fab")
		)
		(pad "1" smd circle
			(at 0 0)
			(size 0.8128 0.8128)
			(layers "F.Cu" "F.Mask" "F.Paste")
			(net "ACT_HDD_32")
		)
	)
	(footprint ""
		(layer "F.Cu")
		(at 118.618 -157.226)
		(property "Reference" "C230"
			(at 0 0 0)
			(layer "F.SilkS")
			(hide yes)
			(effects
				(font
					(size 1.27 1.27)
				)
			)
		)
		(property "Value" "SC4D7U25V5KX-1-GP"
			(at -0.0762 -6.1214 0)
			(unlocked yes)
			(layer "F.Fab")
			(hide yes)
			(effects
				(font
					(size 1.016 1.016)
					(thickness 0.1524)
				)
			)
		)
		(property "Device Type" "C805H58"
			(at -0.0762 -8.1534 0)
			(unlocked yes)
			(layer "F.Fab")
			(hide yes)
			(effects
				(font
					(size 1.016 1.016)
					(thickness 0.1524)
				)
			)
		)
		(duplicate_pad_numbers_are_jumpers no)
		(fp_line
			(start 0.635 0)
			(end -0.635 0)
			(stroke
				(width 0.508)
				(type default)
			)
			(layer "F.SilkS")
		)
		(fp_rect
			(start -0.9652 1.778)
			(end 0.9652 -1.778)
			(stroke
				(width 0)
				(type default)
			)
			(fill no)
			(layer "F.CrtYd")
		)
		(fp_poly
			(pts
				(xy -0.9652 -1.778) (xy 0.9652 -1.778) (xy 0.9652 1.778) (xy -0.9652 1.778)
			)
			(stroke
				(width 0)
				(type default)
			)
			(fill no)
			(layer "F.Fab")
		)
		(pad "1" smd rect
			(at 0 -0.9652)
			(size 1.397 1.143)
			(layers "F.Cu" "F.Mask" "F.Paste")
			(net "P12V_HDD15")
		)
		(pad "2" smd rect
			(at 0 0.9652)
			(size 1.397 1.143)
			(layers "F.Cu" "F.Mask" "F.Paste")
			(net "GND")
		)
	)
	(footprint ""
		(layer "F.Cu")
		(at 118.237 -11.049 180)
		(property "Reference" "R705"
			(at 0 0 180)
			(layer "F.SilkS")
			(hide yes)
			(effects
				(font
					(size 1.27 1.27)
				)
			)
		)
		(property "Value" "4K7R2J-2-GP"
			(at 0.064008 -3.993896 180)
			(unlocked yes)
			(layer "F.Fab")
			(hide yes)
			(effects
				(font
					(size 1.016 1.016)
					(thickness 0.1524)
				)
			)
		)
		(property "Device Type" "R402H16"
			(at 0.064008 -5.517896 180)
			(unlocked yes)
			(layer "F.Fab")
			(hide yes)
			(effects
				(font
					(size 1.016 1.016)
					(thickness 0.1524)
				)
			)
		)
		(duplicate_pad_numbers_are_jumpers no)
		(fp_line
			(start 0.508 -0.9398)
			(end -0.508 -0.9398)
			(stroke
				(width 0.1524)
				(type default)
			)
			(layer "F.SilkS")
		)
		(fp_line
			(start -0.508 -0.9398)
			(end -0.508 0.9398)
			(stroke
				(width 0.1524)
				(type default)
			)
			(layer "F.SilkS")
		)
		(fp_rect
			(start -0.508 0.9398)
			(end 0.508 -0.9398)
			(stroke
				(width 0)
				(type default)
			)
			(fill no)
			(layer "F.CrtYd")
		)
		(fp_rect
			(start -0.508 0.9398)
			(end 0.508 -0.9398)
			(stroke
				(width 0)
				(type default)
			)
			(fill no)
			(layer "F.Fab")
		)
		(pad "1" smd custom
			(at 0 -0.4445 180)
			(size 0.1397 0.1397)
			(layers "F.Cu" "F.Mask" "F.Paste")
			(net "P12V_B")
			(options
				(clearance outline)
				(anchor circle)
			)
			(primitives
				(gr_poly
					(pts
						(arc
							(start -0.1778 -0.2794)
							(mid -0.249642 -0.249642)
							(end -0.2794 -0.1778)
						)
						(arc
							(start -0.2794 0.1778)
							(mid -0.249642 0.249642)
							(end -0.1778 0.2794)
						)
						(arc
							(start 0.1778 0.2794)
							(mid 0.249642 0.249642)
							(end 0.2794 0.1778)
						)
						(arc
							(start 0.2794 -0.1778)
							(mid 0.249642 -0.249642)
							(end 0.1778 -0.2794)
						)
					)
					(width 0)
					(fill yes)
				)
			)
		)
		(pad "2" smd custom
			(at 0 0.4445 180)
			(size 0.1397 0.1397)
			(layers "F.Cu" "F.Mask" "F.Paste")
			(net "SW_HDD_R27")
			(options
				(clearance outline)
				(anchor circle)
			)
			(primitives
				(gr_poly
					(pts
						(arc
							(start -0.1778 -0.2794)
							(mid -0.249642 -0.249642)
							(end -0.2794 -0.1778)
						)
						(arc
							(start -0.2794 0.1778)
							(mid -0.249642 0.249642)
							(end -0.1778 0.2794)
						)
						(arc
							(start 0.1778 0.2794)
							(mid 0.249642 0.249642)
							(end 0.2794 0.1778)
						)
						(arc
							(start 0.2794 -0.1778)
							(mid 0.249642 -0.249642)
							(end 0.1778 -0.2794)
						)
					)
					(width 0)
					(fill yes)
				)
			)
		)
	)
	(footprint ""
		(layer "F.Cu")
		(at 51.225196 -360.8832)
		(property "Reference" "Q127"
			(at 0 0 0)
			(layer "F.SilkS")
			(hide yes)
			(effects
				(font
					(size 1.27 1.27)
				)
			)
		)
		(property "Value" "AO4407AL-GP"
			(at -3.707384 -1.5367 0)
			(unlocked yes)
			(layer "F.Fab")
			(hide yes)
			(effects
				(font
					(size 1.016 1.016)
					(thickness 0.1524)
				)
			)
		)
		(property "Device Type" "SOIC8H69"
			(at -3.707384 -3.0607 0)
			(unlocked yes)
			(layer "F.Fab")
			(hide yes)
			(effects
				(font
					(size 1.016 1.016)
					(thickness 0.1524)
				)
			)
		)
		(duplicate_pad_numbers_are_jumpers no)
		(fp_line
			(start -2.7432 -1.4224)
			(end -2.7432 1.4224)
			(stroke
				(width 0.1524)
				(type default)
			)
			(layer "F.SilkS")
		)
		(fp_line
			(start -2.7432 1.4224)
			(end -2.6416 1.4224)
			(stroke
				(width 0.1524)
				(type default)
			)
			(layer "F.SilkS")
		)
		(fp_line
			(start -2.7432 1.4224)
			(end 2.1336 1.4224)
			(stroke
				(width 0.1524)
				(type default)
			)
			(layer "F.SilkS")
		)
		(fp_line
			(start -2.7178 -0.508)
			(end -2.1844 -0.0508)
			(stroke
				(width 0.1524)
				(type default)
			)
			(layer "F.SilkS")
		)
		(fp_line
			(start -2.6289 3.4417)
			(end -2.6289 1.4732)
			(stroke
				(width 0.381)
				(type default)
			)
			(layer "F.SilkS")
		)
		(fp_line
			(start -2.1844 -0.0508)
			(end -2.7178 0.508)
			(stroke
				(width 0.1524)
				(type default)
			)
			(layer "F.SilkS")
		)
		(fp_line
			(start 2.1336 -1.4224)
			(end -2.7432 -1.4224)
			(stroke
				(width 0.1524)
				(type default)
			)
			(layer "F.SilkS")
		)
		(fp_line
			(start 2.1336 1.4224)
			(end 2.1336 -1.4224)
			(stroke
				(width 0.1524)
				(type default)
			)
			(layer "F.SilkS")
		)
		(fp_poly
			(pts
				(xy -2.2098 -1.4224) (xy -2.2098 1.4224) (xy 2.2098 1.4224) (xy 2.2098 -1.4224)
			)
			(stroke
				(width 0)
				(type default)
			)
			(fill yes)
			(layer "F.SilkS")
		)
		(fp_rect
			(start -2.450084 2.999994)
			(end 2.450084 -2.999994)
			(stroke
				(width 0)
				(type default)
			)
			(fill no)
			(layer "F.CrtYd")
		)
		(fp_poly
			(pts
				(xy -2.8194 3.6322) (xy -2.8194 -3.6322) (xy 2.8194 -3.6322) (xy 2.8194 1.18364) (xy 2.450084 1.18364)
				(xy 2.450084 -2.999994) (xy -2.450084 -2.999994) (xy -2.450084 2.999994) (xy 2.450084 2.999994)
				(xy 2.450084 1.18618) (xy 2.8194 1.18618) (xy 2.8194 3.6322)
			)
			(stroke
				(width 0)
				(type default)
			)
			(fill no)
			(layer "F.CrtYd")
		)
		(fp_rect
			(start -2.8194 3.6322)
			(end 2.8194 -3.6322)
			(stroke
				(width 0)
				(type default)
			)
			(fill no)
			(layer "F.Fab")
		)
		(pad "1" smd rect
			(at -1.905 2.54)
			(size 0.635 1.651)
			(layers "F.Cu" "F.Mask" "F.Paste")
			(net "P12V_IN")
		)
		(pad "2" smd rect
			(at -0.635 2.54)
			(size 0.635 1.651)
			(layers "F.Cu" "F.Mask" "F.Paste")
			(net "P12V_IN")
		)
		(pad "3" smd rect
			(at 0.635 2.54)
			(size 0.635 1.651)
			(layers "F.Cu" "F.Mask" "F.Paste")
			(net "P12V_IN")
		)
		(pad "4" smd rect
			(at 1.905 2.54)
			(size 0.635 1.651)
			(layers "F.Cu" "F.Mask" "F.Paste")
			(net "GATE_FAN0_R")
		)
		(pad "5" smd rect
			(at 1.905 -2.54)
			(size 0.635 1.651)
			(layers "F.Cu" "F.Mask" "F.Paste")
			(net "P12V_FAN0")
		)
		(pad "6" smd rect
			(at 0.635 -2.54)
			(size 0.635 1.651)
			(layers "F.Cu" "F.Mask" "F.Paste")
			(net "P12V_FAN0")
		)
		(pad "7" smd rect
			(at -0.635 -2.54)
			(size 0.635 1.651)
			(layers "F.Cu" "F.Mask" "F.Paste")
			(net "P12V_FAN0")
		)
		(pad "8" smd rect
			(at -1.905 -2.54)
			(size 0.635 1.651)
			(layers "F.Cu" "F.Mask" "F.Paste")
			(net "P12V_FAN0")
		)
	)
	(footprint ""
		(layer "F.Cu")
		(at 181.356 -14.5796 90)
		(property "Reference" "R754"
			(at 0 0 90)
			(layer "F.SilkS")
			(hide yes)
			(effects
				(font
					(size 1.27 1.27)
				)
			)
		)
		(property "Value" "0R2J-2-GP"
			(at 0.064008 -3.993896 90)
			(unlocked yes)
			(layer "F.Fab")
			(hide yes)
			(effects
				(font
					(size 1.016 1.016)
					(thickness 0.1524)
				)
			)
		)
		(property "Device Type" "R402H16"
			(at 0.064008 -5.517896 90)
			(unlocked yes)
			(layer "F.Fab")
			(hide yes)
			(effects
				(font
					(size 1.016 1.016)
					(thickness 0.1524)
				)
			)
		)
		(duplicate_pad_numbers_are_jumpers no)
		(fp_line
			(start 0.508 -0.9398)
			(end -0.508 -0.9398)
			(stroke
				(width 0.1524)
				(type default)
			)
			(layer "F.SilkS")
		)
		(fp_line
			(start -0.508 -0.9398)
			(end -0.508 0.9398)
			(stroke
				(width 0.1524)
				(type default)
			)
			(layer "F.SilkS")
		)
		(fp_rect
			(start -0.508 0.9398)
			(end 0.508 -0.9398)
			(stroke
				(width 0)
				(type default)
			)
			(fill no)
			(layer "F.CrtYd")
		)
		(fp_rect
			(start -0.508 0.9398)
			(end 0.508 -0.9398)
			(stroke
				(width 0)
				(type default)
			)
			(fill no)
			(layer "F.Fab")
		)
		(pad "1" smd custom
			(at 0 -0.4445 90)
			(size 0.1397 0.1397)
			(layers "F.Cu" "F.Mask" "F.Paste")
			(net "SW_HDD_G29")
			(options
				(clearance outline)
				(anchor circle)
			)
			(primitives
				(gr_poly
					(pts
						(arc
							(start -0.1778 -0.2794)
							(mid -0.249642 -0.249642)
							(end -0.2794 -0.1778)
						)
						(arc
							(start -0.2794 0.1778)
							(mid -0.249642 0.249642)
							(end -0.1778 0.2794)
						)
						(arc
							(start 0.1778 0.2794)
							(mid 0.249642 0.249642)
							(end 0.2794 0.1778)
						)
						(arc
							(start 0.2794 -0.1778)
							(mid 0.249642 -0.249642)
							(end 0.1778 -0.2794)
						)
					)
					(width 0)
					(fill yes)
				)
			)
		)
		(pad "2" smd custom
			(at 0 0.4445 90)
			(size 0.1397 0.1397)
			(layers "F.Cu" "F.Mask" "F.Paste")
			(net "SW_HDD_R29")
			(options
				(clearance outline)
				(anchor circle)
			)
			(primitives
				(gr_poly
					(pts
						(arc
							(start -0.1778 -0.2794)
							(mid -0.249642 -0.249642)
							(end -0.2794 -0.1778)
						)
						(arc
							(start -0.2794 0.1778)
							(mid -0.249642 0.249642)
							(end -0.1778 0.2794)
						)
						(arc
							(start 0.1778 0.2794)
							(mid 0.249642 0.249642)
							(end 0.2794 0.1778)
						)
						(arc
							(start 0.2794 -0.1778)
							(mid 0.249642 -0.249642)
							(end 0.1778 -0.2794)
						)
					)
					(width 0)
					(fill yes)
				)
			)
		)
	)
	(footprint ""
		(layer "F.Cu")
		(at 82.042 -265.684 90)
		(property "Reference" "R192"
			(at 0 0 90)
			(layer "F.SilkS")
			(hide yes)
			(effects
				(font
					(size 1.27 1.27)
				)
			)
		)
		(property "Value" "2R6F-GP"
			(at -0.0508 -4.8514 90)
			(unlocked yes)
			(layer "F.Fab")
			(hide yes)
			(effects
				(font
					(size 1.016 1.016)
					(thickness 0.1524)
				)
			)
		)
		(property "Device Type" "R1206H26"
			(at 0 -6.3754 90)
			(unlocked yes)
			(layer "F.Fab")
			(hide yes)
			(effects
				(font
					(size 1.016 1.016)
					(thickness 0.1524)
				)
			)
		)
		(duplicate_pad_numbers_are_jumpers no)
		(fp_line
			(start 1.016 -2.2352)
			(end 1.016 2.2352)
			(stroke
				(width 0.1524)
				(type default)
			)
			(layer "F.SilkS")
		)
		(fp_line
			(start -1.016 -2.2352)
			(end 1.016 -2.2352)
			(stroke
				(width 0.1524)
				(type default)
			)
			(layer "F.SilkS")
		)
		(fp_line
			(start 1.016 2.2352)
			(end -1.016 2.2352)
			(stroke
				(width 0.1524)
				(type default)
			)
			(layer "F.SilkS")
		)
		(fp_line
			(start -1.016 2.2352)
			(end -1.016 -2.2352)
			(stroke
				(width 0.1524)
				(type default)
			)
			(layer "F.SilkS")
		)
		(fp_rect
			(start -1.0922 2.3114)
			(end 1.0922 -2.3114)
			(stroke
				(width 0)
				(type default)
			)
			(fill no)
			(layer "F.CrtYd")
		)
		(fp_poly
			(pts
				(xy -1.0922 -2.3114) (xy 1.0922 -2.3114) (xy 1.0922 2.3114) (xy -1.0922 2.3114)
			)
			(stroke
				(width 0)
				(type default)
			)
			(fill no)
			(layer "F.Fab")
		)
		(pad "1" smd rect
			(at 0 -1.397 90)
			(size 1.651 1.27)
			(layers "F.Cu" "F.Mask" "F.Paste")
			(net "P12V_HDD2")
		)
		(pad "2" smd rect
			(at 0 1.397 90)
			(size 1.651 1.27)
			(layers "F.Cu" "F.Mask" "F.Paste")
			(net "12V_PRE_2")
		)
	)
	(footprint ""
		(layer "F.Cu")
		(at 331.7494 -250.4948 -90)
		(property "Reference" "C116"
			(at 0 0 270)
			(layer "F.SilkS")
			(hide yes)
			(effects
				(font
					(size 1.27 1.27)
				)
			)
		)
		(property "Value" "SCD033U25V2KX-GP"
			(at 1.1811 -2.7051 270)
			(unlocked yes)
			(layer "F.Fab")
			(hide yes)
			(effects
				(font
					(size 1.016 1.016)
					(thickness 0.1524)
				)
			)
		)
		(property "Device Type" "C402H22"
			(at 1.1811 -4.2291 270)
			(unlocked yes)
			(layer "F.Fab")
			(hide yes)
			(effects
				(font
					(size 1.016 1.016)
					(thickness 0.1524)
				)
			)
		)
		(duplicate_pad_numbers_are_jumpers no)
		(fp_rect
			(start -0.4318 0.9525)
			(end 0.4318 -0.9525)
			(stroke
				(width 0)
				(type default)
			)
			(fill no)
			(layer "F.CrtYd")
		)
		(fp_rect
			(start -0.4318 0.9525)
			(end 0.4318 -0.9525)
			(stroke
				(width 0)
				(type default)
			)
			(fill no)
			(layer "F.Fab")
		)
		(pad "1" smd custom
			(at 0 -0.4445 270)
			(size 0.1524 0.1524)
			(layers "F.Cu" "F.Mask" "F.Paste")
			(net "SW_HDD_P6")
			(options
				(clearance outline)
				(anchor circle)
			)
			(primitives
				(gr_poly
					(pts
						(arc
							(start 0.3048 -0.2032)
							(mid 0.275042 -0.275042)
							(end 0.2032 -0.3048)
						)
						(arc
							(start -0.2032 -0.3048)
							(mid -0.275042 -0.275042)
							(end -0.3048 -0.2032)
						)
						(arc
							(start -0.3048 0.2032)
							(mid -0.275042 0.275042)
							(end -0.2032 0.3048)
						)
						(arc
							(start 0.2032 0.3048)
							(mid 0.275042 0.275042)
							(end 0.3048 0.2032)
						)
					)
					(width 0)
					(fill yes)
				)
			)
		)
		(pad "2" smd custom
			(at 0 0.4445 270)
			(size 0.1524 0.1524)
			(layers "F.Cu" "F.Mask" "F.Paste")
			(net "GND")
			(options
				(clearance outline)
				(anchor circle)
			)
			(primitives
				(gr_poly
					(pts
						(arc
							(start 0.3048 -0.2032)
							(mid 0.275042 -0.275042)
							(end 0.2032 -0.3048)
						)
						(arc
							(start -0.2032 -0.3048)
							(mid -0.275042 -0.275042)
							(end -0.3048 -0.2032)
						)
						(arc
							(start -0.3048 0.2032)
							(mid -0.275042 0.275042)
							(end -0.2032 0.3048)
						)
						(arc
							(start 0.2032 0.3048)
							(mid 0.275042 0.275042)
							(end 0.3048 0.2032)
						)
					)
					(width 0)
					(fill yes)
				)
			)
		)
	)
	(footprint ""
		(layer "F.Cu")
		(at 454.98766 -222.048324 90)
		(property "Reference" "C658"
			(at 0 0 90)
			(layer "F.SilkS")
			(hide yes)
			(effects
				(font
					(size 1.27 1.27)
				)
			)
		)
		(property "Value" "SC10U16V5KX-7-GP-U"
			(at -0.0762 -6.1214 90)
			(unlocked yes)
			(layer "F.Fab")
			(hide yes)
			(effects
				(font
					(size 1.016 1.016)
					(thickness 0.1524)
				)
			)
		)
		(property "Device Type" "C805H58"
			(at -0.0762 -8.1534 90)
			(unlocked yes)
			(layer "F.Fab")
			(hide yes)
			(effects
				(font
					(size 1.016 1.016)
					(thickness 0.1524)
				)
			)
		)
		(duplicate_pad_numbers_are_jumpers no)
		(fp_line
			(start 0.635 0)
			(end -0.635 0)
			(stroke
				(width 0.508)
				(type default)
			)
			(layer "F.SilkS")
		)
		(fp_rect
			(start -0.9652 1.778)
			(end 0.9652 -1.778)
			(stroke
				(width 0)
				(type default)
			)
			(fill no)
			(layer "F.CrtYd")
		)
		(fp_poly
			(pts
				(xy -0.9652 -1.778) (xy 0.9652 -1.778) (xy 0.9652 1.778) (xy -0.9652 1.778)
			)
			(stroke
				(width 0)
				(type default)
			)
			(fill no)
			(layer "F.Fab")
		)
		(pad "1" smd rect
			(at 0 -0.9652 90)
			(size 1.397 1.143)
			(layers "F.Cu" "F.Mask" "F.Paste")
			(net "P12V_B_3_VIN_U33")
		)
		(pad "2" smd rect
			(at 0 0.9652 90)
			(size 1.397 1.143)
			(layers "F.Cu" "F.Mask" "F.Paste")
			(net "GND")
		)
	)
	(footprint ""
		(layer "F.Cu")
		(at 176.276 -374.904 90)
		(property "Reference" "C542"
			(at 0 0 90)
			(layer "F.SilkS")
			(hide yes)
			(effects
				(font
					(size 1.27 1.27)
				)
			)
		)
		(property "Value" "SCD1U16V2KX-3GP"
			(at 1.1811 -2.7051 90)
			(unlocked yes)
			(layer "F.Fab")
			(hide yes)
			(effects
				(font
					(size 1.016 1.016)
					(thickness 0.1524)
				)
			)
		)
		(property "Device Type" "C402H22"
			(at 1.1811 -4.2291 90)
			(unlocked yes)
			(layer "F.Fab")
			(hide yes)
			(effects
				(font
					(size 1.016 1.016)
					(thickness 0.1524)
				)
			)
		)
		(duplicate_pad_numbers_are_jumpers no)
		(fp_rect
			(start -0.4318 0.9525)
			(end 0.4318 -0.9525)
			(stroke
				(width 0)
				(type default)
			)
			(fill no)
			(layer "F.CrtYd")
		)
		(fp_rect
			(start -0.4318 0.9525)
			(end 0.4318 -0.9525)
			(stroke
				(width 0)
				(type default)
			)
			(fill no)
			(layer "F.Fab")
		)
		(pad "1" smd custom
			(at 0 -0.4445 90)
			(size 0.1524 0.1524)
			(layers "F.Cu" "F.Mask" "F.Paste")
			(net "MB0_CM_VOUT_R")
			(options
				(clearance outline)
				(anchor circle)
			)
			(primitives
				(gr_poly
					(pts
						(arc
							(start 0.3048 -0.2032)
							(mid 0.275042 -0.275042)
							(end 0.2032 -0.3048)
						)
						(arc
							(start -0.2032 -0.3048)
							(mid -0.275042 -0.275042)
							(end -0.3048 -0.2032)
						)
						(arc
							(start -0.3048 0.2032)
							(mid -0.275042 0.275042)
							(end -0.2032 0.3048)
						)
						(arc
							(start 0.2032 0.3048)
							(mid 0.275042 0.275042)
							(end 0.3048 0.2032)
						)
					)
					(width 0)
					(fill yes)
				)
			)
		)
		(pad "2" smd custom
			(at 0 0.4445 90)
			(size 0.1524 0.1524)
			(layers "F.Cu" "F.Mask" "F.Paste")
			(net "AGND_CURRENT_MON")
			(options
				(clearance outline)
				(anchor circle)
			)
			(primitives
				(gr_poly
					(pts
						(arc
							(start 0.3048 -0.2032)
							(mid 0.275042 -0.275042)
							(end 0.2032 -0.3048)
						)
						(arc
							(start -0.2032 -0.3048)
							(mid -0.275042 -0.275042)
							(end -0.3048 -0.2032)
						)
						(arc
							(start -0.3048 0.2032)
							(mid -0.275042 0.275042)
							(end -0.2032 0.3048)
						)
						(arc
							(start 0.2032 0.3048)
							(mid 0.275042 0.275042)
							(end 0.3048 0.2032)
						)
					)
					(width 0)
					(fill yes)
				)
			)
		)
	)
	(footprint ""
		(layer "F.Cu")
		(at 244.37848 -193.29654 -90)
		(property "Reference" "R74"
			(at 0 0 270)
			(layer "F.SilkS")
			(hide yes)
			(effects
				(font
					(size 1.27 1.27)
				)
			)
		)
		(property "Value" "4K7R2F-GP"
			(at 0.064008 -3.993896 270)
			(unlocked yes)
			(layer "F.Fab")
			(hide yes)
			(effects
				(font
					(size 1.016 1.016)
					(thickness 0.1524)
				)
			)
		)
		(property "Device Type" "R402H16"
			(at 0.064008 -5.517896 270)
			(unlocked yes)
			(layer "F.Fab")
			(hide yes)
			(effects
				(font
					(size 1.016 1.016)
					(thickness 0.1524)
				)
			)
		)
		(duplicate_pad_numbers_are_jumpers no)
		(fp_line
			(start -0.508 -0.9398)
			(end -0.508 0.9398)
			(stroke
				(width 0.1524)
				(type default)
			)
			(layer "F.SilkS")
		)
		(fp_line
			(start 0.508 -0.9398)
			(end -0.508 -0.9398)
			(stroke
				(width 0.1524)
				(type default)
			)
			(layer "F.SilkS")
		)
		(fp_rect
			(start -0.508 0.9398)
			(end 0.508 -0.9398)
			(stroke
				(width 0)
				(type default)
			)
			(fill no)
			(layer "F.CrtYd")
		)
		(fp_rect
			(start -0.508 0.9398)
			(end 0.508 -0.9398)
			(stroke
				(width 0)
				(type default)
			)
			(fill no)
			(layer "F.Fab")
		)
		(pad "1" smd custom
			(at 0 -0.4445 270)
			(size 0.1397 0.1397)
			(layers "F.Cu" "F.Mask" "F.Paste")
			(net "P3V3_STBY_B")
			(options
				(clearance outline)
				(anchor circle)
			)
			(primitives
				(gr_poly
					(pts
						(arc
							(start -0.1778 -0.2794)
							(mid -0.249642 -0.249642)
							(end -0.2794 -0.1778)
						)
						(arc
							(start -0.2794 0.1778)
							(mid -0.249642 0.249642)
							(end -0.1778 0.2794)
						)
						(arc
							(start 0.1778 0.2794)
							(mid 0.249642 0.249642)
							(end 0.2794 0.1778)
						)
						(arc
							(start 0.2794 -0.1778)
							(mid 0.249642 -0.249642)
							(end 0.1778 -0.2794)
						)
					)
					(width 0)
					(fill yes)
				)
			)
		)
		(pad "2" smd custom
			(at 0 0.4445 270)
			(size 0.1397 0.1397)
			(layers "F.Cu" "F.Mask" "F.Paste")
			(net "IO_EXP2_INT_N")
			(options
				(clearance outline)
				(anchor circle)
			)
			(primitives
				(gr_poly
					(pts
						(arc
							(start -0.1778 -0.2794)
							(mid -0.249642 -0.249642)
							(end -0.2794 -0.1778)
						)
						(arc
							(start -0.2794 0.1778)
							(mid -0.249642 0.249642)
							(end -0.1778 0.2794)
						)
						(arc
							(start 0.1778 0.2794)
							(mid 0.249642 0.249642)
							(end 0.2794 0.1778)
						)
						(arc
							(start 0.2794 -0.1778)
							(mid 0.249642 -0.249642)
							(end 0.1778 -0.2794)
						)
					)
					(width 0)
					(fill yes)
				)
			)
		)
	)
	(footprint ""
		(layer "F.Cu")
		(at 109.982 -14.3764)
		(property "Reference" "Q138"
			(at 0 0 0)
			(layer "F.SilkS")
			(hide yes)
			(effects
				(font
					(size 1.27 1.27)
				)
			)
		)
		(property "Value" "AO4407AL-GP"
			(at -3.707384 -1.5367 0)
			(unlocked yes)
			(layer "F.Fab")
			(hide yes)
			(effects
				(font
					(size 1.016 1.016)
					(thickness 0.1524)
				)
			)
		)
		(property "Device Type" "SOIC8H69"
			(at -3.707384 -3.0607 0)
			(unlocked yes)
			(layer "F.Fab")
			(hide yes)
			(effects
				(font
					(size 1.016 1.016)
					(thickness 0.1524)
				)
			)
		)
		(duplicate_pad_numbers_are_jumpers no)
		(fp_line
			(start -2.7432 -1.4224)
			(end -2.7432 1.4224)
			(stroke
				(width 0.1524)
				(type default)
			)
			(layer "F.SilkS")
		)
		(fp_line
			(start -2.7432 1.4224)
			(end -2.6416 1.4224)
			(stroke
				(width 0.1524)
				(type default)
			)
			(layer "F.SilkS")
		)
		(fp_line
			(start -2.7432 1.4224)
			(end 2.1336 1.4224)
			(stroke
				(width 0.1524)
				(type default)
			)
			(layer "F.SilkS")
		)
		(fp_line
			(start -2.7178 -0.508)
			(end -2.1844 -0.0508)
			(stroke
				(width 0.1524)
				(type default)
			)
			(layer "F.SilkS")
		)
		(fp_line
			(start -2.6289 3.4417)
			(end -2.6289 1.4732)
			(stroke
				(width 0.381)
				(type default)
			)
			(layer "F.SilkS")
		)
		(fp_line
			(start -2.1844 -0.0508)
			(end -2.7178 0.508)
			(stroke
				(width 0.1524)
				(type default)
			)
			(layer "F.SilkS")
		)
		(fp_line
			(start 2.1336 -1.4224)
			(end -2.7432 -1.4224)
			(stroke
				(width 0.1524)
				(type default)
			)
			(layer "F.SilkS")
		)
		(fp_line
			(start 2.1336 1.4224)
			(end 2.1336 -1.4224)
			(stroke
				(width 0.1524)
				(type default)
			)
			(layer "F.SilkS")
		)
		(fp_poly
			(pts
				(xy -2.2098 -1.4224) (xy -2.2098 1.4224) (xy 2.2098 1.4224) (xy 2.2098 -1.4224)
			)
			(stroke
				(width 0)
				(type default)
			)
			(fill yes)
			(layer "F.SilkS")
		)
		(fp_rect
			(start -2.450084 2.999994)
			(end 2.450084 -2.999994)
			(stroke
				(width 0)
				(type default)
			)
			(fill no)
			(layer "F.CrtYd")
		)
		(fp_poly
			(pts
				(xy -2.8194 3.6322) (xy -2.8194 -3.6322) (xy 2.8194 -3.6322) (xy 2.8194 1.18364) (xy 2.450084 1.18364)
				(xy 2.450084 -2.999994) (xy -2.450084 -2.999994) (xy -2.450084 2.999994) (xy 2.450084 2.999994)
				(xy 2.450084 1.18618) (xy 2.8194 1.18618) (xy 2.8194 3.6322)
			)
			(stroke
				(width 0)
				(type default)
			)
			(fill no)
			(layer "F.CrtYd")
		)
		(fp_rect
			(start -2.8194 3.6322)
			(end 2.8194 -3.6322)
			(stroke
				(width 0)
				(type default)
			)
			(fill no)
			(layer "F.Fab")
		)
		(pad "1" smd rect
			(at -1.905 2.54)
			(size 0.635 1.651)
			(layers "F.Cu" "F.Mask" "F.Paste")
			(net "P12V_B")
		)
		(pad "2" smd rect
			(at -0.635 2.54)
			(size 0.635 1.651)
			(layers "F.Cu" "F.Mask" "F.Paste")
			(net "P12V_B")
		)
		(pad "3" smd rect
			(at 0.635 2.54)
			(size 0.635 1.651)
			(layers "F.Cu" "F.Mask" "F.Paste")
			(net "P12V_B")
		)
		(pad "4" smd rect
			(at 1.905 2.54)
			(size 0.635 1.651)
			(layers "F.Cu" "F.Mask" "F.Paste")
			(net "SW_HDD_N27")
		)
		(pad "5" smd rect
			(at 1.905 -2.54)
			(size 0.635 1.651)
			(layers "F.Cu" "F.Mask" "F.Paste")
			(net "P12V_HDD27")
		)
		(pad "6" smd rect
			(at 0.635 -2.54)
			(size 0.635 1.651)
			(layers "F.Cu" "F.Mask" "F.Paste")
			(net "P12V_HDD27")
		)
		(pad "7" smd rect
			(at -0.635 -2.54)
			(size 0.635 1.651)
			(layers "F.Cu" "F.Mask" "F.Paste")
			(net "P12V_HDD27")
		)
		(pad "8" smd rect
			(at -1.905 -2.54)
			(size 0.635 1.651)
			(layers "F.Cu" "F.Mask" "F.Paste")
			(net "P12V_HDD27")
		)
	)
	(footprint ""
		(layer "F.Cu")
		(at 160.963864 -154.70505)
		(property "Reference" "TP101"
			(at 0 0 0)
			(layer "F.SilkS")
			(hide yes)
			(effects
				(font
					(size 1.27 1.27)
				)
			)
		)
		(property "Value" "*"
			(at -0.0508 -1.6764 0)
			(unlocked yes)
			(layer "F.Fab")
			(hide yes)
			(effects
				(font
					(size 1.016 1.016)
					(thickness 0.1524)
				)
			)
		)
		(property "Device Type" "TPAD32"
			(at -0.0508 -3.2004 0)
			(unlocked yes)
			(layer "F.Fab")
			(hide yes)
			(effects
				(font
					(size 1.016 1.016)
					(thickness 0.1524)
				)
			)
		)
		(duplicate_pad_numbers_are_jumpers no)
		(fp_poly
			(pts
				(arc
					(start 0.4064 0)
					(mid -0.4064 0)
					(end 0.4064 0)
				)
			)
			(stroke
				(width 0)
				(type default)
			)
			(fill no)
			(layer "F.CrtYd")
		)
		(fp_poly
			(pts
				(arc
					(start 0.7112 0)
					(mid -0.7112 0)
					(end 0.7112 0)
				)
			)
			(stroke
				(width 0)
				(type default)
			)
			(fill no)
			(layer "F.Fab")
		)
		(pad "1" smd circle
			(at 0 0)
			(size 0.8128 0.8128)
			(layers "F.Cu" "F.Mask" "F.Paste")
			(net "ACT_HDD_16")
		)
	)
	(footprint ""
		(layer "F.Cu")
		(at 146.4564 -33.782 -90)
		(property "Reference" "C394"
			(at 0 0 270)
			(layer "F.SilkS")
			(hide yes)
			(effects
				(font
					(size 1.27 1.27)
				)
			)
		)
		(property "Value" "SC1U16V3KX-5GP"
			(at 0 -2.8194 270)
			(unlocked yes)
			(layer "F.Fab")
			(hide yes)
			(effects
				(font
					(size 1.016 1.016)
					(thickness 0.1524)
				)
			)
		)
		(property "Device Type" "C603H36"
			(at 0 -4.3434 270)
			(unlocked yes)
			(layer "F.Fab")
			(hide yes)
			(effects
				(font
					(size 1.016 1.016)
					(thickness 0.1524)
				)
			)
		)
		(duplicate_pad_numbers_are_jumpers no)
		(fp_line
			(start 0.508 0)
			(end -0.508 0)
			(stroke
				(width 0.2032)
				(type default)
			)
			(layer "F.SilkS")
		)
		(fp_rect
			(start -0.5842 1.3335)
			(end 0.5842 -1.3335)
			(stroke
				(width 0)
				(type default)
			)
			(fill no)
			(layer "F.CrtYd")
		)
		(fp_rect
			(start -0.5842 1.3335)
			(end 0.5842 -1.3335)
			(stroke
				(width 0)
				(type default)
			)
			(fill no)
			(layer "F.Fab")
		)
		(pad "1" smd custom
			(at 0 -0.762 270)
			(size 0.2159 0.2159)
			(layers "F.Cu" "F.Mask" "F.Paste")
			(net "P5V_HDD28")
			(options
				(clearance outline)
				(anchor circle)
			)
			(primitives
				(gr_poly
					(pts
						(arc
							(start -0.3302 -0.4318)
							(mid -0.402042 -0.402042)
							(end -0.4318 -0.3302)
						)
						(arc
							(start -0.4318 0.3302)
							(mid -0.402042 0.402042)
							(end -0.3302 0.4318)
						)
						(arc
							(start 0.3302 0.4318)
							(mid 0.402042 0.402042)
							(end 0.4318 0.3302)
						)
						(arc
							(start 0.4318 -0.3302)
							(mid 0.402042 -0.402042)
							(end 0.3302 -0.4318)
						)
					)
					(width 0)
					(fill yes)
				)
			)
		)
		(pad "2" smd custom
			(at 0 0.762 270)
			(size 0.2159 0.2159)
			(layers "F.Cu" "F.Mask" "F.Paste")
			(net "GND")
			(options
				(clearance outline)
				(anchor circle)
			)
			(primitives
				(gr_poly
					(pts
						(arc
							(start -0.3302 -0.4318)
							(mid -0.402042 -0.402042)
							(end -0.4318 -0.3302)
						)
						(arc
							(start -0.4318 0.3302)
							(mid -0.402042 0.402042)
							(end -0.3302 0.4318)
						)
						(arc
							(start 0.3302 0.4318)
							(mid 0.402042 0.402042)
							(end 0.4318 0.3302)
						)
						(arc
							(start 0.4318 -0.3302)
							(mid 0.402042 -0.402042)
							(end 0.3302 -0.4318)
						)
					)
					(width 0)
					(fill yes)
				)
			)
		)
	)
	(footprint ""
		(layer "F.Cu")
		(at 334.899 -138.938 -90)
		(property "Reference" "Q82"
			(at 0 0 270)
			(layer "F.SilkS")
			(hide yes)
			(effects
				(font
					(size 1.27 1.27)
				)
			)
		)
		(property "Value" "AO4406AL-GP"
			(at -3.707384 -1.5367 270)
			(unlocked yes)
			(layer "F.Fab")
			(hide yes)
			(effects
				(font
					(size 1.016 1.016)
					(thickness 0.1524)
				)
			)
		)
		(property "Device Type" "SOIC8H69"
			(at -3.707384 -3.0607 270)
			(unlocked yes)
			(layer "F.Fab")
			(hide yes)
			(effects
				(font
					(size 1.016 1.016)
					(thickness 0.1524)
				)
			)
		)
		(duplicate_pad_numbers_are_jumpers no)
		(fp_line
			(start -2.6289 3.4417)
			(end -2.6289 1.4732)
			(stroke
				(width 0.381)
				(type default)
			)
			(layer "F.SilkS")
		)
		(fp_line
			(start -2.7432 1.4224)
			(end -2.6416 1.4224)
			(stroke
				(width 0.1524)
				(type default)
			)
			(layer "F.SilkS")
		)
		(fp_line
			(start -2.7432 1.4224)
			(end 2.1336 1.4224)
			(stroke
				(width 0.1524)
				(type default)
			)
			(layer "F.SilkS")
		)
		(fp_line
			(start 2.1336 1.4224)
			(end 2.1336 -1.4224)
			(stroke
				(width 0.1524)
				(type default)
			)
			(layer "F.SilkS")
		)
		(fp_line
			(start -2.1844 -0.0508)
			(end -2.7178 0.508)
			(stroke
				(width 0.1524)
				(type default)
			)
			(layer "F.SilkS")
		)
		(fp_line
			(start -2.7178 -0.508)
			(end -2.1844 -0.0508)
			(stroke
				(width 0.1524)
				(type default)
			)
			(layer "F.SilkS")
		)
		(fp_line
			(start -2.7432 -1.4224)
			(end -2.7432 1.4224)
			(stroke
				(width 0.1524)
				(type default)
			)
			(layer "F.SilkS")
		)
		(fp_line
			(start 2.1336 -1.4224)
			(end -2.7432 -1.4224)
			(stroke
				(width 0.1524)
				(type default)
			)
			(layer "F.SilkS")
		)
		(fp_poly
			(pts
				(xy -2.2098 -1.4224) (xy -2.2098 1.4224) (xy 2.2098 1.4224) (xy 2.2098 -1.4224)
			)
			(stroke
				(width 0)
				(type default)
			)
			(fill yes)
			(layer "F.SilkS")
		)
		(fp_rect
			(start -2.450084 2.999994)
			(end 2.450084 -2.999994)
			(stroke
				(width 0)
				(type default)
			)
			(fill no)
			(layer "F.CrtYd")
		)
		(fp_poly
			(pts
				(xy -2.8194 3.6322) (xy -2.8194 -3.6322) (xy 2.8194 -3.6322) (xy 2.8194 1.18364) (xy 2.450084 1.18364)
				(xy 2.450084 -2.999994) (xy -2.450084 -2.999994) (xy -2.450084 2.999994) (xy 2.450084 2.999994)
				(xy 2.450084 1.18618) (xy 2.8194 1.18618) (xy 2.8194 3.6322)
			)
			(stroke
				(width 0)
				(type default)
			)
			(fill no)
			(layer "F.CrtYd")
		)
		(fp_rect
			(start -2.8194 3.6322)
			(end 2.8194 -3.6322)
			(stroke
				(width 0)
				(type default)
			)
			(fill no)
			(layer "F.Fab")
		)
		(pad "1" smd rect
			(at -1.905 2.54 270)
			(size 0.635 1.651)
			(layers "F.Cu" "F.Mask" "F.Paste")
			(net "P5V_HDD18")
		)
		(pad "2" smd rect
			(at -0.635 2.54 270)
			(size 0.635 1.651)
			(layers "F.Cu" "F.Mask" "F.Paste")
			(net "P5V_HDD18")
		)
		(pad "3" smd rect
			(at 0.635 2.54 270)
			(size 0.635 1.651)
			(layers "F.Cu" "F.Mask" "F.Paste")
			(net "P5V_HDD18")
		)
		(pad "4" smd rect
			(at 1.905 2.54 270)
			(size 0.635 1.651)
			(layers "F.Cu" "F.Mask" "F.Paste")
			(net "SW_HDD_P18")
		)
		(pad "5" smd rect
			(at 1.905 -2.54 270)
			(size 0.635 1.651)
			(layers "F.Cu" "F.Mask" "F.Paste")
			(net "P5V_B_3")
		)
		(pad "6" smd rect
			(at 0.635 -2.54 270)
			(size 0.635 1.651)
			(layers "F.Cu" "F.Mask" "F.Paste")
			(net "P5V_B_3")
		)
		(pad "7" smd rect
			(at -0.635 -2.54 270)
			(size 0.635 1.651)
			(layers "F.Cu" "F.Mask" "F.Paste")
			(net "P5V_B_3")
		)
		(pad "8" smd rect
			(at -1.905 -2.54 270)
			(size 0.635 1.651)
			(layers "F.Cu" "F.Mask" "F.Paste")
			(net "P5V_B_3")
		)
	)
	(footprint ""
		(layer "F.Cu")
		(at 444.929768 -102.26802 -90)
		(property "Reference" "R486"
			(at 0 0 270)
			(layer "F.SilkS")
			(hide yes)
			(effects
				(font
					(size 1.27 1.27)
				)
			)
		)
		(property "Value" "4K7R2F-GP"
			(at 0.064008 -3.993896 270)
			(unlocked yes)
			(layer "F.Fab")
			(hide yes)
			(effects
				(font
					(size 1.016 1.016)
					(thickness 0.1524)
				)
			)
		)
		(property "Device Type" "R402H16"
			(at 0.064008 -5.517896 270)
			(unlocked yes)
			(layer "F.Fab")
			(hide yes)
			(effects
				(font
					(size 1.016 1.016)
					(thickness 0.1524)
				)
			)
		)
		(duplicate_pad_numbers_are_jumpers no)
		(fp_line
			(start -0.508 -0.9398)
			(end -0.508 0.9398)
			(stroke
				(width 0.1524)
				(type default)
			)
			(layer "F.SilkS")
		)
		(fp_line
			(start 0.508 -0.9398)
			(end -0.508 -0.9398)
			(stroke
				(width 0.1524)
				(type default)
			)
			(layer "F.SilkS")
		)
		(fp_rect
			(start -0.508 0.9398)
			(end 0.508 -0.9398)
			(stroke
				(width 0)
				(type default)
			)
			(fill no)
			(layer "F.CrtYd")
		)
		(fp_rect
			(start -0.508 0.9398)
			(end 0.508 -0.9398)
			(stroke
				(width 0)
				(type default)
			)
			(fill no)
			(layer "F.Fab")
		)
		(pad "1" smd custom
			(at 0 -0.4445 270)
			(size 0.1397 0.1397)
			(layers "F.Cu" "F.Mask" "F.Paste")
			(net "DRIVE_B_22_ACT")
			(options
				(clearance outline)
				(anchor circle)
			)
			(primitives
				(gr_poly
					(pts
						(arc
							(start -0.1778 -0.2794)
							(mid -0.249642 -0.249642)
							(end -0.2794 -0.1778)
						)
						(arc
							(start -0.2794 0.1778)
							(mid -0.249642 0.249642)
							(end -0.1778 0.2794)
						)
						(arc
							(start 0.1778 0.2794)
							(mid 0.249642 0.249642)
							(end 0.2794 0.1778)
						)
						(arc
							(start 0.2794 -0.1778)
							(mid 0.249642 -0.249642)
							(end 0.1778 -0.2794)
						)
					)
					(width 0)
					(fill yes)
				)
			)
		)
		(pad "2" smd custom
			(at 0 0.4445 270)
			(size 0.1397 0.1397)
			(layers "F.Cu" "F.Mask" "F.Paste")
			(net "GND")
			(options
				(clearance outline)
				(anchor circle)
			)
			(primitives
				(gr_poly
					(pts
						(arc
							(start -0.1778 -0.2794)
							(mid -0.249642 -0.249642)
							(end -0.2794 -0.1778)
						)
						(arc
							(start -0.2794 0.1778)
							(mid -0.249642 0.249642)
							(end -0.1778 0.2794)
						)
						(arc
							(start 0.1778 0.2794)
							(mid 0.249642 0.249642)
							(end 0.2794 0.1778)
						)
						(arc
							(start 0.2794 -0.1778)
							(mid 0.249642 -0.249642)
							(end 0.1778 -0.2794)
						)
					)
					(width 0)
					(fill yes)
				)
			)
		)
	)
	(footprint ""
		(layer "F.Cu")
		(at 146.304 -262.001 -90)
		(property "Reference" "C83"
			(at 0 0 270)
			(layer "F.SilkS")
			(hide yes)
			(effects
				(font
					(size 1.27 1.27)
				)
			)
		)
		(property "Value" "SC10U16V6KX-2GP"
			(at -0.0762 -5.1308 270)
			(unlocked yes)
			(layer "F.Fab")
			(hide yes)
			(effects
				(font
					(size 1.016 1.016)
					(thickness 0.1524)
				)
			)
		)
		(property "Device Type" "C1206H71"
			(at -0.127 -6.6548 270)
			(unlocked yes)
			(layer "F.Fab")
			(hide yes)
			(effects
				(font
					(size 1.016 1.016)
					(thickness 0.1524)
				)
			)
		)
		(duplicate_pad_numbers_are_jumpers no)
		(fp_line
			(start -1.016 2.2352)
			(end -1.016 0.8382)
			(stroke
				(width 0.1524)
				(type default)
			)
			(layer "F.SilkS")
		)
		(fp_line
			(start 1.016 2.2352)
			(end -1.016 2.2352)
			(stroke
				(width 0.1524)
				(type default)
			)
			(layer "F.SilkS")
		)
		(fp_line
			(start 1.016 0.8382)
			(end 1.016 2.2352)
			(stroke
				(width 0.1524)
				(type default)
			)
			(layer "F.SilkS")
		)
		(fp_line
			(start -1.016 -0.8382)
			(end -1.016 -2.2352)
			(stroke
				(width 0.1524)
				(type default)
			)
			(layer "F.SilkS")
		)
		(fp_line
			(start -1.016 -2.2352)
			(end 1.016 -2.2352)
			(stroke
				(width 0.1524)
				(type default)
			)
			(layer "F.SilkS")
		)
		(fp_line
			(start 1.016 -2.2352)
			(end 1.016 -0.8382)
			(stroke
				(width 0.1524)
				(type default)
			)
			(layer "F.SilkS")
		)
		(fp_rect
			(start -1.0922 2.3114)
			(end 1.0922 -2.3114)
			(stroke
				(width 0)
				(type default)
			)
			(fill no)
			(layer "F.CrtYd")
		)
		(fp_poly
			(pts
				(xy 1.0922 -2.3114) (xy 1.0922 2.3114) (xy -1.0922 2.3114) (xy -1.0922 -2.3114)
			)
			(stroke
				(width 0)
				(type default)
			)
			(fill no)
			(layer "F.Fab")
		)
		(pad "1" smd rect
			(at 0 -1.397 270)
			(size 1.651 1.27)
			(layers "F.Cu" "F.Mask" "F.Paste")
			(net "P5V_HDD4")
		)
		(pad "2" smd rect
			(at 0 1.397 270)
			(size 1.651 1.27)
			(layers "F.Cu" "F.Mask" "F.Paste")
			(net "GND")
		)
	)
	(footprint ""
		(layer "F.Cu")
		(at 20.701 -26.289 180)
		(property "Reference" "Q118"
			(at 0 0 180)
			(layer "F.SilkS")
			(hide yes)
			(effects
				(font
					(size 1.27 1.27)
				)
			)
		)
		(property "Value" "AO4406AL-GP"
			(at -3.707384 -1.5367 180)
			(unlocked yes)
			(layer "F.Fab")
			(hide yes)
			(effects
				(font
					(size 1.016 1.016)
					(thickness 0.1524)
				)
			)
		)
		(property "Device Type" "SOIC8H69"
			(at -3.707384 -3.0607 180)
			(unlocked yes)
			(layer "F.Fab")
			(hide yes)
			(effects
				(font
					(size 1.016 1.016)
					(thickness 0.1524)
				)
			)
		)
		(duplicate_pad_numbers_are_jumpers no)
		(fp_line
			(start 2.1336 1.4224)
			(end 2.1336 -1.4224)
			(stroke
				(width 0.1524)
				(type default)
			)
			(layer "F.SilkS")
		)
		(fp_line
			(start 2.1336 -1.4224)
			(end -2.7432 -1.4224)
			(stroke
				(width 0.1524)
				(type default)
			)
			(layer "F.SilkS")
		)
		(fp_line
			(start -2.1844 -0.0508)
			(end -2.7178 0.508)
			(stroke
				(width 0.1524)
				(type default)
			)
			(layer "F.SilkS")
		)
		(fp_line
			(start -2.6289 3.4417)
			(end -2.6289 1.4732)
			(stroke
				(width 0.381)
				(type default)
			)
			(layer "F.SilkS")
		)
		(fp_line
			(start -2.7178 -0.508)
			(end -2.1844 -0.0508)
			(stroke
				(width 0.1524)
				(type default)
			)
			(layer "F.SilkS")
		)
		(fp_line
			(start -2.7432 1.4224)
			(end 2.1336 1.4224)
			(stroke
				(width 0.1524)
				(type default)
			)
			(layer "F.SilkS")
		)
		(fp_line
			(start -2.7432 1.4224)
			(end -2.6416 1.4224)
			(stroke
				(width 0.1524)
				(type default)
			)
			(layer "F.SilkS")
		)
		(fp_line
			(start -2.7432 -1.4224)
			(end -2.7432 1.4224)
			(stroke
				(width 0.1524)
				(type default)
			)
			(layer "F.SilkS")
		)
		(fp_poly
			(pts
				(xy -2.2098 -1.4224) (xy -2.2098 1.4224) (xy 2.2098 1.4224) (xy 2.2098 -1.4224)
			)
			(stroke
				(width 0)
				(type default)
			)
			(fill yes)
			(layer "F.SilkS")
		)
		(fp_rect
			(start -2.450084 2.999994)
			(end 2.450084 -2.999994)
			(stroke
				(width 0)
				(type default)
			)
			(fill no)
			(layer "F.CrtYd")
		)
		(fp_poly
			(pts
				(xy -2.8194 3.6322) (xy -2.8194 -3.6322) (xy 2.8194 -3.6322) (xy 2.8194 1.18364) (xy 2.450084 1.18364)
				(xy 2.450084 -2.999994) (xy -2.450084 -2.999994) (xy -2.450084 2.999994) (xy 2.450084 2.999994)
				(xy 2.450084 1.18618) (xy 2.8194 1.18618) (xy 2.8194 3.6322)
			)
			(stroke
				(width 0)
				(type default)
			)
			(fill no)
			(layer "F.CrtYd")
		)
		(fp_rect
			(start -2.8194 3.6322)
			(end 2.8194 -3.6322)
			(stroke
				(width 0)
				(type default)
			)
			(fill no)
			(layer "F.Fab")
		)
		(pad "1" smd rect
			(at -1.905 2.54 180)
			(size 0.635 1.651)
			(layers "F.Cu" "F.Mask" "F.Paste")
			(net "P5V_HDD24")
		)
		(pad "2" smd rect
			(at -0.635 2.54 180)
			(size 0.635 1.651)
			(layers "F.Cu" "F.Mask" "F.Paste")
			(net "P5V_HDD24")
		)
		(pad "3" smd rect
			(at 0.635 2.54 180)
			(size 0.635 1.651)
			(layers "F.Cu" "F.Mask" "F.Paste")
			(net "P5V_HDD24")
		)
		(pad "4" smd rect
			(at 1.905 2.54 180)
			(size 0.635 1.651)
			(layers "F.Cu" "F.Mask" "F.Paste")
			(net "SW_HDD_P24")
		)
		(pad "5" smd rect
			(at 1.905 -2.54 180)
			(size 0.635 1.651)
			(layers "F.Cu" "F.Mask" "F.Paste")
			(net "P5V_B_2")
		)
		(pad "6" smd rect
			(at 0.635 -2.54 180)
			(size 0.635 1.651)
			(layers "F.Cu" "F.Mask" "F.Paste")
			(net "P5V_B_2")
		)
		(pad "7" smd rect
			(at -0.635 -2.54 180)
			(size 0.635 1.651)
			(layers "F.Cu" "F.Mask" "F.Paste")
			(net "P5V_B_2")
		)
		(pad "8" smd rect
			(at -1.905 -2.54 180)
			(size 0.635 1.651)
			(layers "F.Cu" "F.Mask" "F.Paste")
			(net "P5V_B_2")
		)
	)
	(footprint ""
		(layer "F.Cu")
		(at 381.1778 -261.3152)
		(property "Reference" "R289"
			(at 0 0 0)
			(layer "F.SilkS")
			(hide yes)
			(effects
				(font
					(size 1.27 1.27)
				)
			)
		)
		(property "Value" "220R3F-1-GP"
			(at -0.0254 -2.5146 0)
			(unlocked yes)
			(layer "F.Fab")
			(hide yes)
			(effects
				(font
					(size 1.016 1.016)
					(thickness 0.1524)
				)
			)
		)
		(property "Device Type" "R603H22"
			(at -0.0254 -4.0386 0)
			(unlocked yes)
			(layer "F.Fab")
			(hide yes)
			(effects
				(font
					(size 1.016 1.016)
					(thickness 0.1524)
				)
			)
		)
		(duplicate_pad_numbers_are_jumpers no)
		(fp_line
			(start -0.4826 0)
			(end -0.2032 0)
			(stroke
				(width 0.2032)
				(type default)
			)
			(layer "F.SilkS")
		)
		(fp_line
			(start 0.2032 0)
			(end 0.4826 0)
			(stroke
				(width 0.2032)
				(type default)
			)
			(layer "F.SilkS")
		)
		(fp_rect
			(start -0.5842 1.3335)
			(end 0.5842 -1.3335)
			(stroke
				(width 0)
				(type default)
			)
			(fill no)
			(layer "F.CrtYd")
		)
		(fp_rect
			(start -0.5842 1.3335)
			(end 0.5842 -1.3335)
			(stroke
				(width 0)
				(type default)
			)
			(fill no)
			(layer "F.Fab")
		)
		(pad "1" smd custom
			(at 0 -0.762)
			(size 0.2159 0.2159)
			(layers "F.Cu" "F.Mask" "F.Paste")
			(net "HDD_PRSNT_8")
			(options
				(clearance outline)
				(anchor circle)
			)
			(primitives
				(gr_poly
					(pts
						(arc
							(start -0.3302 -0.4318)
							(mid -0.402042 -0.402042)
							(end -0.4318 -0.3302)
						)
						(arc
							(start -0.4318 0.3302)
							(mid -0.402042 0.402042)
							(end -0.3302 0.4318)
						)
						(arc
							(start 0.3302 0.4318)
							(mid 0.402042 0.402042)
							(end 0.4318 0.3302)
						)
						(arc
							(start 0.4318 -0.3302)
							(mid 0.402042 -0.402042)
							(end 0.3302 -0.4318)
						)
					)
					(width 0)
					(fill yes)
				)
			)
		)
		(pad "2" smd custom
			(at 0 0.762)
			(size 0.2159 0.2159)
			(layers "F.Cu" "F.Mask" "F.Paste")
			(net "DRIVE_B_8_INS")
			(options
				(clearance outline)
				(anchor circle)
			)
			(primitives
				(gr_poly
					(pts
						(arc
							(start -0.3302 -0.4318)
							(mid -0.402042 -0.402042)
							(end -0.4318 -0.3302)
						)
						(arc
							(start -0.4318 0.3302)
							(mid -0.402042 0.402042)
							(end -0.3302 0.4318)
						)
						(arc
							(start 0.3302 0.4318)
							(mid 0.402042 0.402042)
							(end 0.4318 0.3302)
						)
						(arc
							(start 0.4318 -0.3302)
							(mid 0.402042 -0.402042)
							(end 0.3302 -0.4318)
						)
					)
					(width 0)
					(fill yes)
				)
			)
		)
	)
	(footprint ""
		(layer "F.Cu")
		(at 364.744 -243.586 180)
		(property "Reference" "R276"
			(at 0 0 180)
			(layer "F.SilkS")
			(hide yes)
			(effects
				(font
					(size 1.27 1.27)
				)
			)
		)
		(property "Value" "1KR2F-3-GP"
			(at 0.064008 -3.993896 180)
			(unlocked yes)
			(layer "F.Fab")
			(hide yes)
			(effects
				(font
					(size 1.016 1.016)
					(thickness 0.1524)
				)
			)
		)
		(property "Device Type" "R402H16"
			(at 0.064008 -5.517896 180)
			(unlocked yes)
			(layer "F.Fab")
			(hide yes)
			(effects
				(font
					(size 1.016 1.016)
					(thickness 0.1524)
				)
			)
		)
		(duplicate_pad_numbers_are_jumpers no)
		(fp_line
			(start 0.508 -0.9398)
			(end -0.508 -0.9398)
			(stroke
				(width 0.1524)
				(type default)
			)
			(layer "F.SilkS")
		)
		(fp_line
			(start -0.508 -0.9398)
			(end -0.508 0.9398)
			(stroke
				(width 0.1524)
				(type default)
			)
			(layer "F.SilkS")
		)
		(fp_rect
			(start -0.508 0.9398)
			(end 0.508 -0.9398)
			(stroke
				(width 0)
				(type default)
			)
			(fill no)
			(layer "F.CrtYd")
		)
		(fp_rect
			(start -0.508 0.9398)
			(end 0.508 -0.9398)
			(stroke
				(width 0)
				(type default)
			)
			(fill no)
			(layer "F.Fab")
		)
		(pad "1" smd custom
			(at 0 -0.4445 180)
			(size 0.1397 0.1397)
			(layers "F.Cu" "F.Mask" "F.Paste")
			(net "P3V3_STBY_B")
			(options
				(clearance outline)
				(anchor circle)
			)
			(primitives
				(gr_poly
					(pts
						(arc
							(start -0.1778 -0.2794)
							(mid -0.249642 -0.249642)
							(end -0.2794 -0.1778)
						)
						(arc
							(start -0.2794 0.1778)
							(mid -0.249642 0.249642)
							(end -0.1778 0.2794)
						)
						(arc
							(start 0.1778 0.2794)
							(mid 0.249642 0.249642)
							(end 0.2794 0.1778)
						)
						(arc
							(start 0.2794 -0.1778)
							(mid 0.249642 -0.249642)
							(end 0.1778 -0.2794)
						)
					)
					(width 0)
					(fill yes)
				)
			)
		)
		(pad "2" smd custom
			(at 0 0.4445 180)
			(size 0.1397 0.1397)
			(layers "F.Cu" "F.Mask" "F.Paste")
			(net "SW_PWR_R_HDD7")
			(options
				(clearance outline)
				(anchor circle)
			)
			(primitives
				(gr_poly
					(pts
						(arc
							(start -0.1778 -0.2794)
							(mid -0.249642 -0.249642)
							(end -0.2794 -0.1778)
						)
						(arc
							(start -0.2794 0.1778)
							(mid -0.249642 0.249642)
							(end -0.1778 0.2794)
						)
						(arc
							(start 0.1778 0.2794)
							(mid 0.249642 0.249642)
							(end 0.2794 0.1778)
						)
						(arc
							(start 0.2794 -0.1778)
							(mid 0.249642 -0.249642)
							(end 0.1778 -0.2794)
						)
					)
					(width 0)
					(fill yes)
				)
			)
		)
	)
	(footprint ""
		(layer "F.Cu")
		(at 378.249942 -180.399944)
		(property "Reference" "LED9"
			(at 0 0 0)
			(layer "F.SilkS")
			(hide yes)
			(effects
				(font
					(size 1.27 1.27)
				)
			)
		)
		(property "Value" "LED-BY-19-GP"
			(at -2.132076 1.414018 0)
			(unlocked yes)
			(layer "F.Fab")
			(hide yes)
			(effects
				(font
					(size 1.016 1.016)
					(thickness 0.1524)
				)
			)
		)
		(property "Device Type" "LED-1615-4PH26"
			(at -2.132076 -0.109982 0)
			(unlocked yes)
			(layer "F.Fab")
			(hide yes)
			(effects
				(font
					(size 1.016 1.016)
					(thickness 0.1524)
				)
			)
		)
		(duplicate_pad_numbers_are_jumpers no)
		(fp_line
			(start -1.2954 0.254)
			(end -1.2954 1.6002)
			(stroke
				(width 0.508)
				(type default)
			)
			(layer "F.SilkS")
		)
		(fp_line
			(start -1.2954 1.6002)
			(end 1.2954 1.6002)
			(stroke
				(width 0.508)
				(type default)
			)
			(layer "F.SilkS")
		)
		(fp_line
			(start -1.1176 -1.4224)
			(end 1.1176 -1.4224)
			(stroke
				(width 0.1524)
				(type default)
			)
			(layer "F.SilkS")
		)
		(fp_line
			(start -1.1176 1.4224)
			(end -1.1176 -1.4224)
			(stroke
				(width 0.1524)
				(type default)
			)
			(layer "F.SilkS")
		)
		(fp_line
			(start 1.1176 -1.4224)
			(end 1.1176 1.4224)
			(stroke
				(width 0.1524)
				(type default)
			)
			(layer "F.SilkS")
		)
		(fp_line
			(start 1.1176 1.4224)
			(end -1.1176 1.4224)
			(stroke
				(width 0.1524)
				(type default)
			)
			(layer "F.SilkS")
		)
		(fp_line
			(start 1.2954 1.6002)
			(end 1.2954 0.254)
			(stroke
				(width 0.508)
				(type default)
			)
			(layer "F.SilkS")
		)
		(fp_rect
			(start -0.7493 0.8001)
			(end 0.7493 -0.8001)
			(stroke
				(width 0)
				(type default)
			)
			(fill no)
			(layer "F.CrtYd")
		)
		(fp_poly
			(pts
				(xy -1.3716 1.6764) (xy -1.3716 -1.6764) (xy 1.3716 -1.6764) (xy 1.3716 0.0635) (xy 0.7493 0.0635)
				(xy 0.7493 -0.8001) (xy -0.7493 -0.8001) (xy -0.7493 0.8001) (xy 0.7493 0.8001) (xy 0.7493 0.0762)
				(xy 1.3716 0.0762) (xy 1.3716 1.6764)
			)
			(stroke
				(width 0)
				(type default)
			)
			(fill no)
			(layer "F.CrtYd")
		)
		(fp_rect
			(start -1.3716 1.6764)
			(end 1.3716 -1.6764)
			(stroke
				(width 0)
				(type default)
			)
			(fill no)
			(layer "F.Fab")
		)
		(pad "1" smd rect
			(at 0.50038 -0.73025)
			(size 0.7112 0.8636)
			(layers "F.Cu" "F.Mask" "F.Paste")
			(net "DRV_ACT_8")
		)
		(pad "2" smd rect
			(at -0.50038 -0.73025)
			(size 0.7112 0.8636)
			(layers "F.Cu" "F.Mask" "F.Paste")
			(net "FLT_HDD8")
		)
		(pad "3" smd rect
			(at 0.50038 0.73025)
			(size 0.7112 0.8636)
			(layers "F.Cu" "F.Mask" "F.Paste")
			(net "DRV_ACT_8_N")
		)
		(pad "4" smd rect
			(at -0.50038 0.73025)
			(size 0.7112 0.8636)
			(layers "F.Cu" "F.Mask" "F.Paste")
			(net "FLT_HDD8_N")
		)
	)
	(footprint ""
		(layer "F.Cu")
		(at 32.463486 -15.219426 90)
		(property "Reference" "C340"
			(at 0 0 90)
			(layer "F.SilkS")
			(hide yes)
			(effects
				(font
					(size 1.27 1.27)
				)
			)
		)
		(property "Value" "SCD01U16V1KX-GP"
			(at -2.8321 -1.7399 90)
			(unlocked yes)
			(layer "F.Fab")
			(hide yes)
			(effects
				(font
					(size 1.016 1.016)
					(thickness 0.1524)
				)
			)
		)
		(property "Device Type" "C0201H13"
			(at -2.8321 -3.2639 90)
			(unlocked yes)
			(layer "F.Fab")
			(hide yes)
			(effects
				(font
					(size 1.016 1.016)
					(thickness 0.1524)
				)
			)
		)
		(duplicate_pad_numbers_are_jumpers no)
		(fp_rect
			(start -0.2794 0.6477)
			(end 0.2794 -0.6477)
			(stroke
				(width 0)
				(type default)
			)
			(fill no)
			(layer "F.CrtYd")
		)
		(fp_rect
			(start -0.2794 0.6477)
			(end 0.2794 -0.6477)
			(stroke
				(width 0)
				(type default)
			)
			(fill no)
			(layer "F.Fab")
		)
		(pad "1" smd custom
			(at 0 -0.2794 90)
			(size 0.0762 0.0762)
			(layers "F.Cu" "F.Mask" "F.Paste")
			(net "SAS_HDD_RX_N24")
			(options
				(clearance outline)
				(anchor circle)
			)
			(primitives
				(gr_poly
					(pts
						(arc
							(start 0.1524 -0.127)
							(mid 0.137521 -0.162921)
							(end 0.1016 -0.1778)
						)
						(arc
							(start -0.1016 -0.1778)
							(mid -0.137521 -0.162921)
							(end -0.1524 -0.127)
						)
						(arc
							(start -0.1524 0.127)
							(mid -0.137521 0.162921)
							(end -0.1016 0.1778)
						)
						(arc
							(start 0.1016 0.1778)
							(mid 0.137521 0.162921)
							(end 0.1524 0.127)
						)
					)
					(width 0)
					(fill yes)
				)
			)
		)
		(pad "2" smd custom
			(at 0 0.2794 90)
			(size 0.0762 0.0762)
			(layers "F.Cu" "F.Mask" "F.Paste")
			(net "PHY_SCC_B_TO_DRV_B_24_DN")
			(options
				(clearance outline)
				(anchor circle)
			)
			(primitives
				(gr_poly
					(pts
						(arc
							(start 0.1524 -0.127)
							(mid 0.137521 -0.162921)
							(end 0.1016 -0.1778)
						)
						(arc
							(start -0.1016 -0.1778)
							(mid -0.137521 -0.162921)
							(end -0.1524 -0.127)
						)
						(arc
							(start -0.1524 0.127)
							(mid -0.137521 0.162921)
							(end -0.1016 0.1778)
						)
						(arc
							(start 0.1016 0.1778)
							(mid 0.137521 0.162921)
							(end 0.1524 0.127)
						)
					)
					(width 0)
					(fill yes)
				)
			)
		)
	)
	(footprint ""
		(layer "F.Cu")
		(at 479.384614 -15.219426 -90)
		(property "Reference" "C483"
			(at 0 0 270)
			(layer "F.SilkS")
			(hide yes)
			(effects
				(font
					(size 1.27 1.27)
				)
			)
		)
		(property "Value" "SCD01U16V1KX-GP"
			(at -2.8321 -1.7399 270)
			(unlocked yes)
			(layer "F.Fab")
			(hide yes)
			(effects
				(font
					(size 1.016 1.016)
					(thickness 0.1524)
				)
			)
		)
		(property "Device Type" "C0201H13"
			(at -2.8321 -3.2639 270)
			(unlocked yes)
			(layer "F.Fab")
			(hide yes)
			(effects
				(font
					(size 1.016 1.016)
					(thickness 0.1524)
				)
			)
		)
		(duplicate_pad_numbers_are_jumpers no)
		(fp_rect
			(start -0.2794 0.6477)
			(end 0.2794 -0.6477)
			(stroke
				(width 0)
				(type default)
			)
			(fill no)
			(layer "F.CrtYd")
		)
		(fp_rect
			(start -0.2794 0.6477)
			(end 0.2794 -0.6477)
			(stroke
				(width 0)
				(type default)
			)
			(fill no)
			(layer "F.Fab")
		)
		(pad "1" smd custom
			(at 0 -0.2794 270)
			(size 0.0762 0.0762)
			(layers "F.Cu" "F.Mask" "F.Paste")
			(net "SAS_HDD_RX_N35")
			(options
				(clearance outline)
				(anchor circle)
			)
			(primitives
				(gr_poly
					(pts
						(arc
							(start 0.1524 -0.127)
							(mid 0.137521 -0.162921)
							(end 0.1016 -0.1778)
						)
						(arc
							(start -0.1016 -0.1778)
							(mid -0.137521 -0.162921)
							(end -0.1524 -0.127)
						)
						(arc
							(start -0.1524 0.127)
							(mid -0.137521 0.162921)
							(end -0.1016 0.1778)
						)
						(arc
							(start 0.1016 0.1778)
							(mid 0.137521 0.162921)
							(end 0.1524 0.127)
						)
					)
					(width 0)
					(fill yes)
				)
			)
		)
		(pad "2" smd custom
			(at 0 0.2794 270)
			(size 0.0762 0.0762)
			(layers "F.Cu" "F.Mask" "F.Paste")
			(net "PHY_SCC_B_TO_DRV_B_35_DN")
			(options
				(clearance outline)
				(anchor circle)
			)
			(primitives
				(gr_poly
					(pts
						(arc
							(start 0.1524 -0.127)
							(mid 0.137521 -0.162921)
							(end 0.1016 -0.1778)
						)
						(arc
							(start -0.1016 -0.1778)
							(mid -0.137521 -0.162921)
							(end -0.1524 -0.127)
						)
						(arc
							(start -0.1524 0.127)
							(mid -0.137521 0.162921)
							(end -0.1016 0.1778)
						)
						(arc
							(start 0.1016 0.1778)
							(mid 0.137521 0.162921)
							(end 0.1524 0.127)
						)
					)
					(width 0)
					(fill yes)
				)
			)
		)
	)
	(footprint ""
		(layer "F.Cu")
		(at 18.209768 -102.43947 -90)
		(property "Reference" "R338"
			(at 0 0 270)
			(layer "F.SilkS")
			(hide yes)
			(effects
				(font
					(size 1.27 1.27)
				)
			)
		)
		(property "Value" "4K7R2F-GP"
			(at 0.064008 -3.993896 270)
			(unlocked yes)
			(layer "F.Fab")
			(hide yes)
			(effects
				(font
					(size 1.016 1.016)
					(thickness 0.1524)
				)
			)
		)
		(property "Device Type" "R402H16"
			(at 0.064008 -5.517896 270)
			(unlocked yes)
			(layer "F.Fab")
			(hide yes)
			(effects
				(font
					(size 1.016 1.016)
					(thickness 0.1524)
				)
			)
		)
		(duplicate_pad_numbers_are_jumpers no)
		(fp_line
			(start -0.508 -0.9398)
			(end -0.508 0.9398)
			(stroke
				(width 0.1524)
				(type default)
			)
			(layer "F.SilkS")
		)
		(fp_line
			(start 0.508 -0.9398)
			(end -0.508 -0.9398)
			(stroke
				(width 0.1524)
				(type default)
			)
			(layer "F.SilkS")
		)
		(fp_rect
			(start -0.508 0.9398)
			(end 0.508 -0.9398)
			(stroke
				(width 0)
				(type default)
			)
			(fill no)
			(layer "F.CrtYd")
		)
		(fp_rect
			(start -0.508 0.9398)
			(end 0.508 -0.9398)
			(stroke
				(width 0)
				(type default)
			)
			(fill no)
			(layer "F.Fab")
		)
		(pad "1" smd custom
			(at 0 -0.4445 270)
			(size 0.1397 0.1397)
			(layers "F.Cu" "F.Mask" "F.Paste")
			(net "DRIVE_B_12_FLT_LED")
			(options
				(clearance outline)
				(anchor circle)
			)
			(primitives
				(gr_poly
					(pts
						(arc
							(start -0.1778 -0.2794)
							(mid -0.249642 -0.249642)
							(end -0.2794 -0.1778)
						)
						(arc
							(start -0.2794 0.1778)
							(mid -0.249642 0.249642)
							(end -0.1778 0.2794)
						)
						(arc
							(start 0.1778 0.2794)
							(mid 0.249642 0.249642)
							(end 0.2794 0.1778)
						)
						(arc
							(start 0.2794 -0.1778)
							(mid 0.249642 -0.249642)
							(end 0.1778 -0.2794)
						)
					)
					(width 0)
					(fill yes)
				)
			)
		)
		(pad "2" smd custom
			(at 0 0.4445 270)
			(size 0.1397 0.1397)
			(layers "F.Cu" "F.Mask" "F.Paste")
			(net "GND")
			(options
				(clearance outline)
				(anchor circle)
			)
			(primitives
				(gr_poly
					(pts
						(arc
							(start -0.1778 -0.2794)
							(mid -0.249642 -0.249642)
							(end -0.2794 -0.1778)
						)
						(arc
							(start -0.2794 0.1778)
							(mid -0.249642 0.249642)
							(end -0.1778 0.2794)
						)
						(arc
							(start 0.1778 0.2794)
							(mid 0.249642 0.249642)
							(end 0.2794 0.1778)
						)
						(arc
							(start 0.2794 -0.1778)
							(mid 0.249642 -0.249642)
							(end 0.1778 -0.2794)
						)
					)
					(width 0)
					(fill yes)
				)
			)
		)
	)
	(footprint ""
		(layer "F.Cu")
		(at 329.819 -267.843 180)
		(property "Reference" "C108"
			(at 0 0 180)
			(layer "F.SilkS")
			(hide yes)
			(effects
				(font
					(size 1.27 1.27)
				)
			)
		)
		(property "Value" "SC1U16V3KX-5GP"
			(at 0 -2.8194 180)
			(unlocked yes)
			(layer "F.Fab")
			(hide yes)
			(effects
				(font
					(size 1.016 1.016)
					(thickness 0.1524)
				)
			)
		)
		(property "Device Type" "C603H36"
			(at 0 -4.3434 180)
			(unlocked yes)
			(layer "F.Fab")
			(hide yes)
			(effects
				(font
					(size 1.016 1.016)
					(thickness 0.1524)
				)
			)
		)
		(duplicate_pad_numbers_are_jumpers no)
		(fp_line
			(start 0.508 0)
			(end -0.508 0)
			(stroke
				(width 0.2032)
				(type default)
			)
			(layer "F.SilkS")
		)
		(fp_rect
			(start -0.5842 1.3335)
			(end 0.5842 -1.3335)
			(stroke
				(width 0)
				(type default)
			)
			(fill no)
			(layer "F.CrtYd")
		)
		(fp_rect
			(start -0.5842 1.3335)
			(end 0.5842 -1.3335)
			(stroke
				(width 0)
				(type default)
			)
			(fill no)
			(layer "F.Fab")
		)
		(pad "1" smd custom
			(at 0 -0.762 180)
			(size 0.2159 0.2159)
			(layers "F.Cu" "F.Mask" "F.Paste")
			(net "P5V_HDD6")
			(options
				(clearance outline)
				(anchor circle)
			)
			(primitives
				(gr_poly
					(pts
						(arc
							(start -0.3302 -0.4318)
							(mid -0.402042 -0.402042)
							(end -0.4318 -0.3302)
						)
						(arc
							(start -0.4318 0.3302)
							(mid -0.402042 0.402042)
							(end -0.3302 0.4318)
						)
						(arc
							(start 0.3302 0.4318)
							(mid 0.402042 0.402042)
							(end 0.4318 0.3302)
						)
						(arc
							(start 0.4318 -0.3302)
							(mid 0.402042 -0.402042)
							(end 0.3302 -0.4318)
						)
					)
					(width 0)
					(fill yes)
				)
			)
		)
		(pad "2" smd custom
			(at 0 0.762 180)
			(size 0.2159 0.2159)
			(layers "F.Cu" "F.Mask" "F.Paste")
			(net "GND")
			(options
				(clearance outline)
				(anchor circle)
			)
			(primitives
				(gr_poly
					(pts
						(arc
							(start -0.3302 -0.4318)
							(mid -0.402042 -0.402042)
							(end -0.4318 -0.3302)
						)
						(arc
							(start -0.4318 0.3302)
							(mid -0.402042 0.402042)
							(end -0.3302 0.4318)
						)
						(arc
							(start 0.3302 0.4318)
							(mid 0.402042 0.402042)
							(end 0.4318 0.3302)
						)
						(arc
							(start 0.4318 -0.3302)
							(mid 0.402042 -0.402042)
							(end 0.3302 -0.4318)
						)
					)
					(width 0)
					(fill yes)
				)
			)
		)
	)
	(footprint ""
		(layer "F.Cu")
		(at 395.224 -131.318 -90)
		(property "Reference" "Q95"
			(at 0 0 270)
			(layer "F.SilkS")
			(hide yes)
			(effects
				(font
					(size 1.27 1.27)
				)
			)
		)
		(property "Value" "2N7002KDW-GP"
			(at -2.3622 -8.2042 270)
			(unlocked yes)
			(layer "F.Fab")
			(hide yes)
			(effects
				(font
					(size 1.016 1.016)
					(thickness 0.1524)
				)
			)
		)
		(property "Device Type" "SOT-363H44"
			(at -2.3622 -10.1092 270)
			(unlocked yes)
			(layer "F.Fab")
			(hide yes)
			(effects
				(font
					(size 1.016 1.016)
					(thickness 0.1524)
				)
			)
		)
		(duplicate_pad_numbers_are_jumpers no)
		(fp_line
			(start -1.4478 1.7018)
			(end 1.4478 1.7018)
			(stroke
				(width 0.1524)
				(type default)
			)
			(layer "F.SilkS")
		)
		(fp_line
			(start 1.4478 1.7018)
			(end 1.4478 -1.7018)
			(stroke
				(width 0.1524)
				(type default)
			)
			(layer "F.SilkS")
		)
		(fp_line
			(start -1.27 1.524)
			(end -1.27 0.6604)
			(stroke
				(width 0.4826)
				(type default)
			)
			(layer "F.SilkS")
		)
		(fp_line
			(start -1.4478 -1.7018)
			(end -1.4478 1.7018)
			(stroke
				(width 0.1524)
				(type default)
			)
			(layer "F.SilkS")
		)
		(fp_line
			(start 1.4478 -1.7018)
			(end -1.4478 -1.7018)
			(stroke
				(width 0.1524)
				(type default)
			)
			(layer "F.SilkS")
		)
		(fp_poly
			(pts
				(xy -1.524 -1.778) (xy 1.524 -1.778) (xy 1.524 1.778) (xy -1.524 1.778)
			)
			(stroke
				(width 0)
				(type default)
			)
			(fill no)
			(layer "F.CrtYd")
		)
		(fp_poly
			(pts
				(xy -1.524 -1.778) (xy 1.524 -1.778) (xy 1.524 1.778) (xy -1.524 1.778)
			)
			(stroke
				(width 0)
				(type default)
			)
			(fill no)
			(layer "F.Fab")
		)
		(pad "1" smd rect
			(at -0.65024 0.9398 270)
			(size 0.4064 1.016)
			(layers "F.Cu" "F.Mask" "F.Paste")
			(net "GND")
		)
		(pad "2" smd rect
			(at 0 0.9398 270)
			(size 0.4064 1.016)
			(layers "F.Cu" "F.Mask" "F.Paste")
			(net "SW_PWR_R_HDD20")
		)
		(pad "3" smd rect
			(at 0.65024 0.9398 270)
			(size 0.4064 1.016)
			(layers "F.Cu" "F.Mask" "F.Paste")
			(net "SW_HDD_P20")
		)
		(pad "4" smd rect
			(at 0.65024 -0.9398 270)
			(size 0.4064 1.016)
			(layers "F.Cu" "F.Mask" "F.Paste")
			(net "GND")
		)
		(pad "5" smd rect
			(at 0 -0.9398 270)
			(size 0.4064 1.016)
			(layers "F.Cu" "F.Mask" "F.Paste")
			(net "SW_HDD_G20")
		)
		(pad "6" smd rect
			(at -0.65024 -0.9398 270)
			(size 0.4064 1.016)
			(layers "F.Cu" "F.Mask" "F.Paste")
			(net "SW_HDD_R20")
		)
	)
	(footprint ""
		(layer "F.Cu")
		(at 264.192258 -363.093)
		(property "Reference" "C79"
			(at 0 0 0)
			(layer "F.SilkS")
			(hide yes)
			(effects
				(font
					(size 1.27 1.27)
				)
			)
		)
		(property "Value" "SC1U16V3KX-5GP"
			(at 0 -2.8194 0)
			(unlocked yes)
			(layer "F.Fab")
			(hide yes)
			(effects
				(font
					(size 1.016 1.016)
					(thickness 0.1524)
				)
			)
		)
		(property "Device Type" "C603H36"
			(at 0 -4.3434 0)
			(unlocked yes)
			(layer "F.Fab")
			(hide yes)
			(effects
				(font
					(size 1.016 1.016)
					(thickness 0.1524)
				)
			)
		)
		(duplicate_pad_numbers_are_jumpers no)
		(fp_line
			(start 0.508 0)
			(end -0.508 0)
			(stroke
				(width 0.2032)
				(type default)
			)
			(layer "F.SilkS")
		)
		(fp_rect
			(start -0.5842 1.3335)
			(end 0.5842 -1.3335)
			(stroke
				(width 0)
				(type default)
			)
			(fill no)
			(layer "F.CrtYd")
		)
		(fp_rect
			(start -0.5842 1.3335)
			(end 0.5842 -1.3335)
			(stroke
				(width 0)
				(type default)
			)
			(fill no)
			(layer "F.Fab")
		)
		(pad "1" smd custom
			(at 0 -0.762)
			(size 0.2159 0.2159)
			(layers "F.Cu" "F.Mask" "F.Paste")
			(net "P3V3_IN_BIAS")
			(options
				(clearance outline)
				(anchor circle)
			)
			(primitives
				(gr_poly
					(pts
						(arc
							(start -0.3302 -0.4318)
							(mid -0.402042 -0.402042)
							(end -0.4318 -0.3302)
						)
						(arc
							(start -0.4318 0.3302)
							(mid -0.402042 0.402042)
							(end -0.3302 0.4318)
						)
						(arc
							(start 0.3302 0.4318)
							(mid 0.402042 0.402042)
							(end 0.4318 0.3302)
						)
						(arc
							(start 0.4318 -0.3302)
							(mid 0.402042 -0.402042)
							(end 0.3302 -0.4318)
						)
					)
					(width 0)
					(fill yes)
				)
			)
		)
		(pad "2" smd custom
			(at 0 0.762)
			(size 0.2159 0.2159)
			(layers "F.Cu" "F.Mask" "F.Paste")
			(net "GND")
			(options
				(clearance outline)
				(anchor circle)
			)
			(primitives
				(gr_poly
					(pts
						(arc
							(start -0.3302 -0.4318)
							(mid -0.402042 -0.402042)
							(end -0.4318 -0.3302)
						)
						(arc
							(start -0.4318 0.3302)
							(mid -0.402042 0.402042)
							(end -0.3302 0.4318)
						)
						(arc
							(start 0.3302 0.4318)
							(mid 0.402042 0.402042)
							(end 0.4318 0.3302)
						)
						(arc
							(start 0.4318 -0.3302)
							(mid 0.402042 -0.402042)
							(end 0.3302 -0.4318)
						)
					)
					(width 0)
					(fill yes)
				)
			)
		)
	)
	(footprint ""
		(layer "F.Cu")
		(at 38.956996 -369.697)
		(property "Reference" "C519"
			(at 0 0 0)
			(layer "F.SilkS")
			(hide yes)
			(effects
				(font
					(size 1.27 1.27)
				)
			)
		)
		(property "Value" "SCD1U25V2KX-2-GP"
			(at 1.1811 -2.7051 0)
			(unlocked yes)
			(layer "F.Fab")
			(hide yes)
			(effects
				(font
					(size 1.016 1.016)
					(thickness 0.1524)
				)
			)
		)
		(property "Device Type" "C402H22"
			(at 1.1811 -4.2291 0)
			(unlocked yes)
			(layer "F.Fab")
			(hide yes)
			(effects
				(font
					(size 1.016 1.016)
					(thickness 0.1524)
				)
			)
		)
		(duplicate_pad_numbers_are_jumpers no)
		(fp_rect
			(start -0.4318 0.9525)
			(end 0.4318 -0.9525)
			(stroke
				(width 0)
				(type default)
			)
			(fill no)
			(layer "F.CrtYd")
		)
		(fp_rect
			(start -0.4318 0.9525)
			(end 0.4318 -0.9525)
			(stroke
				(width 0)
				(type default)
			)
			(fill no)
			(layer "F.Fab")
		)
		(pad "1" smd custom
			(at 0 -0.4445)
			(size 0.1524 0.1524)
			(layers "F.Cu" "F.Mask" "F.Paste")
			(net "FAN_0_TACH0")
			(options
				(clearance outline)
				(anchor circle)
			)
			(primitives
				(gr_poly
					(pts
						(arc
							(start 0.3048 -0.2032)
							(mid 0.275042 -0.275042)
							(end 0.2032 -0.3048)
						)
						(arc
							(start -0.2032 -0.3048)
							(mid -0.275042 -0.275042)
							(end -0.3048 -0.2032)
						)
						(arc
							(start -0.3048 0.2032)
							(mid -0.275042 0.275042)
							(end -0.2032 0.3048)
						)
						(arc
							(start 0.2032 0.3048)
							(mid 0.275042 0.275042)
							(end 0.3048 0.2032)
						)
					)
					(width 0)
					(fill yes)
				)
			)
		)
		(pad "2" smd custom
			(at 0 0.4445)
			(size 0.1524 0.1524)
			(layers "F.Cu" "F.Mask" "F.Paste")
			(net "GND")
			(options
				(clearance outline)
				(anchor circle)
			)
			(primitives
				(gr_poly
					(pts
						(arc
							(start 0.3048 -0.2032)
							(mid 0.275042 -0.275042)
							(end 0.2032 -0.3048)
						)
						(arc
							(start -0.2032 -0.3048)
							(mid -0.275042 -0.275042)
							(end -0.3048 -0.2032)
						)
						(arc
							(start -0.3048 0.2032)
							(mid -0.275042 0.275042)
							(end -0.2032 0.3048)
						)
						(arc
							(start 0.2032 0.3048)
							(mid 0.275042 0.275042)
							(end 0.3048 0.2032)
						)
					)
					(width 0)
					(fill yes)
				)
			)
		)
	)
	(footprint ""
		(layer "F.Cu")
		(at 168.91 -367.919 -90)
		(property "Reference" "C541"
			(at 0 0 270)
			(layer "F.SilkS")
			(hide yes)
			(effects
				(font
					(size 1.27 1.27)
				)
			)
		)
		(property "Value" "SC1U25V3KX-GP"
			(at 0 -2.8194 270)
			(unlocked yes)
			(layer "F.Fab")
			(hide yes)
			(effects
				(font
					(size 1.016 1.016)
					(thickness 0.1524)
				)
			)
		)
		(property "Device Type" "C603H36"
			(at 0 -4.3434 270)
			(unlocked yes)
			(layer "F.Fab")
			(hide yes)
			(effects
				(font
					(size 1.016 1.016)
					(thickness 0.1524)
				)
			)
		)
		(duplicate_pad_numbers_are_jumpers no)
		(fp_line
			(start 0.508 0)
			(end -0.508 0)
			(stroke
				(width 0.2032)
				(type default)
			)
			(layer "F.SilkS")
		)
		(fp_rect
			(start -0.5842 1.3335)
			(end 0.5842 -1.3335)
			(stroke
				(width 0)
				(type default)
			)
			(fill no)
			(layer "F.CrtYd")
		)
		(fp_rect
			(start -0.5842 1.3335)
			(end 0.5842 -1.3335)
			(stroke
				(width 0)
				(type default)
			)
			(fill no)
			(layer "F.Fab")
		)
		(pad "1" smd custom
			(at 0 -0.762 270)
			(size 0.2159 0.2159)
			(layers "F.Cu" "F.Mask" "F.Paste")
			(net "MB0_P12V_HS")
			(options
				(clearance outline)
				(anchor circle)
			)
			(primitives
				(gr_poly
					(pts
						(arc
							(start -0.3302 -0.4318)
							(mid -0.402042 -0.402042)
							(end -0.4318 -0.3302)
						)
						(arc
							(start -0.4318 0.3302)
							(mid -0.402042 0.402042)
							(end -0.3302 0.4318)
						)
						(arc
							(start 0.3302 0.4318)
							(mid 0.402042 0.402042)
							(end 0.4318 0.3302)
						)
						(arc
							(start 0.4318 -0.3302)
							(mid 0.402042 -0.402042)
							(end 0.3302 -0.4318)
						)
					)
					(width 0)
					(fill yes)
				)
			)
		)
		(pad "2" smd custom
			(at 0 0.762 270)
			(size 0.2159 0.2159)
			(layers "F.Cu" "F.Mask" "F.Paste")
			(net "AGND_CURRENT_MON")
			(options
				(clearance outline)
				(anchor circle)
			)
			(primitives
				(gr_poly
					(pts
						(arc
							(start -0.3302 -0.4318)
							(mid -0.402042 -0.402042)
							(end -0.4318 -0.3302)
						)
						(arc
							(start -0.4318 0.3302)
							(mid -0.402042 0.402042)
							(end -0.3302 0.4318)
						)
						(arc
							(start 0.3302 0.4318)
							(mid 0.402042 0.402042)
							(end 0.4318 0.3302)
						)
						(arc
							(start 0.4318 -0.3302)
							(mid 0.402042 -0.402042)
							(end 0.3302 -0.4318)
						)
					)
					(width 0)
					(fill yes)
				)
			)
		)
	)
	(footprint ""
		(layer "F.Cu")
		(at 181.3306 -373.7864 -90)
		(property "Reference" "R997"
			(at 0 0 270)
			(layer "F.SilkS")
			(hide yes)
			(effects
				(font
					(size 1.27 1.27)
				)
			)
		)
		(property "Value" "10KR2F-2-GP"
			(at 0.064008 -3.993896 270)
			(unlocked yes)
			(layer "F.Fab")
			(hide yes)
			(effects
				(font
					(size 1.016 1.016)
					(thickness 0.1524)
				)
			)
		)
		(property "Device Type" "R402H16"
			(at 0.064008 -5.517896 270)
			(unlocked yes)
			(layer "F.Fab")
			(hide yes)
			(effects
				(font
					(size 1.016 1.016)
					(thickness 0.1524)
				)
			)
		)
		(duplicate_pad_numbers_are_jumpers no)
		(fp_line
			(start -0.508 -0.9398)
			(end -0.508 0.9398)
			(stroke
				(width 0.1524)
				(type default)
			)
			(layer "F.SilkS")
		)
		(fp_line
			(start 0.508 -0.9398)
			(end -0.508 -0.9398)
			(stroke
				(width 0.1524)
				(type default)
			)
			(layer "F.SilkS")
		)
		(fp_rect
			(start -0.508 0.9398)
			(end 0.508 -0.9398)
			(stroke
				(width 0)
				(type default)
			)
			(fill no)
			(layer "F.CrtYd")
		)
		(fp_rect
			(start -0.508 0.9398)
			(end 0.508 -0.9398)
			(stroke
				(width 0)
				(type default)
			)
			(fill no)
			(layer "F.Fab")
		)
		(pad "1" smd custom
			(at 0 -0.4445 270)
			(size 0.1397 0.1397)
			(layers "F.Cu" "F.Mask" "F.Paste")
			(net "P12V_IN")
			(options
				(clearance outline)
				(anchor circle)
			)
			(primitives
				(gr_poly
					(pts
						(arc
							(start -0.1778 -0.2794)
							(mid -0.249642 -0.249642)
							(end -0.2794 -0.1778)
						)
						(arc
							(start -0.2794 0.1778)
							(mid -0.249642 0.249642)
							(end -0.1778 0.2794)
						)
						(arc
							(start 0.1778 0.2794)
							(mid 0.249642 0.249642)
							(end 0.2794 0.1778)
						)
						(arc
							(start 0.2794 -0.1778)
							(mid 0.249642 -0.249642)
							(end 0.1778 -0.2794)
						)
					)
					(width 0)
					(fill yes)
				)
			)
		)
		(pad "2" smd custom
			(at 0 0.4445 270)
			(size 0.1397 0.1397)
			(layers "F.Cu" "F.Mask" "F.Paste")
			(net "P12V_IN_PGOOD")
			(options
				(clearance outline)
				(anchor circle)
			)
			(primitives
				(gr_poly
					(pts
						(arc
							(start -0.1778 -0.2794)
							(mid -0.249642 -0.249642)
							(end -0.2794 -0.1778)
						)
						(arc
							(start -0.2794 0.1778)
							(mid -0.249642 0.249642)
							(end -0.1778 0.2794)
						)
						(arc
							(start 0.1778 0.2794)
							(mid 0.249642 0.249642)
							(end 0.2794 0.1778)
						)
						(arc
							(start 0.2794 -0.1778)
							(mid 0.249642 -0.249642)
							(end 0.1778 -0.2794)
						)
					)
					(width 0)
					(fill yes)
				)
			)
		)
	)
	(footprint ""
		(layer "F.Cu")
		(at 475.3356 -33.655 -90)
		(property "Reference" "C485"
			(at 0 0 270)
			(layer "F.SilkS")
			(hide yes)
			(effects
				(font
					(size 1.27 1.27)
				)
			)
		)
		(property "Value" "SC1U16V3KX-5GP"
			(at 0 -2.8194 270)
			(unlocked yes)
			(layer "F.Fab")
			(hide yes)
			(effects
				(font
					(size 1.016 1.016)
					(thickness 0.1524)
				)
			)
		)
		(property "Device Type" "C603H36"
			(at 0 -4.3434 270)
			(unlocked yes)
			(layer "F.Fab")
			(hide yes)
			(effects
				(font
					(size 1.016 1.016)
					(thickness 0.1524)
				)
			)
		)
		(duplicate_pad_numbers_are_jumpers no)
		(fp_line
			(start 0.508 0)
			(end -0.508 0)
			(stroke
				(width 0.2032)
				(type default)
			)
			(layer "F.SilkS")
		)
		(fp_rect
			(start -0.5842 1.3335)
			(end 0.5842 -1.3335)
			(stroke
				(width 0)
				(type default)
			)
			(fill no)
			(layer "F.CrtYd")
		)
		(fp_rect
			(start -0.5842 1.3335)
			(end 0.5842 -1.3335)
			(stroke
				(width 0)
				(type default)
			)
			(fill no)
			(layer "F.Fab")
		)
		(pad "1" smd custom
			(at 0 -0.762 270)
			(size 0.2159 0.2159)
			(layers "F.Cu" "F.Mask" "F.Paste")
			(net "P5V_HDD35")
			(options
				(clearance outline)
				(anchor circle)
			)
			(primitives
				(gr_poly
					(pts
						(arc
							(start -0.3302 -0.4318)
							(mid -0.402042 -0.402042)
							(end -0.4318 -0.3302)
						)
						(arc
							(start -0.4318 0.3302)
							(mid -0.402042 0.402042)
							(end -0.3302 0.4318)
						)
						(arc
							(start 0.3302 0.4318)
							(mid 0.402042 0.402042)
							(end 0.4318 0.3302)
						)
						(arc
							(start 0.4318 -0.3302)
							(mid 0.402042 -0.402042)
							(end 0.3302 -0.4318)
						)
					)
					(width 0)
					(fill yes)
				)
			)
		)
		(pad "2" smd custom
			(at 0 0.762 270)
			(size 0.2159 0.2159)
			(layers "F.Cu" "F.Mask" "F.Paste")
			(net "GND")
			(options
				(clearance outline)
				(anchor circle)
			)
			(primitives
				(gr_poly
					(pts
						(arc
							(start -0.3302 -0.4318)
							(mid -0.402042 -0.402042)
							(end -0.4318 -0.3302)
						)
						(arc
							(start -0.4318 0.3302)
							(mid -0.402042 0.402042)
							(end -0.3302 0.4318)
						)
						(arc
							(start 0.3302 0.4318)
							(mid 0.402042 0.402042)
							(end 0.4318 0.3302)
						)
						(arc
							(start 0.4318 -0.3302)
							(mid 0.402042 -0.402042)
							(end 0.3302 -0.4318)
						)
					)
					(width 0)
					(fill yes)
				)
			)
		)
	)
	(footprint ""
		(layer "F.Cu")
		(at 268.224 -212.8012 90)
		(property "Reference" "R11"
			(at 0 0 90)
			(layer "F.SilkS")
			(hide yes)
			(effects
				(font
					(size 1.27 1.27)
				)
			)
		)
		(property "Value" "1KR2J-1-GP"
			(at 0.064008 -3.993896 90)
			(unlocked yes)
			(layer "F.Fab")
			(hide yes)
			(effects
				(font
					(size 1.016 1.016)
					(thickness 0.1524)
				)
			)
		)
		(property "Device Type" "R402H16"
			(at 0.064008 -5.517896 90)
			(unlocked yes)
			(layer "F.Fab")
			(hide yes)
			(effects
				(font
					(size 1.016 1.016)
					(thickness 0.1524)
				)
			)
		)
		(duplicate_pad_numbers_are_jumpers no)
		(fp_line
			(start 0.508 -0.9398)
			(end -0.508 -0.9398)
			(stroke
				(width 0.1524)
				(type default)
			)
			(layer "F.SilkS")
		)
		(fp_line
			(start -0.508 -0.9398)
			(end -0.508 0.9398)
			(stroke
				(width 0.1524)
				(type default)
			)
			(layer "F.SilkS")
		)
		(fp_rect
			(start -0.508 0.9398)
			(end 0.508 -0.9398)
			(stroke
				(width 0)
				(type default)
			)
			(fill no)
			(layer "F.CrtYd")
		)
		(fp_rect
			(start -0.508 0.9398)
			(end 0.508 -0.9398)
			(stroke
				(width 0)
				(type default)
			)
			(fill no)
			(layer "F.Fab")
		)
		(pad "1" smd custom
			(at 0 -0.4445 90)
			(size 0.1397 0.1397)
			(layers "F.Cu" "F.Mask" "F.Paste")
			(net "P3V3_STBY_B")
			(options
				(clearance outline)
				(anchor circle)
			)
			(primitives
				(gr_poly
					(pts
						(arc
							(start -0.1778 -0.2794)
							(mid -0.249642 -0.249642)
							(end -0.2794 -0.1778)
						)
						(arc
							(start -0.2794 0.1778)
							(mid -0.249642 0.249642)
							(end -0.1778 0.2794)
						)
						(arc
							(start 0.1778 0.2794)
							(mid 0.249642 0.249642)
							(end 0.2794 0.1778)
						)
						(arc
							(start 0.2794 -0.1778)
							(mid 0.249642 -0.249642)
							(end 0.1778 -0.2794)
						)
					)
					(width 0)
					(fill yes)
				)
			)
		)
		(pad "2" smd custom
			(at 0 0.4445 90)
			(size 0.1397 0.1397)
			(layers "F.Cu" "F.Mask" "F.Paste")
			(net "I2C_DRIVE_B_INS_SDA")
			(options
				(clearance outline)
				(anchor circle)
			)
			(primitives
				(gr_poly
					(pts
						(arc
							(start -0.1778 -0.2794)
							(mid -0.249642 -0.249642)
							(end -0.2794 -0.1778)
						)
						(arc
							(start -0.2794 0.1778)
							(mid -0.249642 0.249642)
							(end -0.1778 0.2794)
						)
						(arc
							(start 0.1778 0.2794)
							(mid 0.249642 0.249642)
							(end 0.2794 0.1778)
						)
						(arc
							(start 0.2794 -0.1778)
							(mid 0.249642 -0.249642)
							(end 0.1778 -0.2794)
						)
					)
					(width 0)
					(fill yes)
				)
			)
		)
	)
	(footprint ""
		(layer "F.Cu")
		(at 368.808 -18.796 90)
		(property "Reference" "D31"
			(at 0 0 90)
			(layer "F.SilkS")
			(hide yes)
			(effects
				(font
					(size 1.27 1.27)
				)
			)
		)
		(property "Value" "RB551V30-GP"
			(at 0 -6.7818 90)
			(unlocked yes)
			(layer "F.Fab")
			(hide yes)
			(effects
				(font
					(size 1.016 1.016)
					(thickness 0.1524)
				)
			)
		)
		(property "Device Type" "SOD323AKH38"
			(at 0 -8.6868 90)
			(unlocked yes)
			(layer "F.Fab")
			(hide yes)
			(effects
				(font
					(size 1.016 1.016)
					(thickness 0.1524)
				)
			)
		)
		(duplicate_pad_numbers_are_jumpers no)
		(fp_line
			(start 0.889 -1.9304)
			(end 0.889 2.159)
			(stroke
				(width 0.1524)
				(type default)
			)
			(layer "F.SilkS")
		)
		(fp_line
			(start -0.889 -1.9304)
			(end 0.889 -1.9304)
			(stroke
				(width 0.1524)
				(type default)
			)
			(layer "F.SilkS")
		)
		(fp_line
			(start 0.762 2.0574)
			(end -0.762 2.0574)
			(stroke
				(width 0.508)
				(type default)
			)
			(layer "F.SilkS")
		)
		(fp_line
			(start 0.889 2.159)
			(end -0.889 2.159)
			(stroke
				(width 0.1524)
				(type default)
			)
			(layer "F.SilkS")
		)
		(fp_line
			(start -0.889 2.159)
			(end -0.889 -1.9304)
			(stroke
				(width 0.1524)
				(type default)
			)
			(layer "F.SilkS")
		)
		(fp_rect
			(start -1.016 2.3114)
			(end 1.016 -2.0066)
			(stroke
				(width 0)
				(type default)
			)
			(fill no)
			(layer "F.CrtYd")
		)
		(fp_poly
			(pts
				(xy -1.016 -2.0066) (xy 1.016 -2.0066) (xy 1.016 2.3114) (xy -1.016 2.3114)
			)
			(stroke
				(width 0)
				(type default)
			)
			(fill no)
			(layer "F.Fab")
		)
		(pad "A" smd rect
			(at 0 -1.143 90)
			(size 0.5588 1.016)
			(layers "F.Cu" "F.Mask" "F.Paste")
			(net "SW_HDD_R31")
		)
		(pad "K" smd rect
			(at 0 1.143 90)
			(size 0.5588 1.016)
			(layers "F.Cu" "F.Mask" "F.Paste")
			(net "SW_HDD_N31")
		)
	)
	(footprint ""
		(layer "F.Cu")
		(at 370.205 -142.875 -90)
		(property "Reference" "R522"
			(at 0 0 270)
			(layer "F.SilkS")
			(hide yes)
			(effects
				(font
					(size 1.27 1.27)
				)
			)
		)
		(property "Value" "300KR2F-GP"
			(at 0.064008 -3.993896 270)
			(unlocked yes)
			(layer "F.Fab")
			(hide yes)
			(effects
				(font
					(size 1.016 1.016)
					(thickness 0.1524)
				)
			)
		)
		(property "Device Type" "R402H16"
			(at 0.064008 -5.517896 270)
			(unlocked yes)
			(layer "F.Fab")
			(hide yes)
			(effects
				(font
					(size 1.016 1.016)
					(thickness 0.1524)
				)
			)
		)
		(duplicate_pad_numbers_are_jumpers no)
		(fp_line
			(start -0.508 -0.9398)
			(end -0.508 0.9398)
			(stroke
				(width 0.1524)
				(type default)
			)
			(layer "F.SilkS")
		)
		(fp_line
			(start 0.508 -0.9398)
			(end -0.508 -0.9398)
			(stroke
				(width 0.1524)
				(type default)
			)
			(layer "F.SilkS")
		)
		(fp_rect
			(start -0.508 0.9398)
			(end 0.508 -0.9398)
			(stroke
				(width 0)
				(type default)
			)
			(fill no)
			(layer "F.CrtYd")
		)
		(fp_rect
			(start -0.508 0.9398)
			(end 0.508 -0.9398)
			(stroke
				(width 0)
				(type default)
			)
			(fill no)
			(layer "F.Fab")
		)
		(pad "1" smd custom
			(at 0 -0.4445 270)
			(size 0.1397 0.1397)
			(layers "F.Cu" "F.Mask" "F.Paste")
			(net "SW_HDD_N19")
			(options
				(clearance outline)
				(anchor circle)
			)
			(primitives
				(gr_poly
					(pts
						(arc
							(start -0.1778 -0.2794)
							(mid -0.249642 -0.249642)
							(end -0.2794 -0.1778)
						)
						(arc
							(start -0.2794 0.1778)
							(mid -0.249642 0.249642)
							(end -0.1778 0.2794)
						)
						(arc
							(start 0.1778 0.2794)
							(mid 0.249642 0.249642)
							(end 0.2794 0.1778)
						)
						(arc
							(start 0.2794 -0.1778)
							(mid 0.249642 -0.249642)
							(end 0.1778 -0.2794)
						)
					)
					(width 0)
					(fill yes)
				)
			)
		)
		(pad "2" smd custom
			(at 0 0.4445 270)
			(size 0.1397 0.1397)
			(layers "F.Cu" "F.Mask" "F.Paste")
			(net "P12V_B")
			(options
				(clearance outline)
				(anchor circle)
			)
			(primitives
				(gr_poly
					(pts
						(arc
							(start -0.1778 -0.2794)
							(mid -0.249642 -0.249642)
							(end -0.2794 -0.1778)
						)
						(arc
							(start -0.2794 0.1778)
							(mid -0.249642 0.249642)
							(end -0.1778 0.2794)
						)
						(arc
							(start 0.1778 0.2794)
							(mid 0.249642 0.249642)
							(end 0.2794 0.1778)
						)
						(arc
							(start 0.2794 -0.1778)
							(mid 0.249642 -0.249642)
							(end 0.1778 -0.2794)
						)
					)
					(width 0)
					(fill yes)
				)
			)
		)
	)
	(footprint ""
		(layer "F.Cu")
		(at 252.461268 -222.9612 180)
		(property "Reference" "R106"
			(at 0 0 180)
			(layer "F.SilkS")
			(hide yes)
			(effects
				(font
					(size 1.27 1.27)
				)
			)
		)
		(property "Value" "4K7R2F-GP"
			(at 0.064008 -3.993896 180)
			(unlocked yes)
			(layer "F.Fab")
			(hide yes)
			(effects
				(font
					(size 1.016 1.016)
					(thickness 0.1524)
				)
			)
		)
		(property "Device Type" "R402H16"
			(at 0.064008 -5.517896 180)
			(unlocked yes)
			(layer "F.Fab")
			(hide yes)
			(effects
				(font
					(size 1.016 1.016)
					(thickness 0.1524)
				)
			)
		)
		(duplicate_pad_numbers_are_jumpers no)
		(fp_line
			(start 0.508 -0.9398)
			(end -0.508 -0.9398)
			(stroke
				(width 0.1524)
				(type default)
			)
			(layer "F.SilkS")
		)
		(fp_line
			(start -0.508 -0.9398)
			(end -0.508 0.9398)
			(stroke
				(width 0.1524)
				(type default)
			)
			(layer "F.SilkS")
		)
		(fp_rect
			(start -0.508 0.9398)
			(end 0.508 -0.9398)
			(stroke
				(width 0)
				(type default)
			)
			(fill no)
			(layer "F.CrtYd")
		)
		(fp_rect
			(start -0.508 0.9398)
			(end 0.508 -0.9398)
			(stroke
				(width 0)
				(type default)
			)
			(fill no)
			(layer "F.Fab")
		)
		(pad "1" smd custom
			(at 0 -0.4445 180)
			(size 0.1397 0.1397)
			(layers "F.Cu" "F.Mask" "F.Paste")
			(net "EEPROM_A0")
			(options
				(clearance outline)
				(anchor circle)
			)
			(primitives
				(gr_poly
					(pts
						(arc
							(start -0.1778 -0.2794)
							(mid -0.249642 -0.249642)
							(end -0.2794 -0.1778)
						)
						(arc
							(start -0.2794 0.1778)
							(mid -0.249642 0.249642)
							(end -0.1778 0.2794)
						)
						(arc
							(start 0.1778 0.2794)
							(mid 0.249642 0.249642)
							(end 0.2794 0.1778)
						)
						(arc
							(start 0.2794 -0.1778)
							(mid 0.249642 -0.249642)
							(end 0.1778 -0.2794)
						)
					)
					(width 0)
					(fill yes)
				)
			)
		)
		(pad "2" smd custom
			(at 0 0.4445 180)
			(size 0.1397 0.1397)
			(layers "F.Cu" "F.Mask" "F.Paste")
			(net "GND")
			(options
				(clearance outline)
				(anchor circle)
			)
			(primitives
				(gr_poly
					(pts
						(arc
							(start -0.1778 -0.2794)
							(mid -0.249642 -0.249642)
							(end -0.2794 -0.1778)
						)
						(arc
							(start -0.2794 0.1778)
							(mid -0.249642 0.249642)
							(end -0.1778 0.2794)
						)
						(arc
							(start 0.1778 0.2794)
							(mid 0.249642 0.249642)
							(end 0.2794 0.1778)
						)
						(arc
							(start 0.2794 -0.1778)
							(mid 0.249642 -0.249642)
							(end 0.1778 -0.2794)
						)
					)
					(width 0)
					(fill yes)
				)
			)
		)
	)
	(footprint ""
		(layer "F.Cu")
		(at 209.03946 -166.41826 90)
		(property "Reference" "R57"
			(at 0 0 90)
			(layer "F.SilkS")
			(hide yes)
			(effects
				(font
					(size 1.27 1.27)
				)
			)
		)
		(property "Value" "4K7R2F-GP"
			(at 0.064008 -3.993896 90)
			(unlocked yes)
			(layer "F.Fab")
			(hide yes)
			(effects
				(font
					(size 1.016 1.016)
					(thickness 0.1524)
				)
			)
		)
		(property "Device Type" "R402H16"
			(at 0.064008 -5.517896 90)
			(unlocked yes)
			(layer "F.Fab")
			(hide yes)
			(effects
				(font
					(size 1.016 1.016)
					(thickness 0.1524)
				)
			)
		)
		(duplicate_pad_numbers_are_jumpers no)
		(fp_line
			(start 0.508 -0.9398)
			(end -0.508 -0.9398)
			(stroke
				(width 0.1524)
				(type default)
			)
			(layer "F.SilkS")
		)
		(fp_line
			(start -0.508 -0.9398)
			(end -0.508 0.9398)
			(stroke
				(width 0.1524)
				(type default)
			)
			(layer "F.SilkS")
		)
		(fp_rect
			(start -0.508 0.9398)
			(end 0.508 -0.9398)
			(stroke
				(width 0)
				(type default)
			)
			(fill no)
			(layer "F.CrtYd")
		)
		(fp_rect
			(start -0.508 0.9398)
			(end 0.508 -0.9398)
			(stroke
				(width 0)
				(type default)
			)
			(fill no)
			(layer "F.Fab")
		)
		(pad "1" smd custom
			(at 0 -0.4445 90)
			(size 0.1397 0.1397)
			(layers "F.Cu" "F.Mask" "F.Paste")
			(net "P3V3_STBY_B")
			(options
				(clearance outline)
				(anchor circle)
			)
			(primitives
				(gr_poly
					(pts
						(arc
							(start -0.1778 -0.2794)
							(mid -0.249642 -0.249642)
							(end -0.2794 -0.1778)
						)
						(arc
							(start -0.2794 0.1778)
							(mid -0.249642 0.249642)
							(end -0.1778 0.2794)
						)
						(arc
							(start 0.1778 0.2794)
							(mid 0.249642 0.249642)
							(end 0.2794 0.1778)
						)
						(arc
							(start 0.2794 -0.1778)
							(mid 0.249642 -0.249642)
							(end 0.1778 -0.2794)
						)
					)
					(width 0)
					(fill yes)
				)
			)
		)
		(pad "2" smd custom
			(at 0 0.4445 90)
			(size 0.1397 0.1397)
			(layers "F.Cu" "F.Mask" "F.Paste")
			(net "IO_EXP6_A0")
			(options
				(clearance outline)
				(anchor circle)
			)
			(primitives
				(gr_poly
					(pts
						(arc
							(start -0.1778 -0.2794)
							(mid -0.249642 -0.249642)
							(end -0.2794 -0.1778)
						)
						(arc
							(start -0.2794 0.1778)
							(mid -0.249642 0.249642)
							(end -0.1778 0.2794)
						)
						(arc
							(start 0.1778 0.2794)
							(mid 0.249642 0.249642)
							(end 0.2794 0.1778)
						)
						(arc
							(start 0.2794 -0.1778)
							(mid 0.249642 -0.249642)
							(end 0.1778 -0.2794)
						)
					)
					(width 0)
					(fill yes)
				)
			)
		)
	)
	(footprint ""
		(layer "F.Cu")
		(at 131.445 -372.179596)
		(property "Reference" "D39"
			(at 0 0 0)
			(layer "F.SilkS")
			(hide yes)
			(effects
				(font
					(size 1.27 1.27)
				)
			)
		)
		(property "Value" "BAS16H-GP"
			(at 0 -5.5372 0)
			(unlocked yes)
			(layer "F.Fab")
			(hide yes)
			(effects
				(font
					(size 1.016 1.016)
					(thickness 0.1524)
				)
			)
		)
		(property "Device Type" "SOD123AKH48"
			(at 0 -7.0612 0)
			(unlocked yes)
			(layer "F.Fab")
			(hide yes)
			(effects
				(font
					(size 1.016 1.016)
					(thickness 0.1524)
				)
			)
		)
		(duplicate_pad_numbers_are_jumpers no)
		(fp_line
			(start -1.016 -2.667)
			(end -1.016 2.667)
			(stroke
				(width 0.1524)
				(type default)
			)
			(layer "F.SilkS")
		)
		(fp_line
			(start -1.016 2.667)
			(end 1.016 2.667)
			(stroke
				(width 0.1524)
				(type default)
			)
			(layer "F.SilkS")
		)
		(fp_line
			(start 0.889 2.921)
			(end -0.889 2.921)
			(stroke
				(width 0.508)
				(type default)
			)
			(layer "F.SilkS")
		)
		(fp_line
			(start 1.016 -2.667)
			(end -1.016 -2.667)
			(stroke
				(width 0.1524)
				(type default)
			)
			(layer "F.SilkS")
		)
		(fp_line
			(start 1.016 2.667)
			(end 1.016 -2.667)
			(stroke
				(width 0.1524)
				(type default)
			)
			(layer "F.SilkS")
		)
		(fp_rect
			(start -1.143 3.175)
			(end 1.143 -2.794)
			(stroke
				(width 0)
				(type default)
			)
			(fill no)
			(layer "F.CrtYd")
		)
		(fp_poly
			(pts
				(xy -1.143 -2.794) (xy 1.143 -2.794) (xy 1.143 3.175) (xy -1.143 3.175)
			)
			(stroke
				(width 0)
				(type default)
			)
			(fill no)
			(layer "F.Fab")
		)
		(pad "A" smd rect
			(at 0 -1.6891)
			(size 0.889 1.397)
			(layers "F.Cu" "F.Mask" "F.Paste")
			(net "FAN_1_TACH0")
		)
		(pad "K" smd rect
			(at 0 1.6891)
			(size 0.889 1.397)
			(layers "F.Cu" "F.Mask" "F.Paste")
			(net "P12V_IN")
		)
	)
	(footprint ""
		(layer "F.Cu")
		(at 172.593 -260.858)
		(property "Reference" "Q20"
			(at 0 0 0)
			(layer "F.SilkS")
			(hide yes)
			(effects
				(font
					(size 1.27 1.27)
				)
			)
		)
		(property "Value" "AO4407AL-GP"
			(at -3.707384 -1.5367 0)
			(unlocked yes)
			(layer "F.Fab")
			(hide yes)
			(effects
				(font
					(size 1.016 1.016)
					(thickness 0.1524)
				)
			)
		)
		(property "Device Type" "SOIC8H69"
			(at -3.707384 -3.0607 0)
			(unlocked yes)
			(layer "F.Fab")
			(hide yes)
			(effects
				(font
					(size 1.016 1.016)
					(thickness 0.1524)
				)
			)
		)
		(duplicate_pad_numbers_are_jumpers no)
		(fp_line
			(start -2.7432 -1.4224)
			(end -2.7432 1.4224)
			(stroke
				(width 0.1524)
				(type default)
			)
			(layer "F.SilkS")
		)
		(fp_line
			(start -2.7432 1.4224)
			(end -2.6416 1.4224)
			(stroke
				(width 0.1524)
				(type default)
			)
			(layer "F.SilkS")
		)
		(fp_line
			(start -2.7432 1.4224)
			(end 2.1336 1.4224)
			(stroke
				(width 0.1524)
				(type default)
			)
			(layer "F.SilkS")
		)
		(fp_line
			(start -2.7178 -0.508)
			(end -2.1844 -0.0508)
			(stroke
				(width 0.1524)
				(type default)
			)
			(layer "F.SilkS")
		)
		(fp_line
			(start -2.6289 3.4417)
			(end -2.6289 1.4732)
			(stroke
				(width 0.381)
				(type default)
			)
			(layer "F.SilkS")
		)
		(fp_line
			(start -2.1844 -0.0508)
			(end -2.7178 0.508)
			(stroke
				(width 0.1524)
				(type default)
			)
			(layer "F.SilkS")
		)
		(fp_line
			(start 2.1336 -1.4224)
			(end -2.7432 -1.4224)
			(stroke
				(width 0.1524)
				(type default)
			)
			(layer "F.SilkS")
		)
		(fp_line
			(start 2.1336 1.4224)
			(end 2.1336 -1.4224)
			(stroke
				(width 0.1524)
				(type default)
			)
			(layer "F.SilkS")
		)
		(fp_poly
			(pts
				(xy -2.2098 -1.4224) (xy -2.2098 1.4224) (xy 2.2098 1.4224) (xy 2.2098 -1.4224)
			)
			(stroke
				(width 0)
				(type default)
			)
			(fill yes)
			(layer "F.SilkS")
		)
		(fp_rect
			(start -2.450084 2.999994)
			(end 2.450084 -2.999994)
			(stroke
				(width 0)
				(type default)
			)
			(fill no)
			(layer "F.CrtYd")
		)
		(fp_poly
			(pts
				(xy -2.8194 3.6322) (xy -2.8194 -3.6322) (xy 2.8194 -3.6322) (xy 2.8194 1.18364) (xy 2.450084 1.18364)
				(xy 2.450084 -2.999994) (xy -2.450084 -2.999994) (xy -2.450084 2.999994) (xy 2.450084 2.999994)
				(xy 2.450084 1.18618) (xy 2.8194 1.18618) (xy 2.8194 3.6322)
			)
			(stroke
				(width 0)
				(type default)
			)
			(fill no)
			(layer "F.CrtYd")
		)
		(fp_rect
			(start -2.8194 3.6322)
			(end 2.8194 -3.6322)
			(stroke
				(width 0)
				(type default)
			)
			(fill no)
			(layer "F.Fab")
		)
		(pad "1" smd rect
			(at -1.905 2.54)
			(size 0.635 1.651)
			(layers "F.Cu" "F.Mask" "F.Paste")
			(net "P12V_B")
		)
		(pad "2" smd rect
			(at -0.635 2.54)
			(size 0.635 1.651)
			(layers "F.Cu" "F.Mask" "F.Paste")
			(net "P12V_B")
		)
		(pad "3" smd rect
			(at 0.635 2.54)
			(size 0.635 1.651)
			(layers "F.Cu" "F.Mask" "F.Paste")
			(net "P12V_B")
		)
		(pad "4" smd rect
			(at 1.905 2.54)
			(size 0.635 1.651)
			(layers "F.Cu" "F.Mask" "F.Paste")
			(net "SW_HDD_N5")
		)
		(pad "5" smd rect
			(at 1.905 -2.54)
			(size 0.635 1.651)
			(layers "F.Cu" "F.Mask" "F.Paste")
			(net "P12V_HDD5")
		)
		(pad "6" smd rect
			(at 0.635 -2.54)
			(size 0.635 1.651)
			(layers "F.Cu" "F.Mask" "F.Paste")
			(net "P12V_HDD5")
		)
		(pad "7" smd rect
			(at -0.635 -2.54)
			(size 0.635 1.651)
			(layers "F.Cu" "F.Mask" "F.Paste")
			(net "P12V_HDD5")
		)
		(pad "8" smd rect
			(at -1.905 -2.54)
			(size 0.635 1.651)
			(layers "F.Cu" "F.Mask" "F.Paste")
			(net "P12V_HDD5")
		)
	)
	(footprint ""
		(layer "F.Cu")
		(at 330.67498 -293.799768)
		(property "Reference" ""
			(at 0 0 0)
			(layer "F.SilkS")
			(hide yes)
			(effects
				(font
					(size 1.27 1.27)
				)
			)
		)
		(property "Value" "*"
			(at -8.398764 -8.057642 0)
			(unlocked yes)
			(layer "F.Fab")
			(hide yes)
			(effects
				(font
					(size 1.016 1.016)
					(thickness 0.1524)
				)
			)
		)
		(duplicate_pad_numbers_are_jumpers no)
		(fp_poly
			(pts
				(arc
					(start 7.3152 0)
					(mid 0 7.3152)
					(end -7.3152 0)
				)
				(arc
					(start -7.3152 -5.9944)
					(mid 0 -13.3096)
					(end 7.3152 -5.9944)
				)
			)
			(stroke
				(width 0)
				(type default)
			)
			(fill no)
			(layer "B.CrtYd")
		)
		(fp_poly
			(pts
				(arc
					(start 7.3152 0)
					(mid 0 7.3152)
					(end -7.3152 0)
				)
				(arc
					(start -7.3152 -5.9944)
					(mid 0 -13.3096)
					(end 7.3152 -5.9944)
				)
			)
			(stroke
				(width 0)
				(type default)
			)
			(fill no)
			(layer "F.CrtYd")
		)
		(fp_poly
			(pts
				(arc
					(start 7.3152 0)
					(mid 0 7.3152)
					(end -7.3152 0)
				)
				(arc
					(start -7.3152 -5.9944)
					(mid 0 -13.3096)
					(end 7.3152 -5.9944)
				)
			)
			(stroke
				(width 0)
				(type default)
			)
			(fill no)
			(layer "B.Fab")
		)
		(fp_poly
			(pts
				(arc
					(start 7.3152 0)
					(mid 0 7.3152)
					(end -7.3152 0)
				)
				(arc
					(start -7.3152 -5.9944)
					(mid 0 -13.3096)
					(end 7.3152 -5.9944)
				)
			)
			(stroke
				(width 0)
				(type default)
			)
			(fill no)
			(layer "F.Fab")
		)
		(pad "1" thru_hole oval
			(at 0 0)
			(size 14.0208 20.0152)
			(drill 0.0254
				(offset 0 -2.9972)
			)
			(layers "*.Cu" "*.Mask")
			(remove_unused_layers no)
			(net "Net_40")
			(clearance -1.002284)
			(thermal_gap 0.1524)
			(padstack
				(mode front_inner_back)
				(layer "Inner"
					(shape custom)
					(size 2.928012 2.928012)
					(options
						(anchor circle)
					)
					(primitives
						(gr_poly
							(pts
								(arc
									(start 4.571746 -2.084324)
									(mid 0.000333 7.430372)
									(end -4.571492 -2.084324)
								)
								(arc
									(start -4.571492 -2.084324)
									(mid -3.570296 -3.611977)
									(end -2.875026 -5.30098)
								)
								(arc
									(start -2.875026 -5.30098)
									(mid 0.000217 -7.43089)
									(end 2.87528 -5.30098)
								)
								(arc
									(start 2.87528 -5.30098)
									(mid 3.570511 -3.611956)
									(end 4.571746 -2.084324)
								)
							)
							(width 0)
							(fill yes)
						)
					)
					(clearance 0.1524)
				)
				(layer "B.Cu"
					(shape oval)
					(size 14.0208 20.0152)
					(offset 0 -2.9972)
					(clearance -1.002284)
				)
			)
		)
		(zone
			(layers "F.Cu" "B.Cu" "In1.Cu" "In2.Cu" "In3.Cu" "In4.Cu" "In5.Cu" "In6.Cu")
			(hatch none 0.5)
			(connect_pads
				(clearance 0)
			)
			(min_thickness 0.25)
			(keepout
				(tracks not_allowed)
				(vias allowed)
				(pads allowed)
				(copperpour not_allowed)
				(footprints allowed)
			)
			(placement
				(enabled no)
				(sheetname "")
			)
			(fill
				(thermal_gap 0.5)
				(thermal_bridge_width 0.5)
				(island_removal_mode 0)
			)
			(polygon
				(pts
					(arc
						(start 323.66458 -299.794168)
						(mid 330.67498 -306.804568)
						(end 337.68538 -299.794168)
					)
					(arc
						(start 337.68538 -293.799768)
						(mid 330.67498 -286.789368)
						(end 323.66458 -293.799768)
					)
				)
			)
		)
	)
	(footprint ""
		(layer "F.Cu")
		(at 86.995 -157.226)
		(property "Reference" "C217"
			(at 0 0 0)
			(layer "F.SilkS")
			(hide yes)
			(effects
				(font
					(size 1.27 1.27)
				)
			)
		)
		(property "Value" "SC4D7U25V5KX-1-GP"
			(at -0.0762 -6.1214 0)
			(unlocked yes)
			(layer "F.Fab")
			(hide yes)
			(effects
				(font
					(size 1.016 1.016)
					(thickness 0.1524)
				)
			)
		)
		(property "Device Type" "C805H58"
			(at -0.0762 -8.1534 0)
			(unlocked yes)
			(layer "F.Fab")
			(hide yes)
			(effects
				(font
					(size 1.016 1.016)
					(thickness 0.1524)
				)
			)
		)
		(duplicate_pad_numbers_are_jumpers no)
		(fp_line
			(start 0.635 0)
			(end -0.635 0)
			(stroke
				(width 0.508)
				(type default)
			)
			(layer "F.SilkS")
		)
		(fp_rect
			(start -0.9652 1.778)
			(end 0.9652 -1.778)
			(stroke
				(width 0)
				(type default)
			)
			(fill no)
			(layer "F.CrtYd")
		)
		(fp_poly
			(pts
				(xy -0.9652 -1.778) (xy 0.9652 -1.778) (xy 0.9652 1.778) (xy -0.9652 1.778)
			)
			(stroke
				(width 0)
				(type default)
			)
			(fill no)
			(layer "F.Fab")
		)
		(pad "1" smd rect
			(at 0 -0.9652)
			(size 1.397 1.143)
			(layers "F.Cu" "F.Mask" "F.Paste")
			(net "P12V_HDD14")
		)
		(pad "2" smd rect
			(at 0 0.9652)
			(size 1.397 1.143)
			(layers "F.Cu" "F.Mask" "F.Paste")
			(net "GND")
		)
	)
	(footprint ""
		(layer "F.Cu")
		(at 241.8334 -131.6482 180)
		(property "Reference" "R604"
			(at 0 0 180)
			(layer "F.SilkS")
			(hide yes)
			(effects
				(font
					(size 1.27 1.27)
				)
			)
		)
		(property "Value" "2K2R2F-GP"
			(at 0.064008 -3.993896 180)
			(unlocked yes)
			(layer "F.Fab")
			(hide yes)
			(effects
				(font
					(size 1.016 1.016)
					(thickness 0.1524)
				)
			)
		)
		(property "Device Type" "R402H16"
			(at 0.064008 -5.517896 180)
			(unlocked yes)
			(layer "F.Fab")
			(hide yes)
			(effects
				(font
					(size 1.016 1.016)
					(thickness 0.1524)
				)
			)
		)
		(duplicate_pad_numbers_are_jumpers no)
		(fp_line
			(start 0.508 -0.9398)
			(end -0.508 -0.9398)
			(stroke
				(width 0.1524)
				(type default)
			)
			(layer "F.SilkS")
		)
		(fp_line
			(start -0.508 -0.9398)
			(end -0.508 0.9398)
			(stroke
				(width 0.1524)
				(type default)
			)
			(layer "F.SilkS")
		)
		(fp_rect
			(start -0.508 0.9398)
			(end 0.508 -0.9398)
			(stroke
				(width 0)
				(type default)
			)
			(fill no)
			(layer "F.CrtYd")
		)
		(fp_rect
			(start -0.508 0.9398)
			(end 0.508 -0.9398)
			(stroke
				(width 0)
				(type default)
			)
			(fill no)
			(layer "F.Fab")
		)
		(pad "1" smd custom
			(at 0 -0.4445 180)
			(size 0.1397 0.1397)
			(layers "F.Cu" "F.Mask" "F.Paste")
			(net "P3V3_STBY_B")
			(options
				(clearance outline)
				(anchor circle)
			)
			(primitives
				(gr_poly
					(pts
						(arc
							(start -0.1778 -0.2794)
							(mid -0.249642 -0.249642)
							(end -0.2794 -0.1778)
						)
						(arc
							(start -0.2794 0.1778)
							(mid -0.249642 0.249642)
							(end -0.1778 0.2794)
						)
						(arc
							(start 0.1778 0.2794)
							(mid 0.249642 0.249642)
							(end 0.2794 0.1778)
						)
						(arc
							(start 0.2794 -0.1778)
							(mid 0.249642 -0.249642)
							(end 0.1778 -0.2794)
						)
					)
					(width 0)
					(fill yes)
				)
			)
		)
		(pad "2" smd custom
			(at 0 0.4445 180)
			(size 0.1397 0.1397)
			(layers "F.Cu" "F.Mask" "F.Paste")
			(net "I2C_DPB_B_SCL")
			(options
				(clearance outline)
				(anchor circle)
			)
			(primitives
				(gr_poly
					(pts
						(arc
							(start -0.1778 -0.2794)
							(mid -0.249642 -0.249642)
							(end -0.2794 -0.1778)
						)
						(arc
							(start -0.2794 0.1778)
							(mid -0.249642 0.249642)
							(end -0.1778 0.2794)
						)
						(arc
							(start 0.1778 0.2794)
							(mid 0.249642 0.249642)
							(end 0.2794 0.1778)
						)
						(arc
							(start 0.2794 -0.1778)
							(mid 0.249642 -0.249642)
							(end 0.1778 -0.2794)
						)
					)
					(width 0)
					(fill yes)
				)
			)
		)
	)
	(footprint ""
		(layer "F.Cu")
		(at 457.7842 -135.6614 -90)
		(property "Reference" "C324"
			(at 0 0 270)
			(layer "F.SilkS")
			(hide yes)
			(effects
				(font
					(size 1.27 1.27)
				)
			)
		)
		(property "Value" "SCD033U25V2KX-GP"
			(at 1.1811 -2.7051 270)
			(unlocked yes)
			(layer "F.Fab")
			(hide yes)
			(effects
				(font
					(size 1.016 1.016)
					(thickness 0.1524)
				)
			)
		)
		(property "Device Type" "C402H22"
			(at 1.1811 -4.2291 270)
			(unlocked yes)
			(layer "F.Fab")
			(hide yes)
			(effects
				(font
					(size 1.016 1.016)
					(thickness 0.1524)
				)
			)
		)
		(duplicate_pad_numbers_are_jumpers no)
		(fp_rect
			(start -0.4318 0.9525)
			(end 0.4318 -0.9525)
			(stroke
				(width 0)
				(type default)
			)
			(fill no)
			(layer "F.CrtYd")
		)
		(fp_rect
			(start -0.4318 0.9525)
			(end 0.4318 -0.9525)
			(stroke
				(width 0)
				(type default)
			)
			(fill no)
			(layer "F.Fab")
		)
		(pad "1" smd custom
			(at 0 -0.4445 270)
			(size 0.1524 0.1524)
			(layers "F.Cu" "F.Mask" "F.Paste")
			(net "SW_HDD_P22")
			(options
				(clearance outline)
				(anchor circle)
			)
			(primitives
				(gr_poly
					(pts
						(arc
							(start 0.3048 -0.2032)
							(mid 0.275042 -0.275042)
							(end 0.2032 -0.3048)
						)
						(arc
							(start -0.2032 -0.3048)
							(mid -0.275042 -0.275042)
							(end -0.3048 -0.2032)
						)
						(arc
							(start -0.3048 0.2032)
							(mid -0.275042 0.275042)
							(end -0.2032 0.3048)
						)
						(arc
							(start 0.2032 0.3048)
							(mid 0.275042 0.275042)
							(end 0.3048 0.2032)
						)
					)
					(width 0)
					(fill yes)
				)
			)
		)
		(pad "2" smd custom
			(at 0 0.4445 270)
			(size 0.1524 0.1524)
			(layers "F.Cu" "F.Mask" "F.Paste")
			(net "GND")
			(options
				(clearance outline)
				(anchor circle)
			)
			(primitives
				(gr_poly
					(pts
						(arc
							(start 0.3048 -0.2032)
							(mid 0.275042 -0.275042)
							(end 0.2032 -0.3048)
						)
						(arc
							(start -0.2032 -0.3048)
							(mid -0.275042 -0.275042)
							(end -0.3048 -0.2032)
						)
						(arc
							(start -0.3048 0.2032)
							(mid -0.275042 0.275042)
							(end -0.2032 0.3048)
						)
						(arc
							(start 0.2032 0.3048)
							(mid 0.275042 0.275042)
							(end 0.3048 0.2032)
						)
					)
					(width 0)
					(fill yes)
				)
			)
		)
	)
	(footprint ""
		(layer "F.Cu")
		(at 109.347 -265.684 -90)
		(property "Reference" "C73"
			(at 0 0 270)
			(layer "F.SilkS")
			(hide yes)
			(effects
				(font
					(size 1.27 1.27)
				)
			)
		)
		(property "Value" "SC4D7U25V5KX-1-GP"
			(at -0.0762 -6.1214 270)
			(unlocked yes)
			(layer "F.Fab")
			(hide yes)
			(effects
				(font
					(size 1.016 1.016)
					(thickness 0.1524)
				)
			)
		)
		(property "Device Type" "C805H58"
			(at -0.0762 -8.1534 270)
			(unlocked yes)
			(layer "F.Fab")
			(hide yes)
			(effects
				(font
					(size 1.016 1.016)
					(thickness 0.1524)
				)
			)
		)
		(duplicate_pad_numbers_are_jumpers no)
		(fp_line
			(start 0.635 0)
			(end -0.635 0)
			(stroke
				(width 0.508)
				(type default)
			)
			(layer "F.SilkS")
		)
		(fp_rect
			(start -0.9652 1.778)
			(end 0.9652 -1.778)
			(stroke
				(width 0)
				(type default)
			)
			(fill no)
			(layer "F.CrtYd")
		)
		(fp_poly
			(pts
				(xy -0.9652 -1.778) (xy 0.9652 -1.778) (xy 0.9652 1.778) (xy -0.9652 1.778)
			)
			(stroke
				(width 0)
				(type default)
			)
			(fill no)
			(layer "F.Fab")
		)
		(pad "1" smd rect
			(at 0 -0.9652 270)
			(size 1.397 1.143)
			(layers "F.Cu" "F.Mask" "F.Paste")
			(net "P12V_HDD3")
		)
		(pad "2" smd rect
			(at 0 0.9652 270)
			(size 1.397 1.143)
			(layers "F.Cu" "F.Mask" "F.Paste")
			(net "GND")
		)
	)
	(footprint ""
		(layer "F.Cu")
		(at 16.764 -24.13 -90)
		(property "Reference" "C350"
			(at 0 0 270)
			(layer "F.SilkS")
			(hide yes)
			(effects
				(font
					(size 1.27 1.27)
				)
			)
		)
		(property "Value" "SCD033U25V2KX-GP"
			(at 1.1811 -2.7051 270)
			(unlocked yes)
			(layer "F.Fab")
			(hide yes)
			(effects
				(font
					(size 1.016 1.016)
					(thickness 0.1524)
				)
			)
		)
		(property "Device Type" "C402H22"
			(at 1.1811 -4.2291 270)
			(unlocked yes)
			(layer "F.Fab")
			(hide yes)
			(effects
				(font
					(size 1.016 1.016)
					(thickness 0.1524)
				)
			)
		)
		(duplicate_pad_numbers_are_jumpers no)
		(fp_rect
			(start -0.4318 0.9525)
			(end 0.4318 -0.9525)
			(stroke
				(width 0)
				(type default)
			)
			(fill no)
			(layer "F.CrtYd")
		)
		(fp_rect
			(start -0.4318 0.9525)
			(end 0.4318 -0.9525)
			(stroke
				(width 0)
				(type default)
			)
			(fill no)
			(layer "F.Fab")
		)
		(pad "1" smd custom
			(at 0 -0.4445 270)
			(size 0.1524 0.1524)
			(layers "F.Cu" "F.Mask" "F.Paste")
			(net "SW_HDD_P24")
			(options
				(clearance outline)
				(anchor circle)
			)
			(primitives
				(gr_poly
					(pts
						(arc
							(start 0.3048 -0.2032)
							(mid 0.275042 -0.275042)
							(end 0.2032 -0.3048)
						)
						(arc
							(start -0.2032 -0.3048)
							(mid -0.275042 -0.275042)
							(end -0.3048 -0.2032)
						)
						(arc
							(start -0.3048 0.2032)
							(mid -0.275042 0.275042)
							(end -0.2032 0.3048)
						)
						(arc
							(start 0.2032 0.3048)
							(mid 0.275042 0.275042)
							(end 0.3048 0.2032)
						)
					)
					(width 0)
					(fill yes)
				)
			)
		)
		(pad "2" smd custom
			(at 0 0.4445 270)
			(size 0.1524 0.1524)
			(layers "F.Cu" "F.Mask" "F.Paste")
			(net "GND")
			(options
				(clearance outline)
				(anchor circle)
			)
			(primitives
				(gr_poly
					(pts
						(arc
							(start 0.3048 -0.2032)
							(mid 0.275042 -0.275042)
							(end 0.2032 -0.3048)
						)
						(arc
							(start -0.2032 -0.3048)
							(mid -0.275042 -0.275042)
							(end -0.3048 -0.2032)
						)
						(arc
							(start -0.3048 0.2032)
							(mid -0.275042 0.275042)
							(end -0.2032 0.3048)
						)
						(arc
							(start 0.2032 0.3048)
							(mid 0.275042 0.275042)
							(end 0.3048 0.2032)
						)
					)
					(width 0)
					(fill yes)
				)
			)
		)
	)
	(footprint ""
		(layer "F.Cu")
		(at 414.436052 -128.627124 180)
		(property "Reference" "VIA43"
			(at 0 0 180)
			(layer "F.SilkS")
			(hide yes)
			(effects
				(font
					(size 1.27 1.27)
				)
			)
		)
		(property "Value" "100OHM-8L-2D36MM-L18-GP"
			(at 3.8989 0.5715 180)
			(unlocked yes)
			(layer "F.Fab")
			(hide yes)
			(effects
				(font
					(size 1.016 1.016)
					(thickness 0.1524)
				)
			)
		)
		(property "Device Type" "VIA-PCIE-4P-414097"
			(at 3.8989 -0.9525 180)
			(unlocked yes)
			(layer "F.Fab")
			(hide yes)
			(effects
				(font
					(size 1.016 1.016)
					(thickness 0.1524)
				)
			)
		)
		(duplicate_pad_numbers_are_jumpers no)
		(fp_rect
			(start -2.0701 0.4826)
			(end 2.0701 -0.4826)
			(stroke
				(width 0)
				(type default)
			)
			(fill no)
			(layer "F.CrtYd")
		)
		(fp_rect
			(start -2.0701 0.4826)
			(end 2.0701 -0.4826)
			(stroke
				(width 0)
				(type default)
			)
			(fill no)
			(layer "F.Fab")
		)
		(pad "1" thru_hole circle
			(at -1.5875 0 180)
			(size 0.508 0.508)
			(drill 0.254)
			(layers "*.Cu" "*.Mask")
			(remove_unused_layers no)
			(net "GND")
			(clearance 0.2286)
			(thermal_gap 0.2286)
		)
		(pad "2" thru_hole circle
			(at -0.5715 0 180)
			(size 0.508 0.508)
			(drill 0.254)
			(layers "*.Cu" "*.Mask")
			(remove_unused_layers no)
			(net "PHY_SCC_B_TO_DRV_B_21_DP")
			(clearance 0.2286)
			(thermal_gap 0.2286)
		)
		(pad "3" thru_hole circle
			(at 0.5715 0 180)
			(size 0.508 0.508)
			(drill 0.254)
			(layers "*.Cu" "*.Mask")
			(remove_unused_layers no)
			(net "PHY_SCC_B_TO_DRV_B_21_DN")
			(clearance 0.2286)
			(thermal_gap 0.2286)
		)
		(pad "4" thru_hole circle
			(at 1.5875 0 180)
			(size 0.508 0.508)
			(drill 0.254)
			(layers "*.Cu" "*.Mask")
			(remove_unused_layers no)
			(net "GND")
			(clearance 0.2286)
			(thermal_gap 0.2286)
		)
	)
	(footprint ""
		(layer "F.Cu")
		(at 445.9859 -128.627124 180)
		(property "Reference" "VIA45"
			(at 0 0 180)
			(layer "F.SilkS")
			(hide yes)
			(effects
				(font
					(size 1.27 1.27)
				)
			)
		)
		(property "Value" "100OHM-8L-2D36MM-L18-GP"
			(at 3.8989 0.5715 180)
			(unlocked yes)
			(layer "F.Fab")
			(hide yes)
			(effects
				(font
					(size 1.016 1.016)
					(thickness 0.1524)
				)
			)
		)
		(property "Device Type" "VIA-PCIE-4P-414097"
			(at 3.8989 -0.9525 180)
			(unlocked yes)
			(layer "F.Fab")
			(hide yes)
			(effects
				(font
					(size 1.016 1.016)
					(thickness 0.1524)
				)
			)
		)
		(duplicate_pad_numbers_are_jumpers no)
		(fp_rect
			(start -2.0701 0.4826)
			(end 2.0701 -0.4826)
			(stroke
				(width 0)
				(type default)
			)
			(fill no)
			(layer "F.CrtYd")
		)
		(fp_rect
			(start -2.0701 0.4826)
			(end 2.0701 -0.4826)
			(stroke
				(width 0)
				(type default)
			)
			(fill no)
			(layer "F.Fab")
		)
		(pad "1" thru_hole circle
			(at -1.5875 0 180)
			(size 0.508 0.508)
			(drill 0.254)
			(layers "*.Cu" "*.Mask")
			(remove_unused_layers no)
			(net "GND")
			(clearance 0.2286)
			(thermal_gap 0.2286)
		)
		(pad "2" thru_hole circle
			(at -0.5715 0 180)
			(size 0.508 0.508)
			(drill 0.254)
			(layers "*.Cu" "*.Mask")
			(remove_unused_layers no)
			(net "PHY_SCC_B_TO_DRV_B_22_DP")
			(clearance 0.2286)
			(thermal_gap 0.2286)
		)
		(pad "3" thru_hole circle
			(at 0.5715 0 180)
			(size 0.508 0.508)
			(drill 0.254)
			(layers "*.Cu" "*.Mask")
			(remove_unused_layers no)
			(net "PHY_SCC_B_TO_DRV_B_22_DN")
			(clearance 0.2286)
			(thermal_gap 0.2286)
		)
		(pad "4" thru_hole circle
			(at 1.5875 0 180)
			(size 0.508 0.508)
			(drill 0.254)
			(layers "*.Cu" "*.Mask")
			(remove_unused_layers no)
			(net "GND")
			(clearance 0.2286)
			(thermal_gap 0.2286)
		)
	)
	(footprint ""
		(layer "F.Cu")
		(at 284.955742 -379.335792 90)
		(property "Reference" "R1065"
			(at 0 0 90)
			(layer "F.SilkS")
			(hide yes)
			(effects
				(font
					(size 1.27 1.27)
				)
			)
		)
		(property "Value" "68R5J-GP"
			(at 0 -8.9535 90)
			(unlocked yes)
			(layer "F.Fab")
			(hide yes)
			(effects
				(font
					(size 1.27 1.016)
					(thickness 0.1524)
				)
			)
		)
		(property "Device Type" "R805H24"
			(at 0 -10.6299 90)
			(unlocked yes)
			(layer "F.Fab")
			(hide yes)
			(effects
				(font
					(size 1.27 1.016)
					(thickness 0.1524)
				)
			)
		)
		(duplicate_pad_numbers_are_jumpers no)
		(fp_line
			(start 0.889 -1.7018)
			(end -0.889 -1.7018)
			(stroke
				(width 0.1524)
				(type default)
			)
			(layer "F.SilkS")
		)
		(fp_line
			(start 0.889 -1.7018)
			(end 0.889 -0.381)
			(stroke
				(width 0.1524)
				(type default)
			)
			(layer "F.SilkS")
		)
		(fp_line
			(start -0.889 -1.7018)
			(end -0.889 0.2794)
			(stroke
				(width 0.1524)
				(type default)
			)
			(layer "F.SilkS")
		)
		(fp_line
			(start -0.889 0.0762)
			(end -0.889 1.7018)
			(stroke
				(width 0.1524)
				(type default)
			)
			(layer "F.SilkS")
		)
		(fp_line
			(start 0.889 1.7018)
			(end 0.889 -0.508)
			(stroke
				(width 0.1524)
				(type default)
			)
			(layer "F.SilkS")
		)
		(fp_line
			(start -0.889 1.7018)
			(end 0.889 1.7018)
			(stroke
				(width 0.1524)
				(type default)
			)
			(layer "F.SilkS")
		)
		(fp_poly
			(pts
				(xy 0.9652 -1.778) (xy 0.9652 1.778) (xy -0.9652 1.778) (xy -0.9652 -1.778)
			)
			(stroke
				(width 0)
				(type default)
			)
			(fill no)
			(layer "F.CrtYd")
		)
		(fp_rect
			(start -0.9652 1.778)
			(end 0.9652 -1.778)
			(stroke
				(width 0)
				(type default)
			)
			(fill no)
			(layer "F.Fab")
		)
		(pad "1" smd rect
			(at 0 -0.9652 90)
			(size 1.397 1.143)
			(layers "F.Cu" "F.Mask" "F.Paste")
			(net "EMITTER_K")
		)
		(pad "2" smd rect
			(at 0 0.9652 90)
			(size 1.397 1.143)
			(layers "F.Cu" "F.Mask" "F.Paste")
			(net "GND")
		)
	)
	(footprint ""
		(layer "F.Cu")
		(at 343.454228 -99.756976 180)
		(property "Reference" "Q238"
			(at 0 0 180)
			(layer "F.SilkS")
			(hide yes)
			(effects
				(font
					(size 1.27 1.27)
				)
			)
		)
		(property "Value" "2N7002K-2-GP"
			(at 0.127 -8.9662 180)
			(unlocked yes)
			(layer "F.Fab")
			(hide yes)
			(effects
				(font
					(size 1.016 1.016)
					(thickness 0.1524)
				)
			)
		)
		(property "Device Type" "SOT23DGS2D4H44"
			(at 0.127 -10.4902 180)
			(unlocked yes)
			(layer "F.Fab")
			(hide yes)
			(effects
				(font
					(size 1.016 1.016)
					(thickness 0.1524)
				)
			)
		)
		(duplicate_pad_numbers_are_jumpers no)
		(fp_line
			(start 1.651 1.778)
			(end 1.651 -1.778)
			(stroke
				(width 0.1524)
				(type default)
			)
			(layer "F.SilkS")
		)
		(fp_line
			(start 1.651 -1.778)
			(end -1.651 -1.778)
			(stroke
				(width 0.1524)
				(type default)
			)
			(layer "F.SilkS")
		)
		(fp_line
			(start -1.651 1.778)
			(end 1.651 1.778)
			(stroke
				(width 0.1524)
				(type default)
			)
			(layer "F.SilkS")
		)
		(fp_line
			(start -1.651 -1.778)
			(end -1.651 1.778)
			(stroke
				(width 0.1524)
				(type default)
			)
			(layer "F.SilkS")
		)
		(fp_poly
			(pts
				(xy -1.778 1.8796) (xy -1.778 -1.8796) (xy 1.778 -1.8796) (xy 1.778 1.8796)
			)
			(stroke
				(width 0)
				(type default)
			)
			(fill no)
			(layer "F.CrtYd")
		)
		(fp_poly
			(pts
				(xy -1.778 1.8796) (xy -1.778 -1.8796) (xy 1.778 -1.8796) (xy 1.778 1.8796)
			)
			(stroke
				(width 0)
				(type default)
			)
			(fill no)
			(layer "F.Fab")
		)
		(pad "D" smd custom
			(at 0 -0.9525 180)
			(size 0.1905 0.1905)
			(layers "F.Cu" "F.Mask" "F.Paste")
			(net "FLT_HDD19_N")
			(options
				(clearance outline)
				(anchor circle)
			)
			(primitives
				(gr_poly
					(pts
						(arc
							(start -0.1778 0.5715)
							(mid -0.321484 0.511984)
							(end -0.381 0.3683)
						)
						(arc
							(start -0.381 -0.3683)
							(mid -0.321484 -0.511984)
							(end -0.1778 -0.5715)
						)
						(arc
							(start 0.1778 -0.5715)
							(mid 0.321484 -0.511984)
							(end 0.381 -0.3683)
						)
						(arc
							(start 0.381 0.3683)
							(mid 0.321484 0.511984)
							(end 0.1778 0.5715)
						)
					)
					(width 0)
					(fill yes)
				)
			)
		)
		(pad "G" smd custom
			(at -0.98425 0.9525 180)
			(size 0.1905 0.1905)
			(layers "F.Cu" "F.Mask" "F.Paste")
			(net "DRIVE_B_19_FLT_LED")
			(options
				(clearance outline)
				(anchor circle)
			)
			(primitives
				(gr_poly
					(pts
						(arc
							(start -0.1778 0.5715)
							(mid -0.321484 0.511984)
							(end -0.381 0.3683)
						)
						(arc
							(start -0.381 -0.3683)
							(mid -0.321484 -0.511984)
							(end -0.1778 -0.5715)
						)
						(arc
							(start 0.1778 -0.5715)
							(mid 0.321484 -0.511984)
							(end 0.381 -0.3683)
						)
						(arc
							(start 0.381 0.3683)
							(mid 0.321484 0.511984)
							(end 0.1778 0.5715)
						)
					)
					(width 0)
					(fill yes)
				)
			)
		)
		(pad "S" smd custom
			(at 0.98425 0.9525 180)
			(size 0.1905 0.1905)
			(layers "F.Cu" "F.Mask" "F.Paste")
			(net "GND")
			(options
				(clearance outline)
				(anchor circle)
			)
			(primitives
				(gr_poly
					(pts
						(arc
							(start -0.1778 0.5715)
							(mid -0.321484 0.511984)
							(end -0.381 0.3683)
						)
						(arc
							(start -0.381 -0.3683)
							(mid -0.321484 -0.511984)
							(end -0.1778 -0.5715)
						)
						(arc
							(start 0.1778 -0.5715)
							(mid 0.321484 -0.511984)
							(end 0.381 -0.3683)
						)
						(arc
							(start 0.381 0.3683)
							(mid 0.321484 0.511984)
							(end 0.1778 0.5715)
						)
					)
					(width 0)
					(fill yes)
				)
			)
		)
	)
	(footprint ""
		(layer "F.Cu")
		(at 409.194 -99.187)
		(property "Reference" "R448"
			(at 0 0 0)
			(layer "F.SilkS")
			(hide yes)
			(effects
				(font
					(size 1.27 1.27)
				)
			)
		)
		(property "Value" "130R3F-GP"
			(at -0.0254 -2.5146 0)
			(unlocked yes)
			(layer "F.Fab")
			(hide yes)
			(effects
				(font
					(size 1.016 1.016)
					(thickness 0.1524)
				)
			)
		)
		(property "Device Type" "R603H22"
			(at -0.0254 -4.0386 0)
			(unlocked yes)
			(layer "F.Fab")
			(hide yes)
			(effects
				(font
					(size 1.016 1.016)
					(thickness 0.1524)
				)
			)
		)
		(duplicate_pad_numbers_are_jumpers no)
		(fp_line
			(start -0.4826 0)
			(end -0.2032 0)
			(stroke
				(width 0.2032)
				(type default)
			)
			(layer "F.SilkS")
		)
		(fp_line
			(start 0.2032 0)
			(end 0.4826 0)
			(stroke
				(width 0.2032)
				(type default)
			)
			(layer "F.SilkS")
		)
		(fp_rect
			(start -0.5842 1.3335)
			(end 0.5842 -1.3335)
			(stroke
				(width 0)
				(type default)
			)
			(fill no)
			(layer "F.CrtYd")
		)
		(fp_rect
			(start -0.5842 1.3335)
			(end 0.5842 -1.3335)
			(stroke
				(width 0)
				(type default)
			)
			(fill no)
			(layer "F.Fab")
		)
		(pad "1" smd custom
			(at 0 -0.762)
			(size 0.2159 0.2159)
			(layers "F.Cu" "F.Mask" "F.Paste")
			(net "P5V_B_4")
			(options
				(clearance outline)
				(anchor circle)
			)
			(primitives
				(gr_poly
					(pts
						(arc
							(start -0.3302 -0.4318)
							(mid -0.402042 -0.402042)
							(end -0.4318 -0.3302)
						)
						(arc
							(start -0.4318 0.3302)
							(mid -0.402042 0.402042)
							(end -0.3302 0.4318)
						)
						(arc
							(start 0.3302 0.4318)
							(mid 0.402042 0.402042)
							(end 0.4318 0.3302)
						)
						(arc
							(start 0.4318 -0.3302)
							(mid 0.402042 -0.402042)
							(end 0.3302 -0.4318)
						)
					)
					(width 0)
					(fill yes)
				)
			)
		)
		(pad "2" smd custom
			(at 0 0.762)
			(size 0.2159 0.2159)
			(layers "F.Cu" "F.Mask" "F.Paste")
			(net "FLT_HDD21")
			(options
				(clearance outline)
				(anchor circle)
			)
			(primitives
				(gr_poly
					(pts
						(arc
							(start -0.3302 -0.4318)
							(mid -0.402042 -0.402042)
							(end -0.4318 -0.3302)
						)
						(arc
							(start -0.4318 0.3302)
							(mid -0.402042 0.402042)
							(end -0.3302 0.4318)
						)
						(arc
							(start 0.3302 0.4318)
							(mid 0.402042 0.402042)
							(end 0.4318 0.3302)
						)
						(arc
							(start 0.4318 -0.3302)
							(mid 0.402042 -0.402042)
							(end 0.3302 -0.4318)
						)
					)
					(width 0)
					(fill yes)
				)
			)
		)
	)
	(footprint ""
		(layer "F.Cu")
		(at 161.163 -371.983 90)
		(property "Reference" "R935"
			(at 0 0 90)
			(layer "F.SilkS")
			(hide yes)
			(effects
				(font
					(size 1.27 1.27)
				)
			)
		)
		(property "Value" "0R2J-2-GP"
			(at 0.064008 -3.993896 90)
			(unlocked yes)
			(layer "F.Fab")
			(hide yes)
			(effects
				(font
					(size 1.016 1.016)
					(thickness 0.1524)
				)
			)
		)
		(property "Device Type" "R402H16"
			(at 0.064008 -5.517896 90)
			(unlocked yes)
			(layer "F.Fab")
			(hide yes)
			(effects
				(font
					(size 1.016 1.016)
					(thickness 0.1524)
				)
			)
		)
		(duplicate_pad_numbers_are_jumpers no)
		(fp_line
			(start 0.508 -0.9398)
			(end -0.508 -0.9398)
			(stroke
				(width 0.1524)
				(type default)
			)
			(layer "F.SilkS")
		)
		(fp_line
			(start -0.508 -0.9398)
			(end -0.508 0.9398)
			(stroke
				(width 0.1524)
				(type default)
			)
			(layer "F.SilkS")
		)
		(fp_rect
			(start -0.508 0.9398)
			(end 0.508 -0.9398)
			(stroke
				(width 0)
				(type default)
			)
			(fill no)
			(layer "F.CrtYd")
		)
		(fp_rect
			(start -0.508 0.9398)
			(end 0.508 -0.9398)
			(stroke
				(width 0)
				(type default)
			)
			(fill no)
			(layer "F.Fab")
		)
		(pad "1" smd custom
			(at 0 -0.4445 90)
			(size 0.1397 0.1397)
			(layers "F.Cu" "F.Mask" "F.Paste")
			(net "FAN_1_PWM")
			(options
				(clearance outline)
				(anchor circle)
			)
			(primitives
				(gr_poly
					(pts
						(arc
							(start -0.1778 -0.2794)
							(mid -0.249642 -0.249642)
							(end -0.2794 -0.1778)
						)
						(arc
							(start -0.2794 0.1778)
							(mid -0.249642 0.249642)
							(end -0.1778 0.2794)
						)
						(arc
							(start 0.1778 0.2794)
							(mid 0.249642 0.249642)
							(end 0.2794 0.1778)
						)
						(arc
							(start 0.2794 -0.1778)
							(mid 0.249642 -0.249642)
							(end 0.1778 -0.2794)
						)
					)
					(width 0)
					(fill yes)
				)
			)
		)
		(pad "2" smd custom
			(at 0 0.4445 90)
			(size 0.1397 0.1397)
			(layers "F.Cu" "F.Mask" "F.Paste")
			(net "PWM_OUT_FAN1")
			(options
				(clearance outline)
				(anchor circle)
			)
			(primitives
				(gr_poly
					(pts
						(arc
							(start -0.1778 -0.2794)
							(mid -0.249642 -0.249642)
							(end -0.2794 -0.1778)
						)
						(arc
							(start -0.2794 0.1778)
							(mid -0.249642 0.249642)
							(end -0.1778 0.2794)
						)
						(arc
							(start 0.1778 0.2794)
							(mid 0.249642 0.249642)
							(end 0.2794 0.1778)
						)
						(arc
							(start 0.2794 -0.1778)
							(mid 0.249642 -0.249642)
							(end 0.1778 -0.2794)
						)
					)
					(width 0)
					(fill yes)
				)
			)
		)
	)
	(footprint ""
		(layer "F.Cu")
		(at 46.355 -140.462 90)
		(property "Reference" "C208"
			(at 0 0 90)
			(layer "F.SilkS")
			(hide yes)
			(effects
				(font
					(size 1.27 1.27)
				)
			)
		)
		(property "Value" "SCD033U25V2KX-GP"
			(at 1.1811 -2.7051 90)
			(unlocked yes)
			(layer "F.Fab")
			(hide yes)
			(effects
				(font
					(size 1.016 1.016)
					(thickness 0.1524)
				)
			)
		)
		(property "Device Type" "C402H22"
			(at 1.1811 -4.2291 90)
			(unlocked yes)
			(layer "F.Fab")
			(hide yes)
			(effects
				(font
					(size 1.016 1.016)
					(thickness 0.1524)
				)
			)
		)
		(duplicate_pad_numbers_are_jumpers no)
		(fp_rect
			(start -0.4318 0.9525)
			(end 0.4318 -0.9525)
			(stroke
				(width 0)
				(type default)
			)
			(fill no)
			(layer "F.CrtYd")
		)
		(fp_rect
			(start -0.4318 0.9525)
			(end 0.4318 -0.9525)
			(stroke
				(width 0)
				(type default)
			)
			(fill no)
			(layer "F.Fab")
		)
		(pad "1" smd custom
			(at 0 -0.4445 90)
			(size 0.1524 0.1524)
			(layers "F.Cu" "F.Mask" "F.Paste")
			(net "P12V_B")
			(options
				(clearance outline)
				(anchor circle)
			)
			(primitives
				(gr_poly
					(pts
						(arc
							(start 0.3048 -0.2032)
							(mid 0.275042 -0.275042)
							(end 0.2032 -0.3048)
						)
						(arc
							(start -0.2032 -0.3048)
							(mid -0.275042 -0.275042)
							(end -0.3048 -0.2032)
						)
						(arc
							(start -0.3048 0.2032)
							(mid -0.275042 0.275042)
							(end -0.2032 0.3048)
						)
						(arc
							(start 0.2032 0.3048)
							(mid 0.275042 0.275042)
							(end 0.3048 0.2032)
						)
					)
					(width 0)
					(fill yes)
				)
			)
		)
		(pad "2" smd custom
			(at 0 0.4445 90)
			(size 0.1524 0.1524)
			(layers "F.Cu" "F.Mask" "F.Paste")
			(net "SW_HDD_N13")
			(options
				(clearance outline)
				(anchor circle)
			)
			(primitives
				(gr_poly
					(pts
						(arc
							(start 0.3048 -0.2032)
							(mid 0.275042 -0.275042)
							(end 0.2032 -0.3048)
						)
						(arc
							(start -0.2032 -0.3048)
							(mid -0.275042 -0.275042)
							(end -0.3048 -0.2032)
						)
						(arc
							(start -0.3048 0.2032)
							(mid -0.275042 0.275042)
							(end -0.2032 0.3048)
						)
						(arc
							(start 0.2032 0.3048)
							(mid 0.275042 0.275042)
							(end 0.3048 0.2032)
						)
					)
					(width 0)
					(fill yes)
				)
			)
		)
	)
	(footprint ""
		(layer "F.Cu")
		(at 469.773 -35.56 -90)
		(property "Reference" "C489"
			(at 0 0 270)
			(layer "F.SilkS")
			(hide yes)
			(effects
				(font
					(size 1.27 1.27)
				)
			)
		)
		(property "Value" "SC4D7U25V5KX-1-GP"
			(at -0.0762 -6.1214 270)
			(unlocked yes)
			(layer "F.Fab")
			(hide yes)
			(effects
				(font
					(size 1.016 1.016)
					(thickness 0.1524)
				)
			)
		)
		(property "Device Type" "C805H58"
			(at -0.0762 -8.1534 270)
			(unlocked yes)
			(layer "F.Fab")
			(hide yes)
			(effects
				(font
					(size 1.016 1.016)
					(thickness 0.1524)
				)
			)
		)
		(duplicate_pad_numbers_are_jumpers no)
		(fp_line
			(start 0.635 0)
			(end -0.635 0)
			(stroke
				(width 0.508)
				(type default)
			)
			(layer "F.SilkS")
		)
		(fp_rect
			(start -0.9652 1.778)
			(end 0.9652 -1.778)
			(stroke
				(width 0)
				(type default)
			)
			(fill no)
			(layer "F.CrtYd")
		)
		(fp_poly
			(pts
				(xy -0.9652 -1.778) (xy 0.9652 -1.778) (xy 0.9652 1.778) (xy -0.9652 1.778)
			)
			(stroke
				(width 0)
				(type default)
			)
			(fill no)
			(layer "F.Fab")
		)
		(pad "1" smd rect
			(at 0 -0.9652 270)
			(size 1.397 1.143)
			(layers "F.Cu" "F.Mask" "F.Paste")
			(net "P12V_HDD35")
		)
		(pad "2" smd rect
			(at 0 0.9652 270)
			(size 1.397 1.143)
			(layers "F.Cu" "F.Mask" "F.Paste")
			(net "GND")
		)
	)
	(footprint ""
		(layer "F.Cu")
		(at 225.552 -303.6824 180)
		(property "Reference" "R505"
			(at 0 0 180)
			(layer "F.SilkS")
			(hide yes)
			(effects
				(font
					(size 1.27 1.27)
				)
			)
		)
		(property "Value" "10KR2F-2-GP"
			(at 0.064008 -3.993896 180)
			(unlocked yes)
			(layer "F.Fab")
			(hide yes)
			(effects
				(font
					(size 1.016 1.016)
					(thickness 0.1524)
				)
			)
		)
		(property "Device Type" "R402H16"
			(at 0.064008 -5.517896 180)
			(unlocked yes)
			(layer "F.Fab")
			(hide yes)
			(effects
				(font
					(size 1.016 1.016)
					(thickness 0.1524)
				)
			)
		)
		(duplicate_pad_numbers_are_jumpers no)
		(fp_line
			(start 0.508 -0.9398)
			(end -0.508 -0.9398)
			(stroke
				(width 0.1524)
				(type default)
			)
			(layer "F.SilkS")
		)
		(fp_line
			(start -0.508 -0.9398)
			(end -0.508 0.9398)
			(stroke
				(width 0.1524)
				(type default)
			)
			(layer "F.SilkS")
		)
		(fp_rect
			(start -0.508 0.9398)
			(end 0.508 -0.9398)
			(stroke
				(width 0)
				(type default)
			)
			(fill no)
			(layer "F.CrtYd")
		)
		(fp_rect
			(start -0.508 0.9398)
			(end 0.508 -0.9398)
			(stroke
				(width 0)
				(type default)
			)
			(fill no)
			(layer "F.Fab")
		)
		(pad "1" smd custom
			(at 0 -0.4445 180)
			(size 0.1397 0.1397)
			(layers "F.Cu" "F.Mask" "F.Paste")
			(net "P3V3_IN")
			(options
				(clearance outline)
				(anchor circle)
			)
			(primitives
				(gr_poly
					(pts
						(arc
							(start -0.1778 -0.2794)
							(mid -0.249642 -0.249642)
							(end -0.2794 -0.1778)
						)
						(arc
							(start -0.2794 0.1778)
							(mid -0.249642 0.249642)
							(end -0.1778 0.2794)
						)
						(arc
							(start 0.1778 0.2794)
							(mid 0.249642 0.249642)
							(end 0.2794 0.1778)
						)
						(arc
							(start 0.2794 -0.1778)
							(mid 0.249642 -0.249642)
							(end 0.1778 -0.2794)
						)
					)
					(width 0)
					(fill yes)
				)
			)
		)
		(pad "2" smd custom
			(at 0 0.4445 180)
			(size 0.1397 0.1397)
			(layers "F.Cu" "F.Mask" "F.Paste")
			(net "FANTACH_A_OE_N")
			(options
				(clearance outline)
				(anchor circle)
			)
			(primitives
				(gr_poly
					(pts
						(arc
							(start -0.1778 -0.2794)
							(mid -0.249642 -0.249642)
							(end -0.2794 -0.1778)
						)
						(arc
							(start -0.2794 0.1778)
							(mid -0.249642 0.249642)
							(end -0.1778 0.2794)
						)
						(arc
							(start 0.1778 0.2794)
							(mid 0.249642 0.249642)
							(end 0.2794 0.1778)
						)
						(arc
							(start 0.2794 -0.1778)
							(mid 0.249642 -0.249642)
							(end 0.1778 -0.2794)
						)
					)
					(width 0)
					(fill yes)
				)
			)
		)
	)
	(footprint ""
		(layer "F.Cu")
		(at 174.117 -99.314)
		(property "Reference" "R426"
			(at 0 0 0)
			(layer "F.SilkS")
			(hide yes)
			(effects
				(font
					(size 1.27 1.27)
				)
			)
		)
		(property "Value" "91R3F-1-GP"
			(at -0.0254 -2.5146 0)
			(unlocked yes)
			(layer "F.Fab")
			(hide yes)
			(effects
				(font
					(size 1.016 1.016)
					(thickness 0.1524)
				)
			)
		)
		(property "Device Type" "R603H22"
			(at -0.0254 -4.0386 0)
			(unlocked yes)
			(layer "F.Fab")
			(hide yes)
			(effects
				(font
					(size 1.016 1.016)
					(thickness 0.1524)
				)
			)
		)
		(duplicate_pad_numbers_are_jumpers no)
		(fp_line
			(start -0.4826 0)
			(end -0.2032 0)
			(stroke
				(width 0.2032)
				(type default)
			)
			(layer "F.SilkS")
		)
		(fp_line
			(start 0.2032 0)
			(end 0.4826 0)
			(stroke
				(width 0.2032)
				(type default)
			)
			(layer "F.SilkS")
		)
		(fp_rect
			(start -0.5842 1.3335)
			(end 0.5842 -1.3335)
			(stroke
				(width 0)
				(type default)
			)
			(fill no)
			(layer "F.CrtYd")
		)
		(fp_rect
			(start -0.5842 1.3335)
			(end 0.5842 -1.3335)
			(stroke
				(width 0)
				(type default)
			)
			(fill no)
			(layer "F.Fab")
		)
		(pad "1" smd custom
			(at 0 -0.762)
			(size 0.2159 0.2159)
			(layers "F.Cu" "F.Mask" "F.Paste")
			(net "P5V_B_2")
			(options
				(clearance outline)
				(anchor circle)
			)
			(primitives
				(gr_poly
					(pts
						(arc
							(start -0.3302 -0.4318)
							(mid -0.402042 -0.402042)
							(end -0.4318 -0.3302)
						)
						(arc
							(start -0.4318 0.3302)
							(mid -0.402042 0.402042)
							(end -0.3302 0.4318)
						)
						(arc
							(start 0.3302 0.4318)
							(mid 0.402042 0.402042)
							(end 0.4318 0.3302)
						)
						(arc
							(start 0.4318 -0.3302)
							(mid 0.402042 -0.402042)
							(end 0.3302 -0.4318)
						)
					)
					(width 0)
					(fill yes)
				)
			)
		)
		(pad "2" smd custom
			(at 0 0.762)
			(size 0.2159 0.2159)
			(layers "F.Cu" "F.Mask" "F.Paste")
			(net "DRV_ACT_17")
			(options
				(clearance outline)
				(anchor circle)
			)
			(primitives
				(gr_poly
					(pts
						(arc
							(start -0.3302 -0.4318)
							(mid -0.402042 -0.402042)
							(end -0.4318 -0.3302)
						)
						(arc
							(start -0.4318 0.3302)
							(mid -0.402042 0.402042)
							(end -0.3302 0.4318)
						)
						(arc
							(start 0.3302 0.4318)
							(mid 0.402042 0.402042)
							(end 0.4318 0.3302)
						)
						(arc
							(start 0.4318 -0.3302)
							(mid 0.402042 -0.402042)
							(end 0.3302 -0.4318)
						)
					)
					(width 0)
					(fill yes)
				)
			)
		)
	)
	(footprint ""
		(layer "F.Cu")
		(at 464.6168 -6.3754 -90)
		(property "Reference" "R140"
			(at 0 0 270)
			(layer "F.SilkS")
			(hide yes)
			(effects
				(font
					(size 1.27 1.27)
				)
			)
		)
		(property "Value" "4K7R2F-GP"
			(at 0.064008 -3.993896 270)
			(unlocked yes)
			(layer "F.Fab")
			(hide yes)
			(effects
				(font
					(size 1.016 1.016)
					(thickness 0.1524)
				)
			)
		)
		(property "Device Type" "R402H16"
			(at 0.064008 -5.517896 270)
			(unlocked yes)
			(layer "F.Fab")
			(hide yes)
			(effects
				(font
					(size 1.016 1.016)
					(thickness 0.1524)
				)
			)
		)
		(duplicate_pad_numbers_are_jumpers no)
		(fp_line
			(start -0.508 -0.9398)
			(end -0.508 0.9398)
			(stroke
				(width 0.1524)
				(type default)
			)
			(layer "F.SilkS")
		)
		(fp_line
			(start 0.508 -0.9398)
			(end -0.508 -0.9398)
			(stroke
				(width 0.1524)
				(type default)
			)
			(layer "F.SilkS")
		)
		(fp_rect
			(start -0.508 0.9398)
			(end 0.508 -0.9398)
			(stroke
				(width 0)
				(type default)
			)
			(fill no)
			(layer "F.CrtYd")
		)
		(fp_rect
			(start -0.508 0.9398)
			(end 0.508 -0.9398)
			(stroke
				(width 0)
				(type default)
			)
			(fill no)
			(layer "F.Fab")
		)
		(pad "1" smd custom
			(at 0 -0.4445 270)
			(size 0.1397 0.1397)
			(layers "F.Cu" "F.Mask" "F.Paste")
			(net "TEMP2_A1")
			(options
				(clearance outline)
				(anchor circle)
			)
			(primitives
				(gr_poly
					(pts
						(arc
							(start -0.1778 -0.2794)
							(mid -0.249642 -0.249642)
							(end -0.2794 -0.1778)
						)
						(arc
							(start -0.2794 0.1778)
							(mid -0.249642 0.249642)
							(end -0.1778 0.2794)
						)
						(arc
							(start 0.1778 0.2794)
							(mid 0.249642 0.249642)
							(end 0.2794 0.1778)
						)
						(arc
							(start 0.2794 -0.1778)
							(mid 0.249642 -0.249642)
							(end 0.1778 -0.2794)
						)
					)
					(width 0)
					(fill yes)
				)
			)
		)
		(pad "2" smd custom
			(at 0 0.4445 270)
			(size 0.1397 0.1397)
			(layers "F.Cu" "F.Mask" "F.Paste")
			(net "GND")
			(options
				(clearance outline)
				(anchor circle)
			)
			(primitives
				(gr_poly
					(pts
						(arc
							(start -0.1778 -0.2794)
							(mid -0.249642 -0.249642)
							(end -0.2794 -0.1778)
						)
						(arc
							(start -0.2794 0.1778)
							(mid -0.249642 0.249642)
							(end -0.1778 0.2794)
						)
						(arc
							(start 0.1778 0.2794)
							(mid 0.249642 0.249642)
							(end 0.2794 0.1778)
						)
						(arc
							(start 0.2794 -0.1778)
							(mid 0.249642 -0.249642)
							(end 0.1778 -0.2794)
						)
					)
					(width 0)
					(fill yes)
				)
			)
		)
	)
	(footprint ""
		(layer "F.Cu")
		(at 43.999912 -13.999972)
		(property "Reference" ""
			(at 0 0 0)
			(layer "F.SilkS")
			(hide yes)
			(effects
				(font
					(size 1.27 1.27)
				)
			)
		)
		(property "Value" "*"
			(at -6.3373 -0.4572 0)
			(unlocked yes)
			(layer "F.Fab")
			(hide yes)
			(effects
				(font
					(size 1.016 1.016)
					(thickness 0.1524)
				)
			)
		)
		(duplicate_pad_numbers_are_jumpers no)
		(fp_poly
			(pts
				(arc
					(start 5.0673 0)
					(mid -5.0673 0)
					(end 5.0673 0)
				)
			)
			(stroke
				(width 0)
				(type default)
			)
			(fill no)
			(layer "B.CrtYd")
		)
		(fp_poly
			(pts
				(arc
					(start 5.0673 0)
					(mid -5.0673 0)
					(end 5.0673 0)
				)
			)
			(stroke
				(width 0)
				(type default)
			)
			(fill no)
			(layer "F.CrtYd")
		)
		(fp_poly
			(pts
				(arc
					(start 5.0673 0)
					(mid -5.0673 0)
					(end 5.0673 0)
				)
			)
			(stroke
				(width 0)
				(type default)
			)
			(fill no)
			(layer "B.Fab")
		)
		(fp_poly
			(pts
				(arc
					(start 5.0673 0)
					(mid -5.0673 0)
					(end 5.0673 0)
				)
			)
			(stroke
				(width 0)
				(type default)
			)
			(fill no)
			(layer "F.Fab")
		)
		(pad "1" thru_hole circle
			(at 0 0)
			(size 9.525 9.525)
			(drill 3.556)
			(layers "*.Cu" "*.Mask")
			(remove_unused_layers no)
			(net "Net_37")
			(clearance -2.4765)
			(thermal_gap 0.3048)
			(padstack
				(mode front_inner_back)
				(layer "Inner"
					(shape circle)
					(size 3.9624 3.9624)
					(clearance 0.3048)
				)
				(layer "B.Cu"
					(shape circle)
					(size 9.525 9.525)
					(clearance -2.4765)
				)
			)
		)
		(zone
			(layers "F.Cu" "B.Cu" "In1.Cu" "In2.Cu" "In3.Cu" "In4.Cu" "In5.Cu" "In6.Cu")
			(hatch none 0.5)
			(connect_pads
				(clearance 0)
			)
			(min_thickness 0.25)
			(keepout
				(tracks not_allowed)
				(vias allowed)
				(pads allowed)
				(copperpour not_allowed)
				(footprints allowed)
			)
			(placement
				(enabled no)
				(sheetname "")
			)
			(fill
				(thermal_gap 0.5)
				(thermal_bridge_width 0.5)
				(island_removal_mode 0)
			)
			(polygon
				(pts
					(arc
						(start 48.762412 -13.999972)
						(mid 39.237412 -13.999972)
						(end 48.762412 -13.999972)
					)
				)
			)
		)
	)
	(footprint ""
		(layer "F.Cu")
		(at 190.0936 -35.5854 180)
		(property "Reference" "R741"
			(at 0 0 180)
			(layer "F.SilkS")
			(hide yes)
			(effects
				(font
					(size 1.27 1.27)
				)
			)
		)
		(property "Value" "220R3F-1-GP"
			(at -0.0254 -2.5146 180)
			(unlocked yes)
			(layer "F.Fab")
			(hide yes)
			(effects
				(font
					(size 1.016 1.016)
					(thickness 0.1524)
				)
			)
		)
		(property "Device Type" "R603H22"
			(at -0.0254 -4.0386 180)
			(unlocked yes)
			(layer "F.Fab")
			(hide yes)
			(effects
				(font
					(size 1.016 1.016)
					(thickness 0.1524)
				)
			)
		)
		(duplicate_pad_numbers_are_jumpers no)
		(fp_line
			(start 0.2032 0)
			(end 0.4826 0)
			(stroke
				(width 0.2032)
				(type default)
			)
			(layer "F.SilkS")
		)
		(fp_line
			(start -0.4826 0)
			(end -0.2032 0)
			(stroke
				(width 0.2032)
				(type default)
			)
			(layer "F.SilkS")
		)
		(fp_rect
			(start -0.5842 1.3335)
			(end 0.5842 -1.3335)
			(stroke
				(width 0)
				(type default)
			)
			(fill no)
			(layer "F.CrtYd")
		)
		(fp_rect
			(start -0.5842 1.3335)
			(end 0.5842 -1.3335)
			(stroke
				(width 0)
				(type default)
			)
			(fill no)
			(layer "F.Fab")
		)
		(pad "1" smd custom
			(at 0 -0.762 180)
			(size 0.2159 0.2159)
			(layers "F.Cu" "F.Mask" "F.Paste")
			(net "HDD_PRSNT_29")
			(options
				(clearance outline)
				(anchor circle)
			)
			(primitives
				(gr_poly
					(pts
						(arc
							(start -0.3302 -0.4318)
							(mid -0.402042 -0.402042)
							(end -0.4318 -0.3302)
						)
						(arc
							(start -0.4318 0.3302)
							(mid -0.402042 0.402042)
							(end -0.3302 0.4318)
						)
						(arc
							(start 0.3302 0.4318)
							(mid 0.402042 0.402042)
							(end 0.4318 0.3302)
						)
						(arc
							(start 0.4318 -0.3302)
							(mid 0.402042 -0.402042)
							(end 0.3302 -0.4318)
						)
					)
					(width 0)
					(fill yes)
				)
			)
		)
		(pad "2" smd custom
			(at 0 0.762 180)
			(size 0.2159 0.2159)
			(layers "F.Cu" "F.Mask" "F.Paste")
			(net "DRIVE_B_29_INS")
			(options
				(clearance outline)
				(anchor circle)
			)
			(primitives
				(gr_poly
					(pts
						(arc
							(start -0.3302 -0.4318)
							(mid -0.402042 -0.402042)
							(end -0.4318 -0.3302)
						)
						(arc
							(start -0.4318 0.3302)
							(mid -0.402042 0.402042)
							(end -0.3302 0.4318)
						)
						(arc
							(start 0.3302 0.4318)
							(mid 0.402042 0.402042)
							(end 0.4318 0.3302)
						)
						(arc
							(start 0.4318 -0.3302)
							(mid 0.402042 -0.402042)
							(end 0.3302 -0.4318)
						)
					)
					(width 0)
					(fill yes)
				)
			)
		)
	)
	(footprint ""
		(layer "F.Cu")
		(at 477.647 -11.176)
		(property "Reference" "R883"
			(at 0 0 0)
			(layer "F.SilkS")
			(hide yes)
			(effects
				(font
					(size 1.27 1.27)
				)
			)
		)
		(property "Value" "1KR2F-3-GP"
			(at 0.064008 -3.993896 0)
			(unlocked yes)
			(layer "F.Fab")
			(hide yes)
			(effects
				(font
					(size 1.016 1.016)
					(thickness 0.1524)
				)
			)
		)
		(property "Device Type" "R402H16"
			(at 0.064008 -5.517896 0)
			(unlocked yes)
			(layer "F.Fab")
			(hide yes)
			(effects
				(font
					(size 1.016 1.016)
					(thickness 0.1524)
				)
			)
		)
		(duplicate_pad_numbers_are_jumpers no)
		(fp_line
			(start -0.508 -0.9398)
			(end -0.508 0.9398)
			(stroke
				(width 0.1524)
				(type default)
			)
			(layer "F.SilkS")
		)
		(fp_line
			(start 0.508 -0.9398)
			(end -0.508 -0.9398)
			(stroke
				(width 0.1524)
				(type default)
			)
			(layer "F.SilkS")
		)
		(fp_rect
			(start -0.508 0.9398)
			(end 0.508 -0.9398)
			(stroke
				(width 0)
				(type default)
			)
			(fill no)
			(layer "F.CrtYd")
		)
		(fp_rect
			(start -0.508 0.9398)
			(end 0.508 -0.9398)
			(stroke
				(width 0)
				(type default)
			)
			(fill no)
			(layer "F.Fab")
		)
		(pad "1" smd custom
			(at 0 -0.4445)
			(size 0.1397 0.1397)
			(layers "F.Cu" "F.Mask" "F.Paste")
			(net "P3V3_STBY_B")
			(options
				(clearance outline)
				(anchor circle)
			)
			(primitives
				(gr_poly
					(pts
						(arc
							(start -0.1778 -0.2794)
							(mid -0.249642 -0.249642)
							(end -0.2794 -0.1778)
						)
						(arc
							(start -0.2794 0.1778)
							(mid -0.249642 0.249642)
							(end -0.1778 0.2794)
						)
						(arc
							(start 0.1778 0.2794)
							(mid 0.249642 0.249642)
							(end 0.2794 0.1778)
						)
						(arc
							(start 0.2794 -0.1778)
							(mid 0.249642 -0.249642)
							(end 0.1778 -0.2794)
						)
					)
					(width 0)
					(fill yes)
				)
			)
		)
		(pad "2" smd custom
			(at 0 0.4445)
			(size 0.1397 0.1397)
			(layers "F.Cu" "F.Mask" "F.Paste")
			(net "SW_PWR_R_HDD35")
			(options
				(clearance outline)
				(anchor circle)
			)
			(primitives
				(gr_poly
					(pts
						(arc
							(start -0.1778 -0.2794)
							(mid -0.249642 -0.249642)
							(end -0.2794 -0.1778)
						)
						(arc
							(start -0.2794 0.1778)
							(mid -0.249642 0.249642)
							(end -0.1778 0.2794)
						)
						(arc
							(start 0.1778 0.2794)
							(mid 0.249642 0.249642)
							(end 0.2794 0.1778)
						)
						(arc
							(start 0.2794 -0.1778)
							(mid 0.249642 -0.249642)
							(end 0.1778 -0.2794)
						)
					)
					(width 0)
					(fill yes)
				)
			)
		)
	)
	(footprint ""
		(layer "F.Cu")
		(at 25.974802 -232.16235)
		(property "Reference" "R1097"
			(at 0 0 0)
			(layer "F.SilkS")
			(hide yes)
			(effects
				(font
					(size 1.27 1.27)
				)
			)
		)
		(property "Value" "49K9R2F-L-GP"
			(at 0.064008 -3.993896 0)
			(unlocked yes)
			(layer "F.Fab")
			(hide yes)
			(effects
				(font
					(size 1.016 1.016)
					(thickness 0.1524)
				)
			)
		)
		(property "Device Type" "R402H16"
			(at 0.064008 -5.517896 0)
			(unlocked yes)
			(layer "F.Fab")
			(hide yes)
			(effects
				(font
					(size 1.016 1.016)
					(thickness 0.1524)
				)
			)
		)
		(duplicate_pad_numbers_are_jumpers no)
		(fp_line
			(start -0.508 -0.9398)
			(end -0.508 0.9398)
			(stroke
				(width 0.1524)
				(type default)
			)
			(layer "F.SilkS")
		)
		(fp_line
			(start 0.508 -0.9398)
			(end -0.508 -0.9398)
			(stroke
				(width 0.1524)
				(type default)
			)
			(layer "F.SilkS")
		)
		(fp_rect
			(start -0.508 0.9398)
			(end 0.508 -0.9398)
			(stroke
				(width 0)
				(type default)
			)
			(fill no)
			(layer "F.CrtYd")
		)
		(fp_rect
			(start -0.508 0.9398)
			(end 0.508 -0.9398)
			(stroke
				(width 0)
				(type default)
			)
			(fill no)
			(layer "F.Fab")
		)
		(pad "1" smd custom
			(at 0 -0.4445)
			(size 0.1397 0.1397)
			(layers "F.Cu" "F.Mask" "F.Paste")
			(net "P12V_B")
			(options
				(clearance outline)
				(anchor circle)
			)
			(primitives
				(gr_poly
					(pts
						(arc
							(start -0.1778 -0.2794)
							(mid -0.249642 -0.249642)
							(end -0.2794 -0.1778)
						)
						(arc
							(start -0.2794 0.1778)
							(mid -0.249642 0.249642)
							(end -0.1778 0.2794)
						)
						(arc
							(start 0.1778 0.2794)
							(mid 0.249642 0.249642)
							(end 0.2794 0.1778)
						)
						(arc
							(start 0.2794 -0.1778)
							(mid 0.249642 -0.249642)
							(end 0.1778 -0.2794)
						)
					)
					(width 0)
					(fill yes)
				)
			)
		)
		(pad "2" smd custom
			(at 0 0.4445)
			(size 0.1397 0.1397)
			(layers "F.Cu" "F.Mask" "F.Paste")
			(net "P5V_B_1_EN_R")
			(options
				(clearance outline)
				(anchor circle)
			)
			(primitives
				(gr_poly
					(pts
						(arc
							(start -0.1778 -0.2794)
							(mid -0.249642 -0.249642)
							(end -0.2794 -0.1778)
						)
						(arc
							(start -0.2794 0.1778)
							(mid -0.249642 0.249642)
							(end -0.1778 0.2794)
						)
						(arc
							(start 0.1778 0.2794)
							(mid 0.249642 0.249642)
							(end 0.2794 0.1778)
						)
						(arc
							(start 0.2794 -0.1778)
							(mid 0.249642 -0.249642)
							(end 0.1778 -0.2794)
						)
					)
					(width 0)
					(fill yes)
				)
			)
		)
	)
	(footprint ""
		(layer "F.Cu")
		(at 143.129 -247.65 180)
		(property "Reference" "D4"
			(at 0 0 180)
			(layer "F.SilkS")
			(hide yes)
			(effects
				(font
					(size 1.27 1.27)
				)
			)
		)
		(property "Value" "RB551V30-GP"
			(at 0 -6.7818 180)
			(unlocked yes)
			(layer "F.Fab")
			(hide yes)
			(effects
				(font
					(size 1.016 1.016)
					(thickness 0.1524)
				)
			)
		)
		(property "Device Type" "SOD323AKH38"
			(at 0 -8.6868 180)
			(unlocked yes)
			(layer "F.Fab")
			(hide yes)
			(effects
				(font
					(size 1.016 1.016)
					(thickness 0.1524)
				)
			)
		)
		(duplicate_pad_numbers_are_jumpers no)
		(fp_line
			(start 0.889 2.159)
			(end -0.889 2.159)
			(stroke
				(width 0.1524)
				(type default)
			)
			(layer "F.SilkS")
		)
		(fp_line
			(start 0.889 -1.9304)
			(end 0.889 2.159)
			(stroke
				(width 0.1524)
				(type default)
			)
			(layer "F.SilkS")
		)
		(fp_line
			(start 0.762 2.0574)
			(end -0.762 2.0574)
			(stroke
				(width 0.508)
				(type default)
			)
			(layer "F.SilkS")
		)
		(fp_line
			(start -0.889 2.159)
			(end -0.889 -1.9304)
			(stroke
				(width 0.1524)
				(type default)
			)
			(layer "F.SilkS")
		)
		(fp_line
			(start -0.889 -1.9304)
			(end 0.889 -1.9304)
			(stroke
				(width 0.1524)
				(type default)
			)
			(layer "F.SilkS")
		)
		(fp_rect
			(start -1.016 2.3114)
			(end 1.016 -2.0066)
			(stroke
				(width 0)
				(type default)
			)
			(fill no)
			(layer "F.CrtYd")
		)
		(fp_poly
			(pts
				(xy -1.016 -2.0066) (xy 1.016 -2.0066) (xy 1.016 2.3114) (xy -1.016 2.3114)
			)
			(stroke
				(width 0)
				(type default)
			)
			(fill no)
			(layer "F.Fab")
		)
		(pad "A" smd rect
			(at 0 -1.143 180)
			(size 0.5588 1.016)
			(layers "F.Cu" "F.Mask" "F.Paste")
			(net "SW_HDD_R4")
		)
		(pad "K" smd rect
			(at 0 1.143 180)
			(size 0.5588 1.016)
			(layers "F.Cu" "F.Mask" "F.Paste")
			(net "SW_HDD_N4")
		)
	)
	(footprint ""
		(layer "F.Cu")
		(at 317.119 -98.171)
		(property "Reference" "R433"
			(at 0 0 0)
			(layer "F.SilkS")
			(hide yes)
			(effects
				(font
					(size 1.27 1.27)
				)
			)
		)
		(property "Value" "91R3F-1-GP"
			(at -0.0254 -2.5146 0)
			(unlocked yes)
			(layer "F.Fab")
			(hide yes)
			(effects
				(font
					(size 1.016 1.016)
					(thickness 0.1524)
				)
			)
		)
		(property "Device Type" "R603H22"
			(at -0.0254 -4.0386 0)
			(unlocked yes)
			(layer "F.Fab")
			(hide yes)
			(effects
				(font
					(size 1.016 1.016)
					(thickness 0.1524)
				)
			)
		)
		(duplicate_pad_numbers_are_jumpers no)
		(fp_line
			(start -0.4826 0)
			(end -0.2032 0)
			(stroke
				(width 0.2032)
				(type default)
			)
			(layer "F.SilkS")
		)
		(fp_line
			(start 0.2032 0)
			(end 0.4826 0)
			(stroke
				(width 0.2032)
				(type default)
			)
			(layer "F.SilkS")
		)
		(fp_rect
			(start -0.5842 1.3335)
			(end 0.5842 -1.3335)
			(stroke
				(width 0)
				(type default)
			)
			(fill no)
			(layer "F.CrtYd")
		)
		(fp_rect
			(start -0.5842 1.3335)
			(end 0.5842 -1.3335)
			(stroke
				(width 0)
				(type default)
			)
			(fill no)
			(layer "F.Fab")
		)
		(pad "1" smd custom
			(at 0 -0.762)
			(size 0.2159 0.2159)
			(layers "F.Cu" "F.Mask" "F.Paste")
			(net "P5V_B_3")
			(options
				(clearance outline)
				(anchor circle)
			)
			(primitives
				(gr_poly
					(pts
						(arc
							(start -0.3302 -0.4318)
							(mid -0.402042 -0.402042)
							(end -0.4318 -0.3302)
						)
						(arc
							(start -0.4318 0.3302)
							(mid -0.402042 0.402042)
							(end -0.3302 0.4318)
						)
						(arc
							(start 0.3302 0.4318)
							(mid 0.402042 0.402042)
							(end 0.4318 0.3302)
						)
						(arc
							(start 0.4318 -0.3302)
							(mid 0.402042 -0.402042)
							(end 0.3302 -0.4318)
						)
					)
					(width 0)
					(fill yes)
				)
			)
		)
		(pad "2" smd custom
			(at 0 0.762)
			(size 0.2159 0.2159)
			(layers "F.Cu" "F.Mask" "F.Paste")
			(net "DRV_ACT_18")
			(options
				(clearance outline)
				(anchor circle)
			)
			(primitives
				(gr_poly
					(pts
						(arc
							(start -0.3302 -0.4318)
							(mid -0.402042 -0.402042)
							(end -0.4318 -0.3302)
						)
						(arc
							(start -0.4318 0.3302)
							(mid -0.402042 0.402042)
							(end -0.3302 0.4318)
						)
						(arc
							(start 0.3302 0.4318)
							(mid 0.402042 0.402042)
							(end 0.4318 0.3302)
						)
						(arc
							(start 0.4318 -0.3302)
							(mid 0.402042 -0.402042)
							(end 0.3302 -0.4318)
						)
					)
					(width 0)
					(fill yes)
				)
			)
		)
	)
	(footprint ""
		(layer "F.Cu")
		(at 256.484374 -228.36505 90)
		(property "Reference" "R165"
			(at 0 0 90)
			(layer "F.SilkS")
			(hide yes)
			(effects
				(font
					(size 1.27 1.27)
				)
			)
		)
		(property "Value" "10KR2F-2-GP"
			(at 0.064008 -3.993896 90)
			(unlocked yes)
			(layer "F.Fab")
			(hide yes)
			(effects
				(font
					(size 1.016 1.016)
					(thickness 0.1524)
				)
			)
		)
		(property "Device Type" "R402H16"
			(at 0.064008 -5.517896 90)
			(unlocked yes)
			(layer "F.Fab")
			(hide yes)
			(effects
				(font
					(size 1.016 1.016)
					(thickness 0.1524)
				)
			)
		)
		(duplicate_pad_numbers_are_jumpers no)
		(fp_line
			(start 0.508 -0.9398)
			(end -0.508 -0.9398)
			(stroke
				(width 0.1524)
				(type default)
			)
			(layer "F.SilkS")
		)
		(fp_line
			(start -0.508 -0.9398)
			(end -0.508 0.9398)
			(stroke
				(width 0.1524)
				(type default)
			)
			(layer "F.SilkS")
		)
		(fp_rect
			(start -0.508 0.9398)
			(end 0.508 -0.9398)
			(stroke
				(width 0)
				(type default)
			)
			(fill no)
			(layer "F.CrtYd")
		)
		(fp_rect
			(start -0.508 0.9398)
			(end 0.508 -0.9398)
			(stroke
				(width 0)
				(type default)
			)
			(fill no)
			(layer "F.Fab")
		)
		(pad "1" smd custom
			(at 0 -0.4445 90)
			(size 0.1397 0.1397)
			(layers "F.Cu" "F.Mask" "F.Paste")
			(net "P5V_B_2_SENSE")
			(options
				(clearance outline)
				(anchor circle)
			)
			(primitives
				(gr_poly
					(pts
						(arc
							(start -0.1778 -0.2794)
							(mid -0.249642 -0.249642)
							(end -0.2794 -0.1778)
						)
						(arc
							(start -0.2794 0.1778)
							(mid -0.249642 0.249642)
							(end -0.1778 0.2794)
						)
						(arc
							(start 0.1778 0.2794)
							(mid 0.249642 0.249642)
							(end 0.2794 0.1778)
						)
						(arc
							(start 0.2794 -0.1778)
							(mid 0.249642 -0.249642)
							(end 0.1778 -0.2794)
						)
					)
					(width 0)
					(fill yes)
				)
			)
		)
		(pad "2" smd custom
			(at 0 0.4445 90)
			(size 0.1397 0.1397)
			(layers "F.Cu" "F.Mask" "F.Paste")
			(net "GND")
			(options
				(clearance outline)
				(anchor circle)
			)
			(primitives
				(gr_poly
					(pts
						(arc
							(start -0.1778 -0.2794)
							(mid -0.249642 -0.249642)
							(end -0.2794 -0.1778)
						)
						(arc
							(start -0.2794 0.1778)
							(mid -0.249642 0.249642)
							(end -0.1778 0.2794)
						)
						(arc
							(start 0.1778 0.2794)
							(mid 0.249642 0.249642)
							(end 0.2794 0.1778)
						)
						(arc
							(start 0.2794 -0.1778)
							(mid 0.249642 -0.249642)
							(end 0.1778 -0.2794)
						)
					)
					(width 0)
					(fill yes)
				)
			)
		)
	)
	(footprint ""
		(layer "F.Cu")
		(at 336.7151 -357.7336 90)
		(property "Reference" "R148"
			(at 0 0 90)
			(layer "F.SilkS")
			(hide yes)
			(effects
				(font
					(size 1.27 1.27)
				)
			)
		)
		(property "Value" "300KR2F-GP"
			(at 0.064008 -3.993896 90)
			(unlocked yes)
			(layer "F.Fab")
			(hide yes)
			(effects
				(font
					(size 1.016 1.016)
					(thickness 0.1524)
				)
			)
		)
		(property "Device Type" "R402H16"
			(at 0.064008 -5.517896 90)
			(unlocked yes)
			(layer "F.Fab")
			(hide yes)
			(effects
				(font
					(size 1.016 1.016)
					(thickness 0.1524)
				)
			)
		)
		(duplicate_pad_numbers_are_jumpers no)
		(fp_line
			(start 0.508 -0.9398)
			(end -0.508 -0.9398)
			(stroke
				(width 0.1524)
				(type default)
			)
			(layer "F.SilkS")
		)
		(fp_line
			(start -0.508 -0.9398)
			(end -0.508 0.9398)
			(stroke
				(width 0.1524)
				(type default)
			)
			(layer "F.SilkS")
		)
		(fp_rect
			(start -0.508 0.9398)
			(end 0.508 -0.9398)
			(stroke
				(width 0)
				(type default)
			)
			(fill no)
			(layer "F.CrtYd")
		)
		(fp_rect
			(start -0.508 0.9398)
			(end 0.508 -0.9398)
			(stroke
				(width 0)
				(type default)
			)
			(fill no)
			(layer "F.Fab")
		)
		(pad "1" smd custom
			(at 0 -0.4445 90)
			(size 0.1397 0.1397)
			(layers "F.Cu" "F.Mask" "F.Paste")
			(net "GATE_FAN2_R")
			(options
				(clearance outline)
				(anchor circle)
			)
			(primitives
				(gr_poly
					(pts
						(arc
							(start -0.1778 -0.2794)
							(mid -0.249642 -0.249642)
							(end -0.2794 -0.1778)
						)
						(arc
							(start -0.2794 0.1778)
							(mid -0.249642 0.249642)
							(end -0.1778 0.2794)
						)
						(arc
							(start 0.1778 0.2794)
							(mid 0.249642 0.249642)
							(end 0.2794 0.1778)
						)
						(arc
							(start 0.2794 -0.1778)
							(mid 0.249642 -0.249642)
							(end 0.1778 -0.2794)
						)
					)
					(width 0)
					(fill yes)
				)
			)
		)
		(pad "2" smd custom
			(at 0 0.4445 90)
			(size 0.1397 0.1397)
			(layers "F.Cu" "F.Mask" "F.Paste")
			(net "P12V_IN")
			(options
				(clearance outline)
				(anchor circle)
			)
			(primitives
				(gr_poly
					(pts
						(arc
							(start -0.1778 -0.2794)
							(mid -0.249642 -0.249642)
							(end -0.2794 -0.1778)
						)
						(arc
							(start -0.2794 0.1778)
							(mid -0.249642 0.249642)
							(end -0.1778 0.2794)
						)
						(arc
							(start 0.1778 0.2794)
							(mid 0.249642 0.249642)
							(end 0.2794 0.1778)
						)
						(arc
							(start 0.2794 -0.1778)
							(mid 0.249642 -0.249642)
							(end 0.1778 -0.2794)
						)
					)
					(width 0)
					(fill yes)
				)
			)
		)
	)
	(footprint ""
		(layer "F.Cu")
		(at 118.872 -275.463 180)
		(property "Reference" "C76"
			(at 0 0 180)
			(layer "F.SilkS")
			(hide yes)
			(effects
				(font
					(size 1.27 1.27)
				)
			)
		)
		(property "Value" "SC1U25V3KX-GP"
			(at 0 -2.8194 180)
			(unlocked yes)
			(layer "F.Fab")
			(hide yes)
			(effects
				(font
					(size 1.016 1.016)
					(thickness 0.1524)
				)
			)
		)
		(property "Device Type" "C603H36"
			(at 0 -4.3434 180)
			(unlocked yes)
			(layer "F.Fab")
			(hide yes)
			(effects
				(font
					(size 1.016 1.016)
					(thickness 0.1524)
				)
			)
		)
		(duplicate_pad_numbers_are_jumpers no)
		(fp_line
			(start 0.508 0)
			(end -0.508 0)
			(stroke
				(width 0.2032)
				(type default)
			)
			(layer "F.SilkS")
		)
		(fp_rect
			(start -0.5842 1.3335)
			(end 0.5842 -1.3335)
			(stroke
				(width 0)
				(type default)
			)
			(fill no)
			(layer "F.CrtYd")
		)
		(fp_rect
			(start -0.5842 1.3335)
			(end 0.5842 -1.3335)
			(stroke
				(width 0)
				(type default)
			)
			(fill no)
			(layer "F.Fab")
		)
		(pad "1" smd custom
			(at 0 -0.762 180)
			(size 0.2159 0.2159)
			(layers "F.Cu" "F.Mask" "F.Paste")
			(net "P12V_HDD3")
			(options
				(clearance outline)
				(anchor circle)
			)
			(primitives
				(gr_poly
					(pts
						(arc
							(start -0.3302 -0.4318)
							(mid -0.402042 -0.402042)
							(end -0.4318 -0.3302)
						)
						(arc
							(start -0.4318 0.3302)
							(mid -0.402042 0.402042)
							(end -0.3302 0.4318)
						)
						(arc
							(start 0.3302 0.4318)
							(mid 0.402042 0.402042)
							(end 0.4318 0.3302)
						)
						(arc
							(start 0.4318 -0.3302)
							(mid 0.402042 -0.402042)
							(end 0.3302 -0.4318)
						)
					)
					(width 0)
					(fill yes)
				)
			)
		)
		(pad "2" smd custom
			(at 0 0.762 180)
			(size 0.2159 0.2159)
			(layers "F.Cu" "F.Mask" "F.Paste")
			(net "GND")
			(options
				(clearance outline)
				(anchor circle)
			)
			(primitives
				(gr_poly
					(pts
						(arc
							(start -0.3302 -0.4318)
							(mid -0.402042 -0.402042)
							(end -0.4318 -0.3302)
						)
						(arc
							(start -0.4318 0.3302)
							(mid -0.402042 0.402042)
							(end -0.3302 0.4318)
						)
						(arc
							(start 0.3302 0.4318)
							(mid 0.402042 0.402042)
							(end 0.4318 0.3302)
						)
						(arc
							(start 0.4318 -0.3302)
							(mid 0.402042 -0.402042)
							(end 0.3302 -0.4318)
						)
					)
					(width 0)
					(fill yes)
				)
			)
		)
	)
	(footprint ""
		(layer "F.Cu")
		(at 381.3302 -32.8676 180)
		(property "Reference" "R810"
			(at 0 0 180)
			(layer "F.SilkS")
			(hide yes)
			(effects
				(font
					(size 1.27 1.27)
				)
			)
		)
		(property "Value" "220R3F-1-GP"
			(at -0.0254 -2.5146 180)
			(unlocked yes)
			(layer "F.Fab")
			(hide yes)
			(effects
				(font
					(size 1.016 1.016)
					(thickness 0.1524)
				)
			)
		)
		(property "Device Type" "R603H22"
			(at -0.0254 -4.0386 180)
			(unlocked yes)
			(layer "F.Fab")
			(hide yes)
			(effects
				(font
					(size 1.016 1.016)
					(thickness 0.1524)
				)
			)
		)
		(duplicate_pad_numbers_are_jumpers no)
		(fp_line
			(start 0.2032 0)
			(end 0.4826 0)
			(stroke
				(width 0.2032)
				(type default)
			)
			(layer "F.SilkS")
		)
		(fp_line
			(start -0.4826 0)
			(end -0.2032 0)
			(stroke
				(width 0.2032)
				(type default)
			)
			(layer "F.SilkS")
		)
		(fp_rect
			(start -0.5842 1.3335)
			(end 0.5842 -1.3335)
			(stroke
				(width 0)
				(type default)
			)
			(fill no)
			(layer "F.CrtYd")
		)
		(fp_rect
			(start -0.5842 1.3335)
			(end 0.5842 -1.3335)
			(stroke
				(width 0)
				(type default)
			)
			(fill no)
			(layer "F.Fab")
		)
		(pad "1" smd custom
			(at 0 -0.762 180)
			(size 0.2159 0.2159)
			(layers "F.Cu" "F.Mask" "F.Paste")
			(net "HDD_PRSNT_32")
			(options
				(clearance outline)
				(anchor circle)
			)
			(primitives
				(gr_poly
					(pts
						(arc
							(start -0.3302 -0.4318)
							(mid -0.402042 -0.402042)
							(end -0.4318 -0.3302)
						)
						(arc
							(start -0.4318 0.3302)
							(mid -0.402042 0.402042)
							(end -0.3302 0.4318)
						)
						(arc
							(start 0.3302 0.4318)
							(mid 0.402042 0.402042)
							(end 0.4318 0.3302)
						)
						(arc
							(start 0.4318 -0.3302)
							(mid 0.402042 -0.402042)
							(end 0.3302 -0.4318)
						)
					)
					(width 0)
					(fill yes)
				)
			)
		)
		(pad "2" smd custom
			(at 0 0.762 180)
			(size 0.2159 0.2159)
			(layers "F.Cu" "F.Mask" "F.Paste")
			(net "DRIVE_B_32_INS")
			(options
				(clearance outline)
				(anchor circle)
			)
			(primitives
				(gr_poly
					(pts
						(arc
							(start -0.3302 -0.4318)
							(mid -0.402042 -0.402042)
							(end -0.4318 -0.3302)
						)
						(arc
							(start -0.4318 0.3302)
							(mid -0.402042 0.402042)
							(end -0.3302 0.4318)
						)
						(arc
							(start 0.3302 0.4318)
							(mid 0.402042 0.402042)
							(end 0.4318 0.3302)
						)
						(arc
							(start 0.4318 -0.3302)
							(mid 0.402042 -0.402042)
							(end 0.3302 -0.4318)
						)
					)
					(width 0)
					(fill yes)
				)
			)
		)
	)
	(footprint ""
		(layer "F.Cu")
		(at 320.312796 -375.0056 -90)
		(property "Reference" "Q217"
			(at 0 0 270)
			(layer "F.SilkS")
			(hide yes)
			(effects
				(font
					(size 1.27 1.27)
				)
			)
		)
		(property "Value" "2N7002KDW-GP"
			(at -2.3622 -8.2042 270)
			(unlocked yes)
			(layer "F.Fab")
			(hide yes)
			(effects
				(font
					(size 1.016 1.016)
					(thickness 0.1524)
				)
			)
		)
		(property "Device Type" "SOT-363H44"
			(at -2.3622 -10.1092 270)
			(unlocked yes)
			(layer "F.Fab")
			(hide yes)
			(effects
				(font
					(size 1.016 1.016)
					(thickness 0.1524)
				)
			)
		)
		(duplicate_pad_numbers_are_jumpers no)
		(fp_line
			(start -1.4478 1.7018)
			(end 1.4478 1.7018)
			(stroke
				(width 0.1524)
				(type default)
			)
			(layer "F.SilkS")
		)
		(fp_line
			(start 1.4478 1.7018)
			(end 1.4478 -1.7018)
			(stroke
				(width 0.1524)
				(type default)
			)
			(layer "F.SilkS")
		)
		(fp_line
			(start -1.27 1.524)
			(end -1.27 0.6604)
			(stroke
				(width 0.4826)
				(type default)
			)
			(layer "F.SilkS")
		)
		(fp_line
			(start -1.4478 -1.7018)
			(end -1.4478 1.7018)
			(stroke
				(width 0.1524)
				(type default)
			)
			(layer "F.SilkS")
		)
		(fp_line
			(start 1.4478 -1.7018)
			(end -1.4478 -1.7018)
			(stroke
				(width 0.1524)
				(type default)
			)
			(layer "F.SilkS")
		)
		(fp_poly
			(pts
				(xy -1.524 -1.778) (xy 1.524 -1.778) (xy 1.524 1.778) (xy -1.524 1.778)
			)
			(stroke
				(width 0)
				(type default)
			)
			(fill no)
			(layer "F.CrtYd")
		)
		(fp_poly
			(pts
				(xy -1.524 -1.778) (xy 1.524 -1.778) (xy 1.524 1.778) (xy -1.524 1.778)
			)
			(stroke
				(width 0)
				(type default)
			)
			(fill no)
			(layer "F.Fab")
		)
		(pad "1" smd rect
			(at -0.65024 0.9398 270)
			(size 0.4064 1.016)
			(layers "F.Cu" "F.Mask" "F.Paste")
			(net "GND")
		)
		(pad "2" smd rect
			(at 0 0.9398 270)
			(size 0.4064 1.016)
			(layers "F.Cu" "F.Mask" "F.Paste")
			(net "FAN_LED2_D")
		)
		(pad "3" smd rect
			(at 0.65024 0.9398 270)
			(size 0.4064 1.016)
			(layers "F.Cu" "F.Mask" "F.Paste")
			(net "FAN_LED2_D")
		)
		(pad "4" smd rect
			(at 0.65024 -0.9398 270)
			(size 0.4064 1.016)
			(layers "F.Cu" "F.Mask" "F.Paste")
			(net "GND")
		)
		(pad "5" smd rect
			(at 0 -0.9398 270)
			(size 0.4064 1.016)
			(layers "F.Cu" "F.Mask" "F.Paste")
			(net "FAN_LED2")
		)
		(pad "6" smd rect
			(at -0.65024 -0.9398 270)
			(size 0.4064 1.016)
			(layers "F.Cu" "F.Mask" "F.Paste")
			(net "FAN_LED2_D2")
		)
	)
	(footprint ""
		(layer "F.Cu")
		(at 117.602 -134.493 90)
		(property "Reference" "R427"
			(at 0 0 90)
			(layer "F.SilkS")
			(hide yes)
			(effects
				(font
					(size 1.27 1.27)
				)
			)
		)
		(property "Value" "4K7R2F-GP"
			(at 0.064008 -3.993896 90)
			(unlocked yes)
			(layer "F.Fab")
			(hide yes)
			(effects
				(font
					(size 1.016 1.016)
					(thickness 0.1524)
				)
			)
		)
		(property "Device Type" "R402H16"
			(at 0.064008 -5.517896 90)
			(unlocked yes)
			(layer "F.Fab")
			(hide yes)
			(effects
				(font
					(size 1.016 1.016)
					(thickness 0.1524)
				)
			)
		)
		(duplicate_pad_numbers_are_jumpers no)
		(fp_line
			(start 0.508 -0.9398)
			(end -0.508 -0.9398)
			(stroke
				(width 0.1524)
				(type default)
			)
			(layer "F.SilkS")
		)
		(fp_line
			(start -0.508 -0.9398)
			(end -0.508 0.9398)
			(stroke
				(width 0.1524)
				(type default)
			)
			(layer "F.SilkS")
		)
		(fp_rect
			(start -0.508 0.9398)
			(end 0.508 -0.9398)
			(stroke
				(width 0)
				(type default)
			)
			(fill no)
			(layer "F.CrtYd")
		)
		(fp_rect
			(start -0.508 0.9398)
			(end 0.508 -0.9398)
			(stroke
				(width 0)
				(type default)
			)
			(fill no)
			(layer "F.Fab")
		)
		(pad "1" smd custom
			(at 0 -0.4445 90)
			(size 0.1397 0.1397)
			(layers "F.Cu" "F.Mask" "F.Paste")
			(net "SW_PWR_R_HDD15")
			(options
				(clearance outline)
				(anchor circle)
			)
			(primitives
				(gr_poly
					(pts
						(arc
							(start -0.1778 -0.2794)
							(mid -0.249642 -0.249642)
							(end -0.2794 -0.1778)
						)
						(arc
							(start -0.2794 0.1778)
							(mid -0.249642 0.249642)
							(end -0.1778 0.2794)
						)
						(arc
							(start 0.1778 0.2794)
							(mid 0.249642 0.249642)
							(end 0.2794 0.1778)
						)
						(arc
							(start 0.2794 -0.1778)
							(mid 0.249642 -0.249642)
							(end 0.1778 -0.2794)
						)
					)
					(width 0)
					(fill yes)
				)
			)
		)
		(pad "2" smd custom
			(at 0 0.4445 90)
			(size 0.1397 0.1397)
			(layers "F.Cu" "F.Mask" "F.Paste")
			(net "GND")
			(options
				(clearance outline)
				(anchor circle)
			)
			(primitives
				(gr_poly
					(pts
						(arc
							(start -0.1778 -0.2794)
							(mid -0.249642 -0.249642)
							(end -0.2794 -0.1778)
						)
						(arc
							(start -0.2794 0.1778)
							(mid -0.249642 0.249642)
							(end -0.1778 0.2794)
						)
						(arc
							(start 0.1778 0.2794)
							(mid 0.249642 0.249642)
							(end 0.2794 0.1778)
						)
						(arc
							(start 0.2794 -0.1778)
							(mid 0.249642 -0.249642)
							(end 0.1778 -0.2794)
						)
					)
					(width 0)
					(fill yes)
				)
			)
		)
	)
	(footprint ""
		(layer "F.Cu")
		(at 212.6488 -203.327 90)
		(property "Reference" "C9"
			(at 0 0 90)
			(layer "F.SilkS")
			(hide yes)
			(effects
				(font
					(size 1.27 1.27)
				)
			)
		)
		(property "Value" "SC1U16V3KX-5GP"
			(at 0 -2.8194 90)
			(unlocked yes)
			(layer "F.Fab")
			(hide yes)
			(effects
				(font
					(size 1.016 1.016)
					(thickness 0.1524)
				)
			)
		)
		(property "Device Type" "C603H36"
			(at 0 -4.3434 90)
			(unlocked yes)
			(layer "F.Fab")
			(hide yes)
			(effects
				(font
					(size 1.016 1.016)
					(thickness 0.1524)
				)
			)
		)
		(duplicate_pad_numbers_are_jumpers no)
		(fp_line
			(start 0.508 0)
			(end -0.508 0)
			(stroke
				(width 0.2032)
				(type default)
			)
			(layer "F.SilkS")
		)
		(fp_rect
			(start -0.5842 1.3335)
			(end 0.5842 -1.3335)
			(stroke
				(width 0)
				(type default)
			)
			(fill no)
			(layer "F.CrtYd")
		)
		(fp_rect
			(start -0.5842 1.3335)
			(end 0.5842 -1.3335)
			(stroke
				(width 0)
				(type default)
			)
			(fill no)
			(layer "F.Fab")
		)
		(pad "1" smd custom
			(at 0 -0.762 90)
			(size 0.2159 0.2159)
			(layers "F.Cu" "F.Mask" "F.Paste")
			(net "P3V3_STBY_B")
			(options
				(clearance outline)
				(anchor circle)
			)
			(primitives
				(gr_poly
					(pts
						(arc
							(start -0.3302 -0.4318)
							(mid -0.402042 -0.402042)
							(end -0.4318 -0.3302)
						)
						(arc
							(start -0.4318 0.3302)
							(mid -0.402042 0.402042)
							(end -0.3302 0.4318)
						)
						(arc
							(start 0.3302 0.4318)
							(mid 0.402042 0.402042)
							(end 0.4318 0.3302)
						)
						(arc
							(start 0.4318 -0.3302)
							(mid 0.402042 -0.402042)
							(end 0.3302 -0.4318)
						)
					)
					(width 0)
					(fill yes)
				)
			)
		)
		(pad "2" smd custom
			(at 0 0.762 90)
			(size 0.2159 0.2159)
			(layers "F.Cu" "F.Mask" "F.Paste")
			(net "GND")
			(options
				(clearance outline)
				(anchor circle)
			)
			(primitives
				(gr_poly
					(pts
						(arc
							(start -0.3302 -0.4318)
							(mid -0.402042 -0.402042)
							(end -0.4318 -0.3302)
						)
						(arc
							(start -0.4318 0.3302)
							(mid -0.402042 0.402042)
							(end -0.3302 0.4318)
						)
						(arc
							(start 0.3302 0.4318)
							(mid 0.402042 0.402042)
							(end 0.4318 0.3302)
						)
						(arc
							(start 0.4318 -0.3302)
							(mid 0.402042 -0.402042)
							(end 0.3302 -0.4318)
						)
					)
					(width 0)
					(fill yes)
				)
			)
		)
	)
	(footprint ""
		(layer "F.Cu")
		(at 284.8864 -307.6956)
		(property "Reference" "TC5"
			(at 0 0 0)
			(layer "F.SilkS")
			(hide yes)
			(effects
				(font
					(size 1.27 1.27)
				)
			)
		)
		(property "Value" "SE270U16VM-8-GP"
			(at -4.5974 -2.54 0)
			(unlocked yes)
			(layer "F.Fab")
			(hide yes)
			(effects
				(font
					(size 1.016 1.016)
					(thickness 0.1524)
				)
			)
		)
		(property "Device Type" "SE361416H394"
			(at -4.5974 -4.064 0)
			(unlocked yes)
			(layer "F.Fab")
			(hide yes)
			(effects
				(font
					(size 1.016 1.016)
					(thickness 0.1524)
				)
			)
		)
		(duplicate_pad_numbers_are_jumpers no)
		(fp_line
			(start -3.556 -3.4163)
			(end -2.3622 -4.6101)
			(stroke
				(width 0.1524)
				(type default)
			)
			(layer "F.SilkS")
		)
		(fp_line
			(start -3.556 4.6101)
			(end -3.556 -3.4163)
			(stroke
				(width 0.1524)
				(type default)
			)
			(layer "F.SilkS")
		)
		(fp_line
			(start -2.3622 -4.6101)
			(end 2.3622 -4.6101)
			(stroke
				(width 0.1524)
				(type default)
			)
			(layer "F.SilkS")
		)
		(fp_line
			(start 2.3622 -4.6101)
			(end 3.556 -3.4163)
			(stroke
				(width 0.1524)
				(type default)
			)
			(layer "F.SilkS")
		)
		(fp_line
			(start 3.556 -3.4163)
			(end 3.556 4.6101)
			(stroke
				(width 0.1524)
				(type default)
			)
			(layer "F.SilkS")
		)
		(fp_line
			(start 3.556 4.6101)
			(end -3.556 4.6101)
			(stroke
				(width 0.1524)
				(type default)
			)
			(layer "F.SilkS")
		)
		(fp_rect
			(start -3.302 3.6449)
			(end 3.302 -3.6449)
			(stroke
				(width 0)
				(type default)
			)
			(fill no)
			(layer "F.CrtYd")
		)
		(fp_poly
			(pts
				(xy 3.81 4.6863) (xy 3.81 -3.4925) (xy 3.302 -3.4925) (xy 3.302 3.6449) (xy -3.302 3.6449) (xy -3.302 -3.6449)
				(xy 3.302 -3.6449) (xy 3.302 -3.5052) (xy 3.81 -3.5052) (xy 3.81 -4.6863) (xy -3.81 -4.6863) (xy -3.81 4.6863)
			)
			(stroke
				(width 0)
				(type default)
			)
			(fill no)
			(layer "F.CrtYd")
		)
		(fp_rect
			(start -3.81 4.6863)
			(end 3.81 -4.6863)
			(stroke
				(width 0)
				(type default)
			)
			(fill no)
			(layer "F.Fab")
		)
		(pad "1" smd rect
			(at 0 -2.574036)
			(size 1.4224 3.556)
			(layers "F.Cu" "F.Mask" "F.Paste")
			(net "P12V_B")
		)
		(pad "2" smd rect
			(at 0 2.574036)
			(size 1.4224 3.556)
			(layers "F.Cu" "F.Mask" "F.Paste")
			(net "GND")
		)
	)
	(footprint ""
		(layer "F.Cu")
		(at 252.080522 -358.622346)
		(property "Reference" "C560"
			(at 0 0 0)
			(layer "F.SilkS")
			(hide yes)
			(effects
				(font
					(size 1.27 1.27)
				)
			)
		)
		(property "Value" "SCD1U25V2KX-2-GP"
			(at 1.1811 -2.7051 0)
			(unlocked yes)
			(layer "F.Fab")
			(hide yes)
			(effects
				(font
					(size 1.016 1.016)
					(thickness 0.1524)
				)
			)
		)
		(property "Device Type" "C402H22"
			(at 1.1811 -4.2291 0)
			(unlocked yes)
			(layer "F.Fab")
			(hide yes)
			(effects
				(font
					(size 1.016 1.016)
					(thickness 0.1524)
				)
			)
		)
		(duplicate_pad_numbers_are_jumpers no)
		(fp_rect
			(start -0.4318 0.9525)
			(end 0.4318 -0.9525)
			(stroke
				(width 0)
				(type default)
			)
			(fill no)
			(layer "F.CrtYd")
		)
		(fp_rect
			(start -0.4318 0.9525)
			(end 0.4318 -0.9525)
			(stroke
				(width 0)
				(type default)
			)
			(fill no)
			(layer "F.Fab")
		)
		(pad "1" smd custom
			(at 0 -0.4445)
			(size 0.1524 0.1524)
			(layers "F.Cu" "F.Mask" "F.Paste")
			(net "MB3_ISET_R")
			(options
				(clearance outline)
				(anchor circle)
			)
			(primitives
				(gr_poly
					(pts
						(arc
							(start 0.3048 -0.2032)
							(mid 0.275042 -0.275042)
							(end 0.2032 -0.3048)
						)
						(arc
							(start -0.2032 -0.3048)
							(mid -0.275042 -0.275042)
							(end -0.3048 -0.2032)
						)
						(arc
							(start -0.3048 0.2032)
							(mid -0.275042 0.275042)
							(end -0.2032 0.3048)
						)
						(arc
							(start 0.2032 0.3048)
							(mid 0.275042 0.275042)
							(end 0.3048 0.2032)
						)
					)
					(width 0)
					(fill yes)
				)
			)
		)
		(pad "2" smd custom
			(at 0 0.4445)
			(size 0.1524 0.1524)
			(layers "F.Cu" "F.Mask" "F.Paste")
			(net "AGND_CURRENT_DPB")
			(options
				(clearance outline)
				(anchor circle)
			)
			(primitives
				(gr_poly
					(pts
						(arc
							(start 0.3048 -0.2032)
							(mid 0.275042 -0.275042)
							(end 0.2032 -0.3048)
						)
						(arc
							(start -0.2032 -0.3048)
							(mid -0.275042 -0.275042)
							(end -0.3048 -0.2032)
						)
						(arc
							(start -0.3048 0.2032)
							(mid -0.275042 0.275042)
							(end -0.2032 0.3048)
						)
						(arc
							(start 0.2032 0.3048)
							(mid 0.275042 0.275042)
							(end 0.3048 0.2032)
						)
					)
					(width 0)
					(fill yes)
				)
			)
		)
	)
	(footprint ""
		(layer "F.Cu")
		(at 377.698 -214.249)
		(property "Reference" "R332"
			(at 0 0 0)
			(layer "F.SilkS")
			(hide yes)
			(effects
				(font
					(size 1.27 1.27)
				)
			)
		)
		(property "Value" "130R3F-GP"
			(at -0.0254 -2.5146 0)
			(unlocked yes)
			(layer "F.Fab")
			(hide yes)
			(effects
				(font
					(size 1.016 1.016)
					(thickness 0.1524)
				)
			)
		)
		(property "Device Type" "R603H22"
			(at -0.0254 -4.0386 0)
			(unlocked yes)
			(layer "F.Fab")
			(hide yes)
			(effects
				(font
					(size 1.016 1.016)
					(thickness 0.1524)
				)
			)
		)
		(duplicate_pad_numbers_are_jumpers no)
		(fp_line
			(start -0.4826 0)
			(end -0.2032 0)
			(stroke
				(width 0.2032)
				(type default)
			)
			(layer "F.SilkS")
		)
		(fp_line
			(start 0.2032 0)
			(end 0.4826 0)
			(stroke
				(width 0.2032)
				(type default)
			)
			(layer "F.SilkS")
		)
		(fp_rect
			(start -0.5842 1.3335)
			(end 0.5842 -1.3335)
			(stroke
				(width 0)
				(type default)
			)
			(fill no)
			(layer "F.CrtYd")
		)
		(fp_rect
			(start -0.5842 1.3335)
			(end 0.5842 -1.3335)
			(stroke
				(width 0)
				(type default)
			)
			(fill no)
			(layer "F.Fab")
		)
		(pad "1" smd custom
			(at 0 -0.762)
			(size 0.2159 0.2159)
			(layers "F.Cu" "F.Mask" "F.Paste")
			(net "P5V_B_3")
			(options
				(clearance outline)
				(anchor circle)
			)
			(primitives
				(gr_poly
					(pts
						(arc
							(start -0.3302 -0.4318)
							(mid -0.402042 -0.402042)
							(end -0.4318 -0.3302)
						)
						(arc
							(start -0.4318 0.3302)
							(mid -0.402042 0.402042)
							(end -0.3302 0.4318)
						)
						(arc
							(start 0.3302 0.4318)
							(mid 0.402042 0.402042)
							(end 0.4318 0.3302)
						)
						(arc
							(start 0.4318 -0.3302)
							(mid 0.402042 -0.402042)
							(end 0.3302 -0.4318)
						)
					)
					(width 0)
					(fill yes)
				)
			)
		)
		(pad "2" smd custom
			(at 0 0.762)
			(size 0.2159 0.2159)
			(layers "F.Cu" "F.Mask" "F.Paste")
			(net "FLT_HDD8")
			(options
				(clearance outline)
				(anchor circle)
			)
			(primitives
				(gr_poly
					(pts
						(arc
							(start -0.3302 -0.4318)
							(mid -0.402042 -0.402042)
							(end -0.4318 -0.3302)
						)
						(arc
							(start -0.4318 0.3302)
							(mid -0.402042 0.402042)
							(end -0.3302 0.4318)
						)
						(arc
							(start 0.3302 0.4318)
							(mid 0.402042 0.402042)
							(end 0.4318 0.3302)
						)
						(arc
							(start 0.4318 -0.3302)
							(mid 0.402042 -0.402042)
							(end 0.3302 -0.4318)
						)
					)
					(width 0)
					(fill yes)
				)
			)
		)
	)
	(footprint ""
		(layer "F.Cu")
		(at 393.674854 -178.799998)
		(property "Reference" ""
			(at 0 0 0)
			(layer "F.SilkS")
			(hide yes)
			(effects
				(font
					(size 1.27 1.27)
				)
			)
		)
		(property "Value" "*"
			(at -8.398764 -8.057642 0)
			(unlocked yes)
			(layer "F.Fab")
			(hide yes)
			(effects
				(font
					(size 1.016 1.016)
					(thickness 0.1524)
				)
			)
		)
		(duplicate_pad_numbers_are_jumpers no)
		(fp_poly
			(pts
				(arc
					(start 7.3152 0)
					(mid 0 7.3152)
					(end -7.3152 0)
				)
				(arc
					(start -7.3152 -5.9944)
					(mid 0 -13.3096)
					(end 7.3152 -5.9944)
				)
			)
			(stroke
				(width 0)
				(type default)
			)
			(fill no)
			(layer "B.CrtYd")
		)
		(fp_poly
			(pts
				(arc
					(start 7.3152 0)
					(mid 0 7.3152)
					(end -7.3152 0)
				)
				(arc
					(start -7.3152 -5.9944)
					(mid 0 -13.3096)
					(end 7.3152 -5.9944)
				)
			)
			(stroke
				(width 0)
				(type default)
			)
			(fill no)
			(layer "F.CrtYd")
		)
		(fp_poly
			(pts
				(arc
					(start 7.3152 0)
					(mid 0 7.3152)
					(end -7.3152 0)
				)
				(arc
					(start -7.3152 -5.9944)
					(mid 0 -13.3096)
					(end 7.3152 -5.9944)
				)
			)
			(stroke
				(width 0)
				(type default)
			)
			(fill no)
			(layer "B.Fab")
		)
		(fp_poly
			(pts
				(arc
					(start 7.3152 0)
					(mid 0 7.3152)
					(end -7.3152 0)
				)
				(arc
					(start -7.3152 -5.9944)
					(mid 0 -13.3096)
					(end 7.3152 -5.9944)
				)
			)
			(stroke
				(width 0)
				(type default)
			)
			(fill no)
			(layer "F.Fab")
		)
		(pad "1" thru_hole oval
			(at 0 0)
			(size 14.0208 20.0152)
			(drill 0.0254
				(offset 0 -2.9972)
			)
			(layers "*.Cu" "*.Mask")
			(remove_unused_layers no)
			(net "Net_43")
			(clearance -1.002284)
			(thermal_gap 0.1524)
			(padstack
				(mode front_inner_back)
				(layer "Inner"
					(shape custom)
					(size 2.928012 2.928012)
					(options
						(anchor circle)
					)
					(primitives
						(gr_poly
							(pts
								(arc
									(start 4.571746 -2.084324)
									(mid 0.000333 7.430372)
									(end -4.571492 -2.084324)
								)
								(arc
									(start -4.571492 -2.084324)
									(mid -3.570296 -3.611977)
									(end -2.875026 -5.30098)
								)
								(arc
									(start -2.875026 -5.30098)
									(mid 0.000217 -7.43089)
									(end 2.87528 -5.30098)
								)
								(arc
									(start 2.87528 -5.30098)
									(mid 3.570511 -3.611956)
									(end 4.571746 -2.084324)
								)
							)
							(width 0)
							(fill yes)
						)
					)
					(clearance 0.1524)
				)
				(layer "B.Cu"
					(shape oval)
					(size 14.0208 20.0152)
					(offset 0 -2.9972)
					(clearance -1.002284)
				)
			)
		)
		(zone
			(layers "F.Cu" "B.Cu" "In1.Cu" "In2.Cu" "In3.Cu" "In4.Cu" "In5.Cu" "In6.Cu")
			(hatch none 0.5)
			(connect_pads
				(clearance 0)
			)
			(min_thickness 0.25)
			(keepout
				(tracks not_allowed)
				(vias allowed)
				(pads allowed)
				(copperpour not_allowed)
				(footprints allowed)
			)
			(placement
				(enabled no)
				(sheetname "")
			)
			(fill
				(thermal_gap 0.5)
				(thermal_bridge_width 0.5)
				(island_removal_mode 0)
			)
			(polygon
				(pts
					(arc
						(start 386.664454 -184.794398)
						(mid 393.674854 -191.804798)
						(end 400.685254 -184.794398)
					)
					(arc
						(start 400.685254 -178.799998)
						(mid 393.674854 -171.789598)
						(end 386.664454 -178.799998)
					)
				)
			)
		)
	)
	(footprint ""
		(layer "F.Cu")
		(at 416.284664 -245.219474 -90)
		(property "Reference" "C145"
			(at 0 0 270)
			(layer "F.SilkS")
			(hide yes)
			(effects
				(font
					(size 1.27 1.27)
				)
			)
		)
		(property "Value" "SCD01U16V1KX-GP"
			(at -2.8321 -1.7399 270)
			(unlocked yes)
			(layer "F.Fab")
			(hide yes)
			(effects
				(font
					(size 1.016 1.016)
					(thickness 0.1524)
				)
			)
		)
		(property "Device Type" "C0201H13"
			(at -2.8321 -3.2639 270)
			(unlocked yes)
			(layer "F.Fab")
			(hide yes)
			(effects
				(font
					(size 1.016 1.016)
					(thickness 0.1524)
				)
			)
		)
		(duplicate_pad_numbers_are_jumpers no)
		(fp_rect
			(start -0.2794 0.6477)
			(end 0.2794 -0.6477)
			(stroke
				(width 0)
				(type default)
			)
			(fill no)
			(layer "F.CrtYd")
		)
		(fp_rect
			(start -0.2794 0.6477)
			(end 0.2794 -0.6477)
			(stroke
				(width 0)
				(type default)
			)
			(fill no)
			(layer "F.Fab")
		)
		(pad "1" smd custom
			(at 0 -0.2794 270)
			(size 0.0762 0.0762)
			(layers "F.Cu" "F.Mask" "F.Paste")
			(net "SAS_HDD_RX_N9")
			(options
				(clearance outline)
				(anchor circle)
			)
			(primitives
				(gr_poly
					(pts
						(arc
							(start 0.1524 -0.127)
							(mid 0.137521 -0.162921)
							(end 0.1016 -0.1778)
						)
						(arc
							(start -0.1016 -0.1778)
							(mid -0.137521 -0.162921)
							(end -0.1524 -0.127)
						)
						(arc
							(start -0.1524 0.127)
							(mid -0.137521 0.162921)
							(end -0.1016 0.1778)
						)
						(arc
							(start 0.1016 0.1778)
							(mid 0.137521 0.162921)
							(end 0.1524 0.127)
						)
					)
					(width 0)
					(fill yes)
				)
			)
		)
		(pad "2" smd custom
			(at 0 0.2794 270)
			(size 0.0762 0.0762)
			(layers "F.Cu" "F.Mask" "F.Paste")
			(net "PHY_SCC_B_TO_DRV_B_9_DN")
			(options
				(clearance outline)
				(anchor circle)
			)
			(primitives
				(gr_poly
					(pts
						(arc
							(start 0.1524 -0.127)
							(mid 0.137521 -0.162921)
							(end 0.1016 -0.1778)
						)
						(arc
							(start -0.1016 -0.1778)
							(mid -0.137521 -0.162921)
							(end -0.1524 -0.127)
						)
						(arc
							(start -0.1524 0.127)
							(mid -0.137521 0.162921)
							(end -0.1016 0.1778)
						)
						(arc
							(start 0.1016 0.1778)
							(mid 0.137521 0.162921)
							(end 0.1524 0.127)
						)
					)
					(width 0)
					(fill yes)
				)
			)
		)
	)
	(footprint ""
		(layer "F.Cu")
		(at 328.643996 -367.157 -90)
		(property "Reference" "D42"
			(at 0 0 270)
			(layer "F.SilkS")
			(hide yes)
			(effects
				(font
					(size 1.27 1.27)
				)
			)
		)
		(property "Value" "BAS16H-GP"
			(at 0 -5.5372 270)
			(unlocked yes)
			(layer "F.Fab")
			(hide yes)
			(effects
				(font
					(size 1.016 1.016)
					(thickness 0.1524)
				)
			)
		)
		(property "Device Type" "SOD123AKH48"
			(at 0 -7.0612 270)
			(unlocked yes)
			(layer "F.Fab")
			(hide yes)
			(effects
				(font
					(size 1.016 1.016)
					(thickness 0.1524)
				)
			)
		)
		(duplicate_pad_numbers_are_jumpers no)
		(fp_line
			(start 0.889 2.921)
			(end -0.889 2.921)
			(stroke
				(width 0.508)
				(type default)
			)
			(layer "F.SilkS")
		)
		(fp_line
			(start -1.016 2.667)
			(end 1.016 2.667)
			(stroke
				(width 0.1524)
				(type default)
			)
			(layer "F.SilkS")
		)
		(fp_line
			(start 1.016 2.667)
			(end 1.016 -2.667)
			(stroke
				(width 0.1524)
				(type default)
			)
			(layer "F.SilkS")
		)
		(fp_line
			(start -1.016 -2.667)
			(end -1.016 2.667)
			(stroke
				(width 0.1524)
				(type default)
			)
			(layer "F.SilkS")
		)
		(fp_line
			(start 1.016 -2.667)
			(end -1.016 -2.667)
			(stroke
				(width 0.1524)
				(type default)
			)
			(layer "F.SilkS")
		)
		(fp_rect
			(start -1.143 3.175)
			(end 1.143 -2.794)
			(stroke
				(width 0)
				(type default)
			)
			(fill no)
			(layer "F.CrtYd")
		)
		(fp_poly
			(pts
				(xy -1.143 -2.794) (xy 1.143 -2.794) (xy 1.143 3.175) (xy -1.143 3.175)
			)
			(stroke
				(width 0)
				(type default)
			)
			(fill no)
			(layer "F.Fab")
		)
		(pad "A" smd rect
			(at 0 -1.6891 270)
			(size 0.889 1.397)
			(layers "F.Cu" "F.Mask" "F.Paste")
			(net "FAN_2_TACH1")
		)
		(pad "K" smd rect
			(at 0 1.6891 270)
			(size 0.889 1.397)
			(layers "F.Cu" "F.Mask" "F.Paste")
			(net "P12V_IN")
		)
	)
	(footprint ""
		(layer "F.Cu")
		(at 325.550022 -28.910026 -90)
		(property "Reference" "HDDSAS30"
			(at 0 0 270)
			(layer "F.SilkS")
			(hide yes)
			(effects
				(font
					(size 1.27 1.27)
				)
			)
		)
		(property "Value" "SKT-SAS15P-14P-45-GP"
			(at -20.7645 -8.9789 270)
			(unlocked yes)
			(layer "F.Fab")
			(hide yes)
			(effects
				(font
					(size 1.016 1.016)
					(thickness 0.1524)
				)
			)
		)
		(property "Device Type" "10120818-001C-TRLF"
			(at -20.7645 -10.5029 270)
			(unlocked yes)
			(layer "F.Fab")
			(hide yes)
			(effects
				(font
					(size 1.016 1.016)
					(thickness 0.1524)
				)
			)
		)
		(duplicate_pad_numbers_are_jumpers no)
		(fp_line
			(start 1.651 4.2926)
			(end 1.651 3.0099)
			(stroke
				(width 0.1524)
				(type default)
			)
			(layer "F.SilkS")
		)
		(fp_line
			(start 8.509 4.2926)
			(end 1.651 4.2926)
			(stroke
				(width 0.1524)
				(type default)
			)
			(layer "F.SilkS")
		)
		(fp_line
			(start -23.4188 3.0099)
			(end -23.4188 -3.2512)
			(stroke
				(width 0.1524)
				(type default)
			)
			(layer "F.SilkS")
		)
		(fp_line
			(start 1.651 3.0099)
			(end -23.4188 3.0099)
			(stroke
				(width 0.1524)
				(type default)
			)
			(layer "F.SilkS")
		)
		(fp_line
			(start 8.509 3.0099)
			(end 8.509 4.2926)
			(stroke
				(width 0.1524)
				(type default)
			)
			(layer "F.SilkS")
		)
		(fp_line
			(start 23.4188 3.0099)
			(end 8.509 3.0099)
			(stroke
				(width 0.1524)
				(type default)
			)
			(layer "F.SilkS")
		)
		(fp_line
			(start -23.4188 -3.2512)
			(end 23.4188 -3.2512)
			(stroke
				(width 0.1524)
				(type default)
			)
			(layer "F.SilkS")
		)
		(fp_line
			(start 23.4188 -3.2512)
			(end 23.4188 3.0099)
			(stroke
				(width 0.1524)
				(type default)
			)
			(layer "F.SilkS")
		)
		(fp_line
			(start 15.5067 -3.3401)
			(end 16.2687 -3.3401)
			(stroke
				(width 0.3302)
				(type default)
			)
			(layer "F.SilkS")
		)
		(fp_poly
			(pts
				(xy 15.868904 -3.230372) (xy 16.503904 -3.865372) (xy 15.233904 -3.865372)
			)
			(stroke
				(width 0)
				(type default)
			)
			(fill yes)
			(layer "F.SilkS")
		)
		(fp_poly
			(pts
				(xy -22.8727 -2.7559) (xy 22.8727 -2.7559) (xy 22.8727 2.7559) (xy 8.255 2.7559) (xy 8.255 3.5179)
				(xy 1.905 3.5179) (xy 1.905 2.7559) (xy -22.8727 2.7559)
			)
			(stroke
				(width 0)
				(type default)
			)
			(fill no)
			(layer "F.CrtYd")
		)
		(fp_poly
			(pts
				(xy 1.397 4.5466) (xy 1.397 3.2639) (xy -23.6728 3.2639) (xy -23.6728 -3.5052) (xy 23.6728 -3.5052)
				(xy 23.6728 -0.00635) (xy 22.8727 -0.00635) (xy 22.8727 -2.7559) (xy -22.8727 -2.7559) (xy -22.8727 2.7559)
				(xy 1.905 2.7559) (xy 1.905 3.5179) (xy 8.255 3.5179) (xy 8.255 2.7559) (xy 22.8727 2.7559) (xy 22.8727 0.00635)
				(xy 23.6728 0.00635) (xy 23.6728 3.2639) (xy 8.763 3.2639) (xy 8.763 4.5466)
			)
			(stroke
				(width 0)
				(type default)
			)
			(fill no)
			(layer "F.CrtYd")
		)
		(fp_poly
			(pts
				(xy 1.397 4.5466) (xy 1.397 3.2639) (xy -23.6728 3.2639) (xy -23.6728 -3.5052) (xy 23.6728 -3.5052)
				(xy 23.6728 3.2639) (xy 8.763 3.2639) (xy 8.763 4.5466)
			)
			(stroke
				(width 0)
				(type default)
			)
			(fill no)
			(layer "F.Fab")
		)
		(pad "" np_thru_hole circle
			(at -18.874994 0 270)
			(size 0.254 0.254)
			(drill 1.3462)
			(layers "*.Cu" "*.Mask")
			(clearance 0.9017)
			(thermal_gap 0.9017)
		)
		(pad "" np_thru_hole circle
			(at 18.874994 0 270)
			(size 0.254 0.254)
			(drill 0.9398)
			(layers "*.Cu" "*.Mask")
			(clearance 0.6985)
			(thermal_gap 0.6985)
		)
		(pad "G1" smd rect
			(at 21.874988 0 270)
			(size 2.5908 2.5908)
			(layers "F.Cu" "F.Mask" "F.Paste")
			(net "GND")
		)
		(pad "G2" smd rect
			(at -21.874988 0 270)
			(size 2.5908 2.5908)
			(layers "F.Cu" "F.Mask" "F.Paste")
			(net "GND")
		)
		(pad "P1" smd rect
			(at 1.905 -1.82499 270)
			(size 0.6096 2.3622)
			(layers "F.Cu" "F.Mask" "F.Paste")
			(net "Net_1644")
		)
		(pad "P2" smd rect
			(at 0.635 -1.82499 270)
			(size 0.6096 2.3622)
			(layers "F.Cu" "F.Mask" "F.Paste")
			(net "Net_1645")
		)
		(pad "P3" smd rect
			(at -0.635 -1.82499 270)
			(size 0.6096 2.3622)
			(layers "F.Cu" "F.Mask" "F.Paste")
			(net "Net_1646")
		)
		(pad "P4" smd rect
			(at -1.905 -1.82499 270)
			(size 0.6096 2.3622)
			(layers "F.Cu" "F.Mask" "F.Paste")
			(net "GND")
		)
		(pad "P5" smd rect
			(at -3.175 -1.82499 270)
			(size 0.6096 2.3622)
			(layers "F.Cu" "F.Mask" "F.Paste")
			(net "HDD_PRSNT_30")
		)
		(pad "P6" smd rect
			(at -4.445 -1.82499 270)
			(size 0.6096 2.3622)
			(layers "F.Cu" "F.Mask" "F.Paste")
			(net "GND")
		)
		(pad "P7" smd rect
			(at -5.715 -1.82499 270)
			(size 0.6096 2.3622)
			(layers "F.Cu" "F.Mask" "F.Paste")
			(net "5V_PRE_30")
		)
		(pad "P8" smd rect
			(at -6.985 -1.82499 270)
			(size 0.6096 2.3622)
			(layers "F.Cu" "F.Mask" "F.Paste")
			(net "P5V_HDD30")
		)
		(pad "P9" smd rect
			(at -8.255 -1.82499 270)
			(size 0.6096 2.3622)
			(layers "F.Cu" "F.Mask" "F.Paste")
			(net "P5V_HDD30")
		)
		(pad "P10" smd rect
			(at -9.525 -1.82499 270)
			(size 0.6096 2.3622)
			(layers "F.Cu" "F.Mask" "F.Paste")
			(net "GND")
		)
		(pad "P11" smd rect
			(at -10.795 -1.82499 270)
			(size 0.6096 2.3622)
			(layers "F.Cu" "F.Mask" "F.Paste")
			(net "ACT_HDD_30")
		)
		(pad "P12" smd rect
			(at -12.065 -1.82499 270)
			(size 0.6096 2.3622)
			(layers "F.Cu" "F.Mask" "F.Paste")
			(net "GND")
		)
		(pad "P13" smd rect
			(at -13.335 -1.82499 270)
			(size 0.6096 2.3622)
			(layers "F.Cu" "F.Mask" "F.Paste")
			(net "12V_PRE_30")
		)
		(pad "P14" smd rect
			(at -14.605 -1.82499 270)
			(size 0.6096 2.3622)
			(layers "F.Cu" "F.Mask" "F.Paste")
			(net "P12V_HDD30")
		)
		(pad "P15" smd rect
			(at -15.875 -1.82499 270)
			(size 0.6096 2.3622)
			(layers "F.Cu" "F.Mask" "F.Paste")
			(net "P12V_HDD30")
		)
		(pad "S1" smd rect
			(at 15.875 -1.82499 270)
			(size 0.6096 2.3622)
			(layers "F.Cu" "F.Mask" "F.Paste")
			(net "GND")
		)
		(pad "S2" smd rect
			(at 14.605 -1.82499 270)
			(size 0.6096 2.3622)
			(layers "F.Cu" "F.Mask" "F.Paste")
			(net "SAS_HDD_RX_P30")
		)
		(pad "S3" smd rect
			(at 13.335 -1.82499 270)
			(size 0.6096 2.3622)
			(layers "F.Cu" "F.Mask" "F.Paste")
			(net "SAS_HDD_RX_N30")
		)
		(pad "S4" smd rect
			(at 12.065 -1.82499 270)
			(size 0.6096 2.3622)
			(layers "F.Cu" "F.Mask" "F.Paste")
			(net "GND")
		)
		(pad "S5" smd rect
			(at 10.795 -1.82499 270)
			(size 0.6096 2.3622)
			(layers "F.Cu" "F.Mask" "F.Paste")
			(net "PHY_DRV_B_TO_SCC_B_30_DN")
		)
		(pad "S6" smd rect
			(at 9.525 -1.82499 270)
			(size 0.6096 2.3622)
			(layers "F.Cu" "F.Mask" "F.Paste")
			(net "PHY_DRV_B_TO_SCC_B_30_DP")
		)
		(pad "S7" smd rect
			(at 8.255 -1.82499 270)
			(size 0.6096 2.3622)
			(layers "F.Cu" "F.Mask" "F.Paste")
			(net "GND")
		)
		(pad "S8" smd rect
			(at 7.480046 2.845054 270)
			(size 0.508 2.3622)
			(layers "F.Cu" "F.Mask" "F.Paste")
			(net "GND")
		)
		(pad "S9" smd rect
			(at 6.679946 2.845054 270)
			(size 0.508 2.3622)
			(layers "F.Cu" "F.Mask" "F.Paste")
			(net "Net_455")
		)
		(pad "S10" smd rect
			(at 5.8801 2.845054 270)
			(size 0.508 2.3622)
			(layers "F.Cu" "F.Mask" "F.Paste")
			(net "Net_347")
		)
		(pad "S11" smd rect
			(at 5.08 2.845054 270)
			(size 0.508 2.3622)
			(layers "F.Cu" "F.Mask" "F.Paste")
			(net "GND")
		)
		(pad "S12" smd rect
			(at 4.2799 2.845054 270)
			(size 0.508 2.3622)
			(layers "F.Cu" "F.Mask" "F.Paste")
			(net "Net_383")
		)
		(pad "S13" smd rect
			(at 3.480054 2.845054 270)
			(size 0.508 2.3622)
			(layers "F.Cu" "F.Mask" "F.Paste")
			(net "Net_419")
		)
		(pad "S14" smd rect
			(at 2.679954 2.845054 270)
			(size 0.508 2.3622)
			(layers "F.Cu" "F.Mask" "F.Paste")
			(net "GND")
		)
		(zone
			(layer "F.Cu")
			(hatch none 0.5)
			(connect_pads
				(clearance 0)
			)
			(min_thickness 0.25)
			(keepout
				(tracks allowed)
				(vias not_allowed)
				(pads allowed)
				(copperpour not_allowed)
				(footprints allowed)
			)
			(placement
				(enabled no)
				(sheetname "")
			)
			(fill
				(thermal_gap 0.5)
				(thermal_bridge_width 0.5)
				(island_removal_mode 0)
			)
			(polygon
				(pts
					(xy 329.207622 -45.648626) (xy 322.133722 -45.648626) (xy 322.133722 -52.582826) (xy 323.238622 -52.582826)
					(xy 323.238622 -48.468026) (xy 327.861422 -48.468026) (xy 327.861422 -52.582826) (xy 329.207622 -52.582826)
				)
			)
		)
		(zone
			(layer "F.Cu")
			(hatch none 0.5)
			(connect_pads
				(clearance 0)
			)
			(min_thickness 0.25)
			(keepout
				(tracks not_allowed)
				(vias allowed)
				(pads allowed)
				(copperpour not_allowed)
				(footprints allowed)
			)
			(placement
				(enabled no)
				(sheetname "")
			)
			(fill
				(thermal_gap 0.5)
				(thermal_bridge_width 0.5)
				(island_removal_mode 0)
			)
			(polygon
				(pts
					(xy 329.207622 -45.648626) (xy 322.133722 -45.648626) (xy 322.133722 -52.582826) (xy 323.238622 -52.582826)
					(xy 323.238622 -48.468026) (xy 327.861422 -48.468026) (xy 327.861422 -52.582826) (xy 329.207622 -52.582826)
				)
			)
		)
		(zone
			(layer "F.Cu")
			(hatch none 0.5)
			(connect_pads
				(clearance 0)
			)
			(min_thickness 0.25)
			(keepout
				(tracks not_allowed)
				(vias allowed)
				(pads allowed)
				(copperpour not_allowed)
				(footprints allowed)
			)
			(placement
				(enabled no)
				(sheetname "")
			)
			(fill
				(thermal_gap 0.5)
				(thermal_bridge_width 0.5)
				(island_removal_mode 0)
			)
			(polygon
				(pts
					(xy 329.207622 -12.171426) (xy 322.133722 -12.171426) (xy 322.133722 -5.237226) (xy 323.238622 -5.237226)
					(xy 323.238622 -9.352026) (xy 327.861422 -9.352026) (xy 327.861422 -5.237226) (xy 329.207622 -5.237226)
				)
			)
		)
		(zone
			(layer "F.Cu")
			(hatch none 0.5)
			(connect_pads
				(clearance 0)
			)
			(min_thickness 0.25)
			(keepout
				(tracks allowed)
				(vias not_allowed)
				(pads allowed)
				(copperpour not_allowed)
				(footprints allowed)
			)
			(placement
				(enabled no)
				(sheetname "")
			)
			(fill
				(thermal_gap 0.5)
				(thermal_bridge_width 0.5)
				(island_removal_mode 0)
			)
			(polygon
				(pts
					(xy 329.207622 -12.171426) (xy 322.133722 -12.171426) (xy 322.133722 -5.237226) (xy 323.238622 -5.237226)
					(xy 323.238622 -9.352026) (xy 327.861422 -9.352026) (xy 327.861422 -5.237226) (xy 329.207622 -5.237226)
				)
			)
		)
		(zone
			(layers "F.Cu" "B.Cu" "In1.Cu" "In2.Cu" "In3.Cu" "In4.Cu" "In5.Cu" "In6.Cu")
			(hatch none 0.5)
			(connect_pads
				(clearance 0)
			)
			(min_thickness 0.25)
			(keepout
				(tracks not_allowed)
				(vias allowed)
				(pads allowed)
				(copperpour not_allowed)
				(footprints allowed)
			)
			(placement
				(enabled no)
				(sheetname "")
			)
			(fill
				(thermal_gap 0.5)
				(thermal_bridge_width 0.5)
				(island_removal_mode 0)
			)
			(polygon
				(pts
					(arc
						(start 326.324722 -10.035032)
						(mid 324.775322 -10.035032)
						(end 326.324722 -10.035032)
					)
				)
			)
		)
		(zone
			(layers "F.Cu" "B.Cu" "In1.Cu" "In2.Cu" "In3.Cu" "In4.Cu" "In5.Cu" "In6.Cu")
			(hatch none 0.5)
			(connect_pads
				(clearance 0)
			)
			(min_thickness 0.25)
			(keepout
				(tracks not_allowed)
				(vias allowed)
				(pads allowed)
				(copperpour not_allowed)
				(footprints allowed)
			)
			(placement
				(enabled no)
				(sheetname "")
			)
			(fill
				(thermal_gap 0.5)
				(thermal_bridge_width 0.5)
				(island_removal_mode 0)
			)
			(polygon
				(pts
					(arc
						(start 326.527922 -47.78502)
						(mid 324.572122 -47.78502)
						(end 326.527922 -47.78502)
					)
				)
			)
		)
	)
	(footprint ""
		(layer "F.Cu")
		(at 146.431 -148.717 -90)
		(property "Reference" "C238"
			(at 0 0 270)
			(layer "F.SilkS")
			(hide yes)
			(effects
				(font
					(size 1.27 1.27)
				)
			)
		)
		(property "Value" "SC1U16V3KX-5GP"
			(at 0 -2.8194 270)
			(unlocked yes)
			(layer "F.Fab")
			(hide yes)
			(effects
				(font
					(size 1.016 1.016)
					(thickness 0.1524)
				)
			)
		)
		(property "Device Type" "C603H36"
			(at 0 -4.3434 270)
			(unlocked yes)
			(layer "F.Fab")
			(hide yes)
			(effects
				(font
					(size 1.016 1.016)
					(thickness 0.1524)
				)
			)
		)
		(duplicate_pad_numbers_are_jumpers no)
		(fp_line
			(start 0.508 0)
			(end -0.508 0)
			(stroke
				(width 0.2032)
				(type default)
			)
			(layer "F.SilkS")
		)
		(fp_rect
			(start -0.5842 1.3335)
			(end 0.5842 -1.3335)
			(stroke
				(width 0)
				(type default)
			)
			(fill no)
			(layer "F.CrtYd")
		)
		(fp_rect
			(start -0.5842 1.3335)
			(end 0.5842 -1.3335)
			(stroke
				(width 0)
				(type default)
			)
			(fill no)
			(layer "F.Fab")
		)
		(pad "1" smd custom
			(at 0 -0.762 270)
			(size 0.2159 0.2159)
			(layers "F.Cu" "F.Mask" "F.Paste")
			(net "P5V_HDD16")
			(options
				(clearance outline)
				(anchor circle)
			)
			(primitives
				(gr_poly
					(pts
						(arc
							(start -0.3302 -0.4318)
							(mid -0.402042 -0.402042)
							(end -0.4318 -0.3302)
						)
						(arc
							(start -0.4318 0.3302)
							(mid -0.402042 0.402042)
							(end -0.3302 0.4318)
						)
						(arc
							(start 0.3302 0.4318)
							(mid 0.402042 0.402042)
							(end 0.4318 0.3302)
						)
						(arc
							(start 0.4318 -0.3302)
							(mid 0.402042 -0.402042)
							(end 0.3302 -0.4318)
						)
					)
					(width 0)
					(fill yes)
				)
			)
		)
		(pad "2" smd custom
			(at 0 0.762 270)
			(size 0.2159 0.2159)
			(layers "F.Cu" "F.Mask" "F.Paste")
			(net "GND")
			(options
				(clearance outline)
				(anchor circle)
			)
			(primitives
				(gr_poly
					(pts
						(arc
							(start -0.3302 -0.4318)
							(mid -0.402042 -0.402042)
							(end -0.4318 -0.3302)
						)
						(arc
							(start -0.4318 0.3302)
							(mid -0.402042 0.402042)
							(end -0.3302 0.4318)
						)
						(arc
							(start 0.3302 0.4318)
							(mid 0.402042 0.402042)
							(end 0.4318 0.3302)
						)
						(arc
							(start 0.4318 -0.3302)
							(mid 0.402042 -0.402042)
							(end 0.3302 -0.4318)
						)
					)
					(width 0)
					(fill yes)
				)
			)
		)
	)
	(footprint ""
		(layer "F.Cu")
		(at 333.629 -270.5862 -90)
		(property "Reference" "R256"
			(at 0 0 270)
			(layer "F.SilkS")
			(hide yes)
			(effects
				(font
					(size 1.27 1.27)
				)
			)
		)
		(property "Value" "2R6F-GP"
			(at -0.0508 -4.8514 270)
			(unlocked yes)
			(layer "F.Fab")
			(hide yes)
			(effects
				(font
					(size 1.016 1.016)
					(thickness 0.1524)
				)
			)
		)
		(property "Device Type" "R1206H26"
			(at 0 -6.3754 270)
			(unlocked yes)
			(layer "F.Fab")
			(hide yes)
			(effects
				(font
					(size 1.016 1.016)
					(thickness 0.1524)
				)
			)
		)
		(duplicate_pad_numbers_are_jumpers no)
		(fp_line
			(start -1.016 2.2352)
			(end -1.016 -2.2352)
			(stroke
				(width 0.1524)
				(type default)
			)
			(layer "F.SilkS")
		)
		(fp_line
			(start 1.016 2.2352)
			(end -1.016 2.2352)
			(stroke
				(width 0.1524)
				(type default)
			)
			(layer "F.SilkS")
		)
		(fp_line
			(start -1.016 -2.2352)
			(end 1.016 -2.2352)
			(stroke
				(width 0.1524)
				(type default)
			)
			(layer "F.SilkS")
		)
		(fp_line
			(start 1.016 -2.2352)
			(end 1.016 2.2352)
			(stroke
				(width 0.1524)
				(type default)
			)
			(layer "F.SilkS")
		)
		(fp_rect
			(start -1.0922 2.3114)
			(end 1.0922 -2.3114)
			(stroke
				(width 0)
				(type default)
			)
			(fill no)
			(layer "F.CrtYd")
		)
		(fp_poly
			(pts
				(xy -1.0922 -2.3114) (xy 1.0922 -2.3114) (xy 1.0922 2.3114) (xy -1.0922 2.3114)
			)
			(stroke
				(width 0)
				(type default)
			)
			(fill no)
			(layer "F.Fab")
		)
		(pad "1" smd rect
			(at 0 -1.397 270)
			(size 1.651 1.27)
			(layers "F.Cu" "F.Mask" "F.Paste")
			(net "P12V_HDD6")
		)
		(pad "2" smd rect
			(at 0 1.397 270)
			(size 1.651 1.27)
			(layers "F.Cu" "F.Mask" "F.Paste")
			(net "12V_PRE_6")
		)
	)
	(footprint ""
		(layer "F.Cu")
		(at 158.663386 -129.66065 90)
		(property "Reference" "C237"
			(at 0 0 90)
			(layer "F.SilkS")
			(hide yes)
			(effects
				(font
					(size 1.27 1.27)
				)
			)
		)
		(property "Value" "SCD01U16V1KX-GP"
			(at -2.8321 -1.7399 90)
			(unlocked yes)
			(layer "F.Fab")
			(hide yes)
			(effects
				(font
					(size 1.016 1.016)
					(thickness 0.1524)
				)
			)
		)
		(property "Device Type" "C0201H13"
			(at -2.8321 -3.2639 90)
			(unlocked yes)
			(layer "F.Fab")
			(hide yes)
			(effects
				(font
					(size 1.016 1.016)
					(thickness 0.1524)
				)
			)
		)
		(duplicate_pad_numbers_are_jumpers no)
		(fp_rect
			(start -0.2794 0.6477)
			(end 0.2794 -0.6477)
			(stroke
				(width 0)
				(type default)
			)
			(fill no)
			(layer "F.CrtYd")
		)
		(fp_rect
			(start -0.2794 0.6477)
			(end 0.2794 -0.6477)
			(stroke
				(width 0)
				(type default)
			)
			(fill no)
			(layer "F.Fab")
		)
		(pad "1" smd custom
			(at 0 -0.2794 90)
			(size 0.0762 0.0762)
			(layers "F.Cu" "F.Mask" "F.Paste")
			(net "SAS_HDD_RX_P16")
			(options
				(clearance outline)
				(anchor circle)
			)
			(primitives
				(gr_poly
					(pts
						(arc
							(start 0.1524 -0.127)
							(mid 0.137521 -0.162921)
							(end 0.1016 -0.1778)
						)
						(arc
							(start -0.1016 -0.1778)
							(mid -0.137521 -0.162921)
							(end -0.1524 -0.127)
						)
						(arc
							(start -0.1524 0.127)
							(mid -0.137521 0.162921)
							(end -0.1016 0.1778)
						)
						(arc
							(start 0.1016 0.1778)
							(mid 0.137521 0.162921)
							(end 0.1524 0.127)
						)
					)
					(width 0)
					(fill yes)
				)
			)
		)
		(pad "2" smd custom
			(at 0 0.2794 90)
			(size 0.0762 0.0762)
			(layers "F.Cu" "F.Mask" "F.Paste")
			(net "PHY_SCC_B_TO_DRV_B_16_DP")
			(options
				(clearance outline)
				(anchor circle)
			)
			(primitives
				(gr_poly
					(pts
						(arc
							(start 0.1524 -0.127)
							(mid 0.137521 -0.162921)
							(end 0.1016 -0.1778)
						)
						(arc
							(start -0.1016 -0.1778)
							(mid -0.137521 -0.162921)
							(end -0.1524 -0.127)
						)
						(arc
							(start -0.1524 0.127)
							(mid -0.137521 0.162921)
							(end -0.1016 0.1778)
						)
						(arc
							(start 0.1016 0.1778)
							(mid 0.137521 0.162921)
							(end 0.1524 0.127)
						)
					)
					(width 0)
					(fill yes)
				)
			)
		)
	)
	(footprint ""
		(layer "F.Cu")
		(at 95.563436 -15.219426 90)
		(property "Reference" "C366"
			(at 0 0 90)
			(layer "F.SilkS")
			(hide yes)
			(effects
				(font
					(size 1.27 1.27)
				)
			)
		)
		(property "Value" "SCD01U16V1KX-GP"
			(at -2.8321 -1.7399 90)
			(unlocked yes)
			(layer "F.Fab")
			(hide yes)
			(effects
				(font
					(size 1.016 1.016)
					(thickness 0.1524)
				)
			)
		)
		(property "Device Type" "C0201H13"
			(at -2.8321 -3.2639 90)
			(unlocked yes)
			(layer "F.Fab")
			(hide yes)
			(effects
				(font
					(size 1.016 1.016)
					(thickness 0.1524)
				)
			)
		)
		(duplicate_pad_numbers_are_jumpers no)
		(fp_rect
			(start -0.2794 0.6477)
			(end 0.2794 -0.6477)
			(stroke
				(width 0)
				(type default)
			)
			(fill no)
			(layer "F.CrtYd")
		)
		(fp_rect
			(start -0.2794 0.6477)
			(end 0.2794 -0.6477)
			(stroke
				(width 0)
				(type default)
			)
			(fill no)
			(layer "F.Fab")
		)
		(pad "1" smd custom
			(at 0 -0.2794 90)
			(size 0.0762 0.0762)
			(layers "F.Cu" "F.Mask" "F.Paste")
			(net "SAS_HDD_RX_N26")
			(options
				(clearance outline)
				(anchor circle)
			)
			(primitives
				(gr_poly
					(pts
						(arc
							(start 0.1524 -0.127)
							(mid 0.137521 -0.162921)
							(end 0.1016 -0.1778)
						)
						(arc
							(start -0.1016 -0.1778)
							(mid -0.137521 -0.162921)
							(end -0.1524 -0.127)
						)
						(arc
							(start -0.1524 0.127)
							(mid -0.137521 0.162921)
							(end -0.1016 0.1778)
						)
						(arc
							(start 0.1016 0.1778)
							(mid 0.137521 0.162921)
							(end 0.1524 0.127)
						)
					)
					(width 0)
					(fill yes)
				)
			)
		)
		(pad "2" smd custom
			(at 0 0.2794 90)
			(size 0.0762 0.0762)
			(layers "F.Cu" "F.Mask" "F.Paste")
			(net "PHY_SCC_B_TO_DRV_B_26_DN")
			(options
				(clearance outline)
				(anchor circle)
			)
			(primitives
				(gr_poly
					(pts
						(arc
							(start 0.1524 -0.127)
							(mid 0.137521 -0.162921)
							(end 0.1016 -0.1778)
						)
						(arc
							(start -0.1016 -0.1778)
							(mid -0.137521 -0.162921)
							(end -0.1524 -0.127)
						)
						(arc
							(start -0.1524 0.127)
							(mid -0.137521 0.162921)
							(end -0.1016 0.1778)
						)
						(arc
							(start 0.1016 0.1778)
							(mid 0.137521 0.162921)
							(end 0.1524 0.127)
						)
					)
					(width 0)
					(fill yes)
				)
			)
		)
	)
	(footprint ""
		(layer "F.Cu")
		(at 333.629 -357.2256)
		(property "Reference" "D47"
			(at 0 0 0)
			(layer "F.SilkS")
			(hide yes)
			(effects
				(font
					(size 1.27 1.27)
				)
			)
		)
		(property "Value" "RB551V30-GP"
			(at 0 -6.7818 0)
			(unlocked yes)
			(layer "F.Fab")
			(hide yes)
			(effects
				(font
					(size 1.016 1.016)
					(thickness 0.1524)
				)
			)
		)
		(property "Device Type" "SOD323AKH38"
			(at 0 -8.6868 0)
			(unlocked yes)
			(layer "F.Fab")
			(hide yes)
			(effects
				(font
					(size 1.016 1.016)
					(thickness 0.1524)
				)
			)
		)
		(duplicate_pad_numbers_are_jumpers no)
		(fp_line
			(start -0.889 -1.9304)
			(end 0.889 -1.9304)
			(stroke
				(width 0.1524)
				(type default)
			)
			(layer "F.SilkS")
		)
		(fp_line
			(start -0.889 2.159)
			(end -0.889 -1.9304)
			(stroke
				(width 0.1524)
				(type default)
			)
			(layer "F.SilkS")
		)
		(fp_line
			(start 0.762 2.0574)
			(end -0.762 2.0574)
			(stroke
				(width 0.508)
				(type default)
			)
			(layer "F.SilkS")
		)
		(fp_line
			(start 0.889 -1.9304)
			(end 0.889 2.159)
			(stroke
				(width 0.1524)
				(type default)
			)
			(layer "F.SilkS")
		)
		(fp_line
			(start 0.889 2.159)
			(end -0.889 2.159)
			(stroke
				(width 0.1524)
				(type default)
			)
			(layer "F.SilkS")
		)
		(fp_rect
			(start -1.016 2.3114)
			(end 1.016 -2.0066)
			(stroke
				(width 0)
				(type default)
			)
			(fill no)
			(layer "F.CrtYd")
		)
		(fp_poly
			(pts
				(xy -1.016 -2.0066) (xy 1.016 -2.0066) (xy 1.016 2.3114) (xy -1.016 2.3114)
			)
			(stroke
				(width 0)
				(type default)
			)
			(fill no)
			(layer "F.Fab")
		)
		(pad "A" smd rect
			(at 0 -1.143)
			(size 0.5588 1.016)
			(layers "F.Cu" "F.Mask" "F.Paste")
			(net "GATE_FAN2")
		)
		(pad "K" smd rect
			(at 0 1.143)
			(size 0.5588 1.016)
			(layers "F.Cu" "F.Mask" "F.Paste")
			(net "GATE_FAN2_R")
		)
	)
	(footprint ""
		(layer "F.Cu")
		(at 17.800066 -180.399944)
		(property "Reference" "LED1"
			(at 0 0 0)
			(layer "F.SilkS")
			(hide yes)
			(effects
				(font
					(size 1.27 1.27)
				)
			)
		)
		(property "Value" "LED-BY-19-GP"
			(at -2.132076 1.414018 0)
			(unlocked yes)
			(layer "F.Fab")
			(hide yes)
			(effects
				(font
					(size 1.016 1.016)
					(thickness 0.1524)
				)
			)
		)
		(property "Device Type" "LED-1615-4PH26"
			(at -2.132076 -0.109982 0)
			(unlocked yes)
			(layer "F.Fab")
			(hide yes)
			(effects
				(font
					(size 1.016 1.016)
					(thickness 0.1524)
				)
			)
		)
		(duplicate_pad_numbers_are_jumpers no)
		(fp_line
			(start -1.2954 0.254)
			(end -1.2954 1.6002)
			(stroke
				(width 0.508)
				(type default)
			)
			(layer "F.SilkS")
		)
		(fp_line
			(start -1.2954 1.6002)
			(end 1.2954 1.6002)
			(stroke
				(width 0.508)
				(type default)
			)
			(layer "F.SilkS")
		)
		(fp_line
			(start -1.1176 -1.4224)
			(end 1.1176 -1.4224)
			(stroke
				(width 0.1524)
				(type default)
			)
			(layer "F.SilkS")
		)
		(fp_line
			(start -1.1176 1.4224)
			(end -1.1176 -1.4224)
			(stroke
				(width 0.1524)
				(type default)
			)
			(layer "F.SilkS")
		)
		(fp_line
			(start 1.1176 -1.4224)
			(end 1.1176 1.4224)
			(stroke
				(width 0.1524)
				(type default)
			)
			(layer "F.SilkS")
		)
		(fp_line
			(start 1.1176 1.4224)
			(end -1.1176 1.4224)
			(stroke
				(width 0.1524)
				(type default)
			)
			(layer "F.SilkS")
		)
		(fp_line
			(start 1.2954 1.6002)
			(end 1.2954 0.254)
			(stroke
				(width 0.508)
				(type default)
			)
			(layer "F.SilkS")
		)
		(fp_rect
			(start -0.7493 0.8001)
			(end 0.7493 -0.8001)
			(stroke
				(width 0)
				(type default)
			)
			(fill no)
			(layer "F.CrtYd")
		)
		(fp_poly
			(pts
				(xy -1.3716 1.6764) (xy -1.3716 -1.6764) (xy 1.3716 -1.6764) (xy 1.3716 0.0635) (xy 0.7493 0.0635)
				(xy 0.7493 -0.8001) (xy -0.7493 -0.8001) (xy -0.7493 0.8001) (xy 0.7493 0.8001) (xy 0.7493 0.0762)
				(xy 1.3716 0.0762) (xy 1.3716 1.6764)
			)
			(stroke
				(width 0)
				(type default)
			)
			(fill no)
			(layer "F.CrtYd")
		)
		(fp_rect
			(start -1.3716 1.6764)
			(end 1.3716 -1.6764)
			(stroke
				(width 0)
				(type default)
			)
			(fill no)
			(layer "F.Fab")
		)
		(pad "1" smd rect
			(at 0.50038 -0.73025)
			(size 0.7112 0.8636)
			(layers "F.Cu" "F.Mask" "F.Paste")
			(net "DRV_ACT_0")
		)
		(pad "2" smd rect
			(at -0.50038 -0.73025)
			(size 0.7112 0.8636)
			(layers "F.Cu" "F.Mask" "F.Paste")
			(net "FLT_HDD0")
		)
		(pad "3" smd rect
			(at 0.50038 0.73025)
			(size 0.7112 0.8636)
			(layers "F.Cu" "F.Mask" "F.Paste")
			(net "DRV_ACT_0_N")
		)
		(pad "4" smd rect
			(at -0.50038 0.73025)
			(size 0.7112 0.8636)
			(layers "F.Cu" "F.Mask" "F.Paste")
			(net "FLT_HDD0_N")
		)
	)
	(footprint ""
		(layer "F.Cu")
		(at 446.8622 -261.6454 180)
		(property "Reference" "R319"
			(at 0 0 180)
			(layer "F.SilkS")
			(hide yes)
			(effects
				(font
					(size 1.27 1.27)
				)
			)
		)
		(property "Value" "10KR2F-2-GP"
			(at 0.064008 -3.993896 180)
			(unlocked yes)
			(layer "F.Fab")
			(hide yes)
			(effects
				(font
					(size 1.016 1.016)
					(thickness 0.1524)
				)
			)
		)
		(property "Device Type" "R402H16"
			(at 0.064008 -5.517896 180)
			(unlocked yes)
			(layer "F.Fab")
			(hide yes)
			(effects
				(font
					(size 1.016 1.016)
					(thickness 0.1524)
				)
			)
		)
		(duplicate_pad_numbers_are_jumpers no)
		(fp_line
			(start 0.508 -0.9398)
			(end -0.508 -0.9398)
			(stroke
				(width 0.1524)
				(type default)
			)
			(layer "F.SilkS")
		)
		(fp_line
			(start -0.508 -0.9398)
			(end -0.508 0.9398)
			(stroke
				(width 0.1524)
				(type default)
			)
			(layer "F.SilkS")
		)
		(fp_rect
			(start -0.508 0.9398)
			(end 0.508 -0.9398)
			(stroke
				(width 0)
				(type default)
			)
			(fill no)
			(layer "F.CrtYd")
		)
		(fp_rect
			(start -0.508 0.9398)
			(end 0.508 -0.9398)
			(stroke
				(width 0)
				(type default)
			)
			(fill no)
			(layer "F.Fab")
		)
		(pad "1" smd custom
			(at 0 -0.4445 180)
			(size 0.1397 0.1397)
			(layers "F.Cu" "F.Mask" "F.Paste")
			(net "P3V3_STBY_B")
			(options
				(clearance outline)
				(anchor circle)
			)
			(primitives
				(gr_poly
					(pts
						(arc
							(start -0.1778 -0.2794)
							(mid -0.249642 -0.249642)
							(end -0.2794 -0.1778)
						)
						(arc
							(start -0.2794 0.1778)
							(mid -0.249642 0.249642)
							(end -0.1778 0.2794)
						)
						(arc
							(start 0.1778 0.2794)
							(mid 0.249642 0.249642)
							(end 0.2794 0.1778)
						)
						(arc
							(start 0.2794 -0.1778)
							(mid 0.249642 -0.249642)
							(end 0.1778 -0.2794)
						)
					)
					(width 0)
					(fill yes)
				)
			)
		)
		(pad "2" smd custom
			(at 0 0.4445 180)
			(size 0.1397 0.1397)
			(layers "F.Cu" "F.Mask" "F.Paste")
			(net "HDD_PRSNT_10")
			(options
				(clearance outline)
				(anchor circle)
			)
			(primitives
				(gr_poly
					(pts
						(arc
							(start -0.1778 -0.2794)
							(mid -0.249642 -0.249642)
							(end -0.2794 -0.1778)
						)
						(arc
							(start -0.2794 0.1778)
							(mid -0.249642 0.249642)
							(end -0.1778 0.2794)
						)
						(arc
							(start 0.1778 0.2794)
							(mid 0.249642 0.249642)
							(end 0.2794 0.1778)
						)
						(arc
							(start 0.2794 -0.1778)
							(mid 0.249642 -0.249642)
							(end 0.1778 -0.2794)
						)
					)
					(width 0)
					(fill yes)
				)
			)
		)
	)
	(footprint ""
		(layer "F.Cu")
		(at 14.859 -24.511 -90)
		(property "Reference" "R637"
			(at 0 0 270)
			(layer "F.SilkS")
			(hide yes)
			(effects
				(font
					(size 1.27 1.27)
				)
			)
		)
		(property "Value" "300KR2F-GP"
			(at 0.064008 -3.993896 270)
			(unlocked yes)
			(layer "F.Fab")
			(hide yes)
			(effects
				(font
					(size 1.016 1.016)
					(thickness 0.1524)
				)
			)
		)
		(property "Device Type" "R402H16"
			(at 0.064008 -5.517896 270)
			(unlocked yes)
			(layer "F.Fab")
			(hide yes)
			(effects
				(font
					(size 1.016 1.016)
					(thickness 0.1524)
				)
			)
		)
		(duplicate_pad_numbers_are_jumpers no)
		(fp_line
			(start -0.508 -0.9398)
			(end -0.508 0.9398)
			(stroke
				(width 0.1524)
				(type default)
			)
			(layer "F.SilkS")
		)
		(fp_line
			(start 0.508 -0.9398)
			(end -0.508 -0.9398)
			(stroke
				(width 0.1524)
				(type default)
			)
			(layer "F.SilkS")
		)
		(fp_rect
			(start -0.508 0.9398)
			(end 0.508 -0.9398)
			(stroke
				(width 0)
				(type default)
			)
			(fill no)
			(layer "F.CrtYd")
		)
		(fp_rect
			(start -0.508 0.9398)
			(end 0.508 -0.9398)
			(stroke
				(width 0)
				(type default)
			)
			(fill no)
			(layer "F.Fab")
		)
		(pad "1" smd custom
			(at 0 -0.4445 270)
			(size 0.1397 0.1397)
			(layers "F.Cu" "F.Mask" "F.Paste")
			(net "SW_HDD_N24")
			(options
				(clearance outline)
				(anchor circle)
			)
			(primitives
				(gr_poly
					(pts
						(arc
							(start -0.1778 -0.2794)
							(mid -0.249642 -0.249642)
							(end -0.2794 -0.1778)
						)
						(arc
							(start -0.2794 0.1778)
							(mid -0.249642 0.249642)
							(end -0.1778 0.2794)
						)
						(arc
							(start 0.1778 0.2794)
							(mid 0.249642 0.249642)
							(end 0.2794 0.1778)
						)
						(arc
							(start 0.2794 -0.1778)
							(mid 0.249642 -0.249642)
							(end 0.1778 -0.2794)
						)
					)
					(width 0)
					(fill yes)
				)
			)
		)
		(pad "2" smd custom
			(at 0 0.4445 270)
			(size 0.1397 0.1397)
			(layers "F.Cu" "F.Mask" "F.Paste")
			(net "P12V_B")
			(options
				(clearance outline)
				(anchor circle)
			)
			(primitives
				(gr_poly
					(pts
						(arc
							(start -0.1778 -0.2794)
							(mid -0.249642 -0.249642)
							(end -0.2794 -0.1778)
						)
						(arc
							(start -0.2794 0.1778)
							(mid -0.249642 0.249642)
							(end -0.1778 0.2794)
						)
						(arc
							(start 0.1778 0.2794)
							(mid 0.249642 0.249642)
							(end 0.2794 0.1778)
						)
						(arc
							(start 0.2794 -0.1778)
							(mid 0.249642 -0.249642)
							(end 0.1778 -0.2794)
						)
					)
					(width 0)
					(fill yes)
				)
			)
		)
	)
	(footprint ""
		(layer "F.Cu")
		(at 16.891 -132.588 180)
		(property "Reference" "D12"
			(at 0 0 180)
			(layer "F.SilkS")
			(hide yes)
			(effects
				(font
					(size 1.27 1.27)
				)
			)
		)
		(property "Value" "RB551V30-GP"
			(at 0 -6.7818 180)
			(unlocked yes)
			(layer "F.Fab")
			(hide yes)
			(effects
				(font
					(size 1.016 1.016)
					(thickness 0.1524)
				)
			)
		)
		(property "Device Type" "SOD323AKH38"
			(at 0 -8.6868 180)
			(unlocked yes)
			(layer "F.Fab")
			(hide yes)
			(effects
				(font
					(size 1.016 1.016)
					(thickness 0.1524)
				)
			)
		)
		(duplicate_pad_numbers_are_jumpers no)
		(fp_line
			(start 0.889 2.159)
			(end -0.889 2.159)
			(stroke
				(width 0.1524)
				(type default)
			)
			(layer "F.SilkS")
		)
		(fp_line
			(start 0.889 -1.9304)
			(end 0.889 2.159)
			(stroke
				(width 0.1524)
				(type default)
			)
			(layer "F.SilkS")
		)
		(fp_line
			(start 0.762 2.0574)
			(end -0.762 2.0574)
			(stroke
				(width 0.508)
				(type default)
			)
			(layer "F.SilkS")
		)
		(fp_line
			(start -0.889 2.159)
			(end -0.889 -1.9304)
			(stroke
				(width 0.1524)
				(type default)
			)
			(layer "F.SilkS")
		)
		(fp_line
			(start -0.889 -1.9304)
			(end 0.889 -1.9304)
			(stroke
				(width 0.1524)
				(type default)
			)
			(layer "F.SilkS")
		)
		(fp_rect
			(start -1.016 2.3114)
			(end 1.016 -2.0066)
			(stroke
				(width 0)
				(type default)
			)
			(fill no)
			(layer "F.CrtYd")
		)
		(fp_poly
			(pts
				(xy -1.016 -2.0066) (xy 1.016 -2.0066) (xy 1.016 2.3114) (xy -1.016 2.3114)
			)
			(stroke
				(width 0)
				(type default)
			)
			(fill no)
			(layer "F.Fab")
		)
		(pad "A" smd rect
			(at 0 -1.143 180)
			(size 0.5588 1.016)
			(layers "F.Cu" "F.Mask" "F.Paste")
			(net "SW_HDD_R12")
		)
		(pad "K" smd rect
			(at 0 1.143 180)
			(size 0.5588 1.016)
			(layers "F.Cu" "F.Mask" "F.Paste")
			(net "SW_HDD_N12")
		)
	)
	(footprint ""
		(layer "F.Cu")
		(at 284.000448 -347.541342 180)
		(property "Reference" "R1082"
			(at 0 0 180)
			(layer "F.SilkS")
			(hide yes)
			(effects
				(font
					(size 1.27 1.27)
				)
			)
		)
		(property "Value" "0R2J-2-GP"
			(at 0.064008 -3.993896 180)
			(unlocked yes)
			(layer "F.Fab")
			(hide yes)
			(effects
				(font
					(size 1.016 1.016)
					(thickness 0.1524)
				)
			)
		)
		(property "Device Type" "R402H16"
			(at 0.064008 -5.517896 180)
			(unlocked yes)
			(layer "F.Fab")
			(hide yes)
			(effects
				(font
					(size 1.016 1.016)
					(thickness 0.1524)
				)
			)
		)
		(duplicate_pad_numbers_are_jumpers no)
		(fp_line
			(start 0.508 -0.9398)
			(end -0.508 -0.9398)
			(stroke
				(width 0.1524)
				(type default)
			)
			(layer "F.SilkS")
		)
		(fp_line
			(start -0.508 -0.9398)
			(end -0.508 0.9398)
			(stroke
				(width 0.1524)
				(type default)
			)
			(layer "F.SilkS")
		)
		(fp_rect
			(start -0.508 0.9398)
			(end 0.508 -0.9398)
			(stroke
				(width 0)
				(type default)
			)
			(fill no)
			(layer "F.CrtYd")
		)
		(fp_rect
			(start -0.508 0.9398)
			(end 0.508 -0.9398)
			(stroke
				(width 0)
				(type default)
			)
			(fill no)
			(layer "F.Fab")
		)
		(pad "1" smd custom
			(at 0 -0.4445 180)
			(size 0.1397 0.1397)
			(layers "F.Cu" "F.Mask" "F.Paste")
			(net "GND")
			(options
				(clearance outline)
				(anchor circle)
			)
			(primitives
				(gr_poly
					(pts
						(arc
							(start -0.1778 -0.2794)
							(mid -0.249642 -0.249642)
							(end -0.2794 -0.1778)
						)
						(arc
							(start -0.2794 0.1778)
							(mid -0.249642 0.249642)
							(end -0.1778 0.2794)
						)
						(arc
							(start 0.1778 0.2794)
							(mid 0.249642 0.249642)
							(end 0.2794 0.1778)
						)
						(arc
							(start 0.2794 -0.1778)
							(mid 0.249642 -0.249642)
							(end 0.1778 -0.2794)
						)
					)
					(width 0)
					(fill yes)
				)
			)
		)
		(pad "2" smd custom
			(at 0 0.4445 180)
			(size 0.1397 0.1397)
			(layers "F.Cu" "F.Mask" "F.Paste")
			(net "MAX31790_B_SPIN_ST")
			(options
				(clearance outline)
				(anchor circle)
			)
			(primitives
				(gr_poly
					(pts
						(arc
							(start -0.1778 -0.2794)
							(mid -0.249642 -0.249642)
							(end -0.2794 -0.1778)
						)
						(arc
							(start -0.2794 0.1778)
							(mid -0.249642 0.249642)
							(end -0.1778 0.2794)
						)
						(arc
							(start 0.1778 0.2794)
							(mid 0.249642 0.249642)
							(end 0.2794 0.1778)
						)
						(arc
							(start 0.2794 -0.1778)
							(mid 0.249642 -0.249642)
							(end 0.1778 -0.2794)
						)
					)
					(width 0)
					(fill yes)
				)
			)
		)
	)
	(footprint ""
		(layer "F.Cu")
		(at 36.035996 -370.078 90)
		(property "Reference" "R924"
			(at 0 0 90)
			(layer "F.SilkS")
			(hide yes)
			(effects
				(font
					(size 1.27 1.27)
				)
			)
		)
		(property "Value" "27KR3F-GP"
			(at -0.0254 -2.5146 90)
			(unlocked yes)
			(layer "F.Fab")
			(hide yes)
			(effects
				(font
					(size 1.016 1.016)
					(thickness 0.1524)
				)
			)
		)
		(property "Device Type" "R603H22"
			(at -0.0254 -4.0386 90)
			(unlocked yes)
			(layer "F.Fab")
			(hide yes)
			(effects
				(font
					(size 1.016 1.016)
					(thickness 0.1524)
				)
			)
		)
		(duplicate_pad_numbers_are_jumpers no)
		(fp_line
			(start 0.2032 0)
			(end 0.4826 0)
			(stroke
				(width 0.2032)
				(type default)
			)
			(layer "F.SilkS")
		)
		(fp_line
			(start -0.4826 0)
			(end -0.2032 0)
			(stroke
				(width 0.2032)
				(type default)
			)
			(layer "F.SilkS")
		)
		(fp_rect
			(start -0.5842 1.3335)
			(end 0.5842 -1.3335)
			(stroke
				(width 0)
				(type default)
			)
			(fill no)
			(layer "F.CrtYd")
		)
		(fp_rect
			(start -0.5842 1.3335)
			(end 0.5842 -1.3335)
			(stroke
				(width 0)
				(type default)
			)
			(fill no)
			(layer "F.Fab")
		)
		(pad "1" smd custom
			(at 0 -0.762 90)
			(size 0.2159 0.2159)
			(layers "F.Cu" "F.Mask" "F.Paste")
			(net "FANTACH_R0")
			(options
				(clearance outline)
				(anchor circle)
			)
			(primitives
				(gr_poly
					(pts
						(arc
							(start -0.3302 -0.4318)
							(mid -0.402042 -0.402042)
							(end -0.4318 -0.3302)
						)
						(arc
							(start -0.4318 0.3302)
							(mid -0.402042 0.402042)
							(end -0.3302 0.4318)
						)
						(arc
							(start 0.3302 0.4318)
							(mid 0.402042 0.402042)
							(end 0.4318 0.3302)
						)
						(arc
							(start 0.4318 -0.3302)
							(mid 0.402042 -0.402042)
							(end 0.3302 -0.4318)
						)
					)
					(width 0)
					(fill yes)
				)
			)
		)
		(pad "2" smd custom
			(at 0 0.762 90)
			(size 0.2159 0.2159)
			(layers "F.Cu" "F.Mask" "F.Paste")
			(net "FAN_0_TACH0")
			(options
				(clearance outline)
				(anchor circle)
			)
			(primitives
				(gr_poly
					(pts
						(arc
							(start -0.3302 -0.4318)
							(mid -0.402042 -0.402042)
							(end -0.4318 -0.3302)
						)
						(arc
							(start -0.4318 0.3302)
							(mid -0.402042 0.402042)
							(end -0.3302 0.4318)
						)
						(arc
							(start 0.3302 0.4318)
							(mid 0.402042 0.402042)
							(end 0.4318 0.3302)
						)
						(arc
							(start 0.4318 -0.3302)
							(mid 0.402042 -0.402042)
							(end 0.3302 -0.4318)
						)
					)
					(width 0)
					(fill yes)
				)
			)
		)
	)
	(footprint ""
		(layer "F.Cu")
		(at 395.224 -243.586)
		(property "Reference" "R295"
			(at 0 0 0)
			(layer "F.SilkS")
			(hide yes)
			(effects
				(font
					(size 1.27 1.27)
				)
			)
		)
		(property "Value" "4K7R2F-GP"
			(at 0.064008 -3.993896 0)
			(unlocked yes)
			(layer "F.Fab")
			(hide yes)
			(effects
				(font
					(size 1.016 1.016)
					(thickness 0.1524)
				)
			)
		)
		(property "Device Type" "R402H16"
			(at 0.064008 -5.517896 0)
			(unlocked yes)
			(layer "F.Fab")
			(hide yes)
			(effects
				(font
					(size 1.016 1.016)
					(thickness 0.1524)
				)
			)
		)
		(duplicate_pad_numbers_are_jumpers no)
		(fp_line
			(start -0.508 -0.9398)
			(end -0.508 0.9398)
			(stroke
				(width 0.1524)
				(type default)
			)
			(layer "F.SilkS")
		)
		(fp_line
			(start 0.508 -0.9398)
			(end -0.508 -0.9398)
			(stroke
				(width 0.1524)
				(type default)
			)
			(layer "F.SilkS")
		)
		(fp_rect
			(start -0.508 0.9398)
			(end 0.508 -0.9398)
			(stroke
				(width 0)
				(type default)
			)
			(fill no)
			(layer "F.CrtYd")
		)
		(fp_rect
			(start -0.508 0.9398)
			(end 0.508 -0.9398)
			(stroke
				(width 0)
				(type default)
			)
			(fill no)
			(layer "F.Fab")
		)
		(pad "1" smd custom
			(at 0 -0.4445)
			(size 0.1397 0.1397)
			(layers "F.Cu" "F.Mask" "F.Paste")
			(net "SW_PWR_R_HDD8")
			(options
				(clearance outline)
				(anchor circle)
			)
			(primitives
				(gr_poly
					(pts
						(arc
							(start -0.1778 -0.2794)
							(mid -0.249642 -0.249642)
							(end -0.2794 -0.1778)
						)
						(arc
							(start -0.2794 0.1778)
							(mid -0.249642 0.249642)
							(end -0.1778 0.2794)
						)
						(arc
							(start 0.1778 0.2794)
							(mid 0.249642 0.249642)
							(end 0.2794 0.1778)
						)
						(arc
							(start 0.2794 -0.1778)
							(mid 0.249642 -0.249642)
							(end 0.1778 -0.2794)
						)
					)
					(width 0)
					(fill yes)
				)
			)
		)
		(pad "2" smd custom
			(at 0 0.4445)
			(size 0.1397 0.1397)
			(layers "F.Cu" "F.Mask" "F.Paste")
			(net "GND")
			(options
				(clearance outline)
				(anchor circle)
			)
			(primitives
				(gr_poly
					(pts
						(arc
							(start -0.1778 -0.2794)
							(mid -0.249642 -0.249642)
							(end -0.2794 -0.1778)
						)
						(arc
							(start -0.2794 0.1778)
							(mid -0.249642 0.249642)
							(end -0.1778 0.2794)
						)
						(arc
							(start 0.1778 0.2794)
							(mid 0.249642 0.249642)
							(end 0.2794 0.1778)
						)
						(arc
							(start 0.2794 -0.1778)
							(mid 0.249642 -0.249642)
							(end 0.1778 -0.2794)
						)
					)
					(width 0)
					(fill yes)
				)
			)
		)
	)
	(footprint ""
		(layer "F.Cu")
		(at 190.258954 -248.750074 -90)
		(property "Reference" "VIA12"
			(at 0 0 270)
			(layer "F.SilkS")
			(hide yes)
			(effects
				(font
					(size 1.27 1.27)
				)
			)
		)
		(property "Value" "100OHM-8L-2D36MM-L16-GP"
			(at -3.4036 -0.4572 270)
			(unlocked yes)
			(layer "F.Fab")
			(hide yes)
			(effects
				(font
					(size 1.016 1.016)
					(thickness 0.1524)
				)
			)
		)
		(property "Device Type" "VIA-PCIE-4P-427097"
			(at -3.4036 -1.9812 270)
			(unlocked yes)
			(layer "F.Fab")
			(hide yes)
			(effects
				(font
					(size 1.016 1.016)
					(thickness 0.1524)
				)
			)
		)
		(duplicate_pad_numbers_are_jumpers no)
		(fp_rect
			(start -2.1336 0.4826)
			(end 2.1336 -0.4826)
			(stroke
				(width 0)
				(type default)
			)
			(fill no)
			(layer "F.CrtYd")
		)
		(fp_rect
			(start -2.1336 0.4826)
			(end 2.1336 -0.4826)
			(stroke
				(width 0)
				(type default)
			)
			(fill no)
			(layer "F.Fab")
		)
		(pad "1" thru_hole circle
			(at -1.651 0 270)
			(size 0.508 0.508)
			(drill 0.254)
			(layers "*.Cu" "*.Mask")
			(remove_unused_layers no)
			(net "GND")
			(clearance 0.2286)
			(thermal_gap 0.2286)
		)
		(pad "2" thru_hole circle
			(at -0.635 0 270)
			(size 0.508 0.508)
			(drill 0.254)
			(layers "*.Cu" "*.Mask")
			(remove_unused_layers no)
			(net "PHY_DRV_B_TO_SCC_B_5_DP")
			(clearance 0.2286)
			(thermal_gap 0.2286)
		)
		(pad "3" thru_hole circle
			(at 0.635 0 270)
			(size 0.508 0.508)
			(drill 0.254)
			(layers "*.Cu" "*.Mask")
			(remove_unused_layers no)
			(net "PHY_DRV_B_TO_SCC_B_5_DN")
			(clearance 0.2286)
			(thermal_gap 0.2286)
		)
		(pad "4" thru_hole circle
			(at 1.651 0 270)
			(size 0.508 0.508)
			(drill 0.254)
			(layers "*.Cu" "*.Mask")
			(remove_unused_layers no)
			(net "GND")
			(clearance 0.2286)
			(thermal_gap 0.2286)
		)
	)
	(footprint ""
		(layer "F.Cu")
		(at 469.9 -145.796)
		(property "Reference" "Q114"
			(at 0 0 0)
			(layer "F.SilkS")
			(hide yes)
			(effects
				(font
					(size 1.27 1.27)
				)
			)
		)
		(property "Value" "AO4407AL-GP"
			(at -3.707384 -1.5367 0)
			(unlocked yes)
			(layer "F.Fab")
			(hide yes)
			(effects
				(font
					(size 1.016 1.016)
					(thickness 0.1524)
				)
			)
		)
		(property "Device Type" "SOIC8H69"
			(at -3.707384 -3.0607 0)
			(unlocked yes)
			(layer "F.Fab")
			(hide yes)
			(effects
				(font
					(size 1.016 1.016)
					(thickness 0.1524)
				)
			)
		)
		(duplicate_pad_numbers_are_jumpers no)
		(fp_line
			(start -2.7432 -1.4224)
			(end -2.7432 1.4224)
			(stroke
				(width 0.1524)
				(type default)
			)
			(layer "F.SilkS")
		)
		(fp_line
			(start -2.7432 1.4224)
			(end -2.6416 1.4224)
			(stroke
				(width 0.1524)
				(type default)
			)
			(layer "F.SilkS")
		)
		(fp_line
			(start -2.7432 1.4224)
			(end 2.1336 1.4224)
			(stroke
				(width 0.1524)
				(type default)
			)
			(layer "F.SilkS")
		)
		(fp_line
			(start -2.7178 -0.508)
			(end -2.1844 -0.0508)
			(stroke
				(width 0.1524)
				(type default)
			)
			(layer "F.SilkS")
		)
		(fp_line
			(start -2.6289 3.4417)
			(end -2.6289 1.4732)
			(stroke
				(width 0.381)
				(type default)
			)
			(layer "F.SilkS")
		)
		(fp_line
			(start -2.1844 -0.0508)
			(end -2.7178 0.508)
			(stroke
				(width 0.1524)
				(type default)
			)
			(layer "F.SilkS")
		)
		(fp_line
			(start 2.1336 -1.4224)
			(end -2.7432 -1.4224)
			(stroke
				(width 0.1524)
				(type default)
			)
			(layer "F.SilkS")
		)
		(fp_line
			(start 2.1336 1.4224)
			(end 2.1336 -1.4224)
			(stroke
				(width 0.1524)
				(type default)
			)
			(layer "F.SilkS")
		)
		(fp_poly
			(pts
				(xy -2.2098 -1.4224) (xy -2.2098 1.4224) (xy 2.2098 1.4224) (xy 2.2098 -1.4224)
			)
			(stroke
				(width 0)
				(type default)
			)
			(fill yes)
			(layer "F.SilkS")
		)
		(fp_rect
			(start -2.450084 2.999994)
			(end 2.450084 -2.999994)
			(stroke
				(width 0)
				(type default)
			)
			(fill no)
			(layer "F.CrtYd")
		)
		(fp_poly
			(pts
				(xy -2.8194 3.6322) (xy -2.8194 -3.6322) (xy 2.8194 -3.6322) (xy 2.8194 1.18364) (xy 2.450084 1.18364)
				(xy 2.450084 -2.999994) (xy -2.450084 -2.999994) (xy -2.450084 2.999994) (xy 2.450084 2.999994)
				(xy 2.450084 1.18618) (xy 2.8194 1.18618) (xy 2.8194 3.6322)
			)
			(stroke
				(width 0)
				(type default)
			)
			(fill no)
			(layer "F.CrtYd")
		)
		(fp_rect
			(start -2.8194 3.6322)
			(end 2.8194 -3.6322)
			(stroke
				(width 0)
				(type default)
			)
			(fill no)
			(layer "F.Fab")
		)
		(pad "1" smd rect
			(at -1.905 2.54)
			(size 0.635 1.651)
			(layers "F.Cu" "F.Mask" "F.Paste")
			(net "P12V_B")
		)
		(pad "2" smd rect
			(at -0.635 2.54)
			(size 0.635 1.651)
			(layers "F.Cu" "F.Mask" "F.Paste")
			(net "P12V_B")
		)
		(pad "3" smd rect
			(at 0.635 2.54)
			(size 0.635 1.651)
			(layers "F.Cu" "F.Mask" "F.Paste")
			(net "P12V_B")
		)
		(pad "4" smd rect
			(at 1.905 2.54)
			(size 0.635 1.651)
			(layers "F.Cu" "F.Mask" "F.Paste")
			(net "SW_HDD_N23")
		)
		(pad "5" smd rect
			(at 1.905 -2.54)
			(size 0.635 1.651)
			(layers "F.Cu" "F.Mask" "F.Paste")
			(net "P12V_HDD23")
		)
		(pad "6" smd rect
			(at 0.635 -2.54)
			(size 0.635 1.651)
			(layers "F.Cu" "F.Mask" "F.Paste")
			(net "P12V_HDD23")
		)
		(pad "7" smd rect
			(at -0.635 -2.54)
			(size 0.635 1.651)
			(layers "F.Cu" "F.Mask" "F.Paste")
			(net "P12V_HDD23")
		)
		(pad "8" smd rect
			(at -1.905 -2.54)
			(size 0.635 1.651)
			(layers "F.Cu" "F.Mask" "F.Paste")
			(net "P12V_HDD23")
		)
	)
	(footprint ""
		(layer "F.Cu")
		(at 426.1866 -19.558 90)
		(property "Reference" "R836"
			(at 0 0 90)
			(layer "F.SilkS")
			(hide yes)
			(effects
				(font
					(size 1.27 1.27)
				)
			)
		)
		(property "Value" "4K7R2J-2-GP"
			(at 0.064008 -3.993896 90)
			(unlocked yes)
			(layer "F.Fab")
			(hide yes)
			(effects
				(font
					(size 1.016 1.016)
					(thickness 0.1524)
				)
			)
		)
		(property "Device Type" "R402H16"
			(at 0.064008 -5.517896 90)
			(unlocked yes)
			(layer "F.Fab")
			(hide yes)
			(effects
				(font
					(size 1.016 1.016)
					(thickness 0.1524)
				)
			)
		)
		(duplicate_pad_numbers_are_jumpers no)
		(fp_line
			(start 0.508 -0.9398)
			(end -0.508 -0.9398)
			(stroke
				(width 0.1524)
				(type default)
			)
			(layer "F.SilkS")
		)
		(fp_line
			(start -0.508 -0.9398)
			(end -0.508 0.9398)
			(stroke
				(width 0.1524)
				(type default)
			)
			(layer "F.SilkS")
		)
		(fp_rect
			(start -0.508 0.9398)
			(end 0.508 -0.9398)
			(stroke
				(width 0)
				(type default)
			)
			(fill no)
			(layer "F.CrtYd")
		)
		(fp_rect
			(start -0.508 0.9398)
			(end 0.508 -0.9398)
			(stroke
				(width 0)
				(type default)
			)
			(fill no)
			(layer "F.Fab")
		)
		(pad "1" smd custom
			(at 0 -0.4445 90)
			(size 0.1397 0.1397)
			(layers "F.Cu" "F.Mask" "F.Paste")
			(net "P12V_B")
			(options
				(clearance outline)
				(anchor circle)
			)
			(primitives
				(gr_poly
					(pts
						(arc
							(start -0.1778 -0.2794)
							(mid -0.249642 -0.249642)
							(end -0.2794 -0.1778)
						)
						(arc
							(start -0.2794 0.1778)
							(mid -0.249642 0.249642)
							(end -0.1778 0.2794)
						)
						(arc
							(start 0.1778 0.2794)
							(mid 0.249642 0.249642)
							(end 0.2794 0.1778)
						)
						(arc
							(start 0.2794 -0.1778)
							(mid 0.249642 -0.249642)
							(end 0.1778 -0.2794)
						)
					)
					(width 0)
					(fill yes)
				)
			)
		)
		(pad "2" smd custom
			(at 0 0.4445 90)
			(size 0.1397 0.1397)
			(layers "F.Cu" "F.Mask" "F.Paste")
			(net "SW_HDD_P33")
			(options
				(clearance outline)
				(anchor circle)
			)
			(primitives
				(gr_poly
					(pts
						(arc
							(start -0.1778 -0.2794)
							(mid -0.249642 -0.249642)
							(end -0.2794 -0.1778)
						)
						(arc
							(start -0.2794 0.1778)
							(mid -0.249642 0.249642)
							(end -0.1778 0.2794)
						)
						(arc
							(start 0.1778 0.2794)
							(mid 0.249642 0.249642)
							(end 0.2794 0.1778)
						)
						(arc
							(start 0.2794 -0.1778)
							(mid 0.249642 -0.249642)
							(end 0.1778 -0.2794)
						)
					)
					(width 0)
					(fill yes)
				)
			)
		)
	)
	(footprint ""
		(layer "F.Cu")
		(at 331.0382 -17.5006 90)
		(property "Reference" "R767"
			(at 0 0 90)
			(layer "F.SilkS")
			(hide yes)
			(effects
				(font
					(size 1.27 1.27)
				)
			)
		)
		(property "Value" "4K7R2J-2-GP"
			(at 0.064008 -3.993896 90)
			(unlocked yes)
			(layer "F.Fab")
			(hide yes)
			(effects
				(font
					(size 1.016 1.016)
					(thickness 0.1524)
				)
			)
		)
		(property "Device Type" "R402H16"
			(at 0.064008 -5.517896 90)
			(unlocked yes)
			(layer "F.Fab")
			(hide yes)
			(effects
				(font
					(size 1.016 1.016)
					(thickness 0.1524)
				)
			)
		)
		(duplicate_pad_numbers_are_jumpers no)
		(fp_line
			(start 0.508 -0.9398)
			(end -0.508 -0.9398)
			(stroke
				(width 0.1524)
				(type default)
			)
			(layer "F.SilkS")
		)
		(fp_line
			(start -0.508 -0.9398)
			(end -0.508 0.9398)
			(stroke
				(width 0.1524)
				(type default)
			)
			(layer "F.SilkS")
		)
		(fp_rect
			(start -0.508 0.9398)
			(end 0.508 -0.9398)
			(stroke
				(width 0)
				(type default)
			)
			(fill no)
			(layer "F.CrtYd")
		)
		(fp_rect
			(start -0.508 0.9398)
			(end 0.508 -0.9398)
			(stroke
				(width 0)
				(type default)
			)
			(fill no)
			(layer "F.Fab")
		)
		(pad "1" smd custom
			(at 0 -0.4445 90)
			(size 0.1397 0.1397)
			(layers "F.Cu" "F.Mask" "F.Paste")
			(net "P12V_B")
			(options
				(clearance outline)
				(anchor circle)
			)
			(primitives
				(gr_poly
					(pts
						(arc
							(start -0.1778 -0.2794)
							(mid -0.249642 -0.249642)
							(end -0.2794 -0.1778)
						)
						(arc
							(start -0.2794 0.1778)
							(mid -0.249642 0.249642)
							(end -0.1778 0.2794)
						)
						(arc
							(start 0.1778 0.2794)
							(mid 0.249642 0.249642)
							(end 0.2794 0.1778)
						)
						(arc
							(start 0.2794 -0.1778)
							(mid 0.249642 -0.249642)
							(end 0.1778 -0.2794)
						)
					)
					(width 0)
					(fill yes)
				)
			)
		)
		(pad "2" smd custom
			(at 0 0.4445 90)
			(size 0.1397 0.1397)
			(layers "F.Cu" "F.Mask" "F.Paste")
			(net "SW_HDD_P30")
			(options
				(clearance outline)
				(anchor circle)
			)
			(primitives
				(gr_poly
					(pts
						(arc
							(start -0.1778 -0.2794)
							(mid -0.249642 -0.249642)
							(end -0.2794 -0.1778)
						)
						(arc
							(start -0.2794 0.1778)
							(mid -0.249642 0.249642)
							(end -0.1778 0.2794)
						)
						(arc
							(start 0.1778 0.2794)
							(mid 0.249642 0.249642)
							(end 0.2794 0.1778)
						)
						(arc
							(start 0.2794 -0.1778)
							(mid 0.249642 -0.249642)
							(end 0.1778 -0.2794)
						)
					)
					(width 0)
					(fill yes)
				)
			)
		)
	)
	(footprint ""
		(layer "F.Cu")
		(at 185.478928 -371.606826)
		(property "Reference" "R1302"
			(at 0 0 0)
			(layer "F.SilkS")
			(hide yes)
			(effects
				(font
					(size 1.27 1.27)
				)
			)
		)
		(property "Value" "4K7R2F-GP"
			(at 0.064008 -3.993896 0)
			(unlocked yes)
			(layer "F.Fab")
			(hide yes)
			(effects
				(font
					(size 1.016 1.016)
					(thickness 0.1524)
				)
			)
		)
		(property "Device Type" "R402H16"
			(at 0.064008 -5.517896 0)
			(unlocked yes)
			(layer "F.Fab")
			(hide yes)
			(effects
				(font
					(size 1.016 1.016)
					(thickness 0.1524)
				)
			)
		)
		(duplicate_pad_numbers_are_jumpers no)
		(fp_line
			(start -0.508 -0.9398)
			(end -0.508 0.9398)
			(stroke
				(width 0.1524)
				(type default)
			)
			(layer "F.SilkS")
		)
		(fp_line
			(start 0.508 -0.9398)
			(end -0.508 -0.9398)
			(stroke
				(width 0.1524)
				(type default)
			)
			(layer "F.SilkS")
		)
		(fp_rect
			(start -0.508 0.9398)
			(end 0.508 -0.9398)
			(stroke
				(width 0)
				(type default)
			)
			(fill no)
			(layer "F.CrtYd")
		)
		(fp_rect
			(start -0.508 0.9398)
			(end 0.508 -0.9398)
			(stroke
				(width 0)
				(type default)
			)
			(fill no)
			(layer "F.Fab")
		)
		(pad "1" smd custom
			(at 0 -0.4445)
			(size 0.1397 0.1397)
			(layers "F.Cu" "F.Mask" "F.Paste")
			(net "FAN_BLUE_LED1")
			(options
				(clearance outline)
				(anchor circle)
			)
			(primitives
				(gr_poly
					(pts
						(arc
							(start -0.1778 -0.2794)
							(mid -0.249642 -0.249642)
							(end -0.2794 -0.1778)
						)
						(arc
							(start -0.2794 0.1778)
							(mid -0.249642 0.249642)
							(end -0.1778 0.2794)
						)
						(arc
							(start 0.1778 0.2794)
							(mid 0.249642 0.249642)
							(end 0.2794 0.1778)
						)
						(arc
							(start 0.2794 -0.1778)
							(mid 0.249642 -0.249642)
							(end 0.1778 -0.2794)
						)
					)
					(width 0)
					(fill yes)
				)
			)
		)
		(pad "2" smd custom
			(at 0 0.4445)
			(size 0.1397 0.1397)
			(layers "F.Cu" "F.Mask" "F.Paste")
			(net "FAN_LED1_D")
			(options
				(clearance outline)
				(anchor circle)
			)
			(primitives
				(gr_poly
					(pts
						(arc
							(start -0.1778 -0.2794)
							(mid -0.249642 -0.249642)
							(end -0.2794 -0.1778)
						)
						(arc
							(start -0.2794 0.1778)
							(mid -0.249642 0.249642)
							(end -0.1778 0.2794)
						)
						(arc
							(start 0.1778 0.2794)
							(mid 0.249642 0.249642)
							(end 0.2794 0.1778)
						)
						(arc
							(start 0.2794 -0.1778)
							(mid 0.249642 -0.249642)
							(end 0.1778 -0.2794)
						)
					)
					(width 0)
					(fill yes)
				)
			)
		)
	)
	(footprint ""
		(layer "F.Cu")
		(at 457.553568 -99.950778 90)
		(property "Reference" "Q264"
			(at 0 0 90)
			(layer "F.SilkS")
			(hide yes)
			(effects
				(font
					(size 1.27 1.27)
				)
			)
		)
		(property "Value" "SSM3K324R-GP"
			(at 0.127 -8.9662 90)
			(unlocked yes)
			(layer "F.Fab")
			(hide yes)
			(effects
				(font
					(size 1.016 1.016)
					(thickness 0.1524)
				)
			)
		)
		(property "Device Type" "SOT23DGS2D4H35"
			(at 0.127 -10.4902 90)
			(unlocked yes)
			(layer "F.Fab")
			(hide yes)
			(effects
				(font
					(size 1.016 1.016)
					(thickness 0.1524)
				)
			)
		)
		(duplicate_pad_numbers_are_jumpers no)
		(fp_line
			(start 1.651 -1.778)
			(end -1.651 -1.778)
			(stroke
				(width 0.1524)
				(type default)
			)
			(layer "F.SilkS")
		)
		(fp_line
			(start -1.651 -1.778)
			(end -1.651 1.778)
			(stroke
				(width 0.1524)
				(type default)
			)
			(layer "F.SilkS")
		)
		(fp_line
			(start 1.651 1.778)
			(end 1.651 -1.778)
			(stroke
				(width 0.1524)
				(type default)
			)
			(layer "F.SilkS")
		)
		(fp_line
			(start -1.651 1.778)
			(end 1.651 1.778)
			(stroke
				(width 0.1524)
				(type default)
			)
			(layer "F.SilkS")
		)
		(fp_poly
			(pts
				(xy -1.778 1.8796) (xy -1.778 -1.8796) (xy 1.778 -1.8796) (xy 1.778 1.8796)
			)
			(stroke
				(width 0)
				(type default)
			)
			(fill no)
			(layer "F.CrtYd")
		)
		(fp_poly
			(pts
				(xy -1.778 1.8796) (xy -1.778 -1.8796) (xy 1.778 -1.8796) (xy 1.778 1.8796)
			)
			(stroke
				(width 0)
				(type default)
			)
			(fill no)
			(layer "F.Fab")
		)
		(pad "D" smd custom
			(at 0 -0.9525 90)
			(size 0.1905 0.1905)
			(layers "F.Cu" "F.Mask" "F.Paste")
			(net "DRV_ACT_23_N")
			(options
				(clearance outline)
				(anchor circle)
			)
			(primitives
				(gr_poly
					(pts
						(arc
							(start -0.1778 0.5715)
							(mid -0.321484 0.511984)
							(end -0.381 0.3683)
						)
						(arc
							(start -0.381 -0.3683)
							(mid -0.321484 -0.511984)
							(end -0.1778 -0.5715)
						)
						(arc
							(start 0.1778 -0.5715)
							(mid 0.321484 -0.511984)
							(end 0.381 -0.3683)
						)
						(arc
							(start 0.381 0.3683)
							(mid 0.321484 0.511984)
							(end 0.1778 0.5715)
						)
					)
					(width 0)
					(fill yes)
				)
			)
		)
		(pad "G" smd custom
			(at -0.98425 0.9525 90)
			(size 0.1905 0.1905)
			(layers "F.Cu" "F.Mask" "F.Paste")
			(net "DRIVE_B_23_ACT")
			(options
				(clearance outline)
				(anchor circle)
			)
			(primitives
				(gr_poly
					(pts
						(arc
							(start -0.1778 0.5715)
							(mid -0.321484 0.511984)
							(end -0.381 0.3683)
						)
						(arc
							(start -0.381 -0.3683)
							(mid -0.321484 -0.511984)
							(end -0.1778 -0.5715)
						)
						(arc
							(start 0.1778 -0.5715)
							(mid 0.321484 -0.511984)
							(end 0.381 -0.3683)
						)
						(arc
							(start 0.381 0.3683)
							(mid 0.321484 0.511984)
							(end 0.1778 0.5715)
						)
					)
					(width 0)
					(fill yes)
				)
			)
		)
		(pad "S" smd custom
			(at 0.98425 0.9525 90)
			(size 0.1905 0.1905)
			(layers "F.Cu" "F.Mask" "F.Paste")
			(net "GND")
			(options
				(clearance outline)
				(anchor circle)
			)
			(primitives
				(gr_poly
					(pts
						(arc
							(start -0.1778 0.5715)
							(mid -0.321484 0.511984)
							(end -0.381 0.3683)
						)
						(arc
							(start -0.381 -0.3683)
							(mid -0.321484 -0.511984)
							(end -0.1778 -0.5715)
						)
						(arc
							(start 0.1778 -0.5715)
							(mid 0.321484 -0.511984)
							(end 0.381 -0.3683)
						)
						(arc
							(start 0.381 0.3683)
							(mid 0.321484 0.511984)
							(end 0.1778 0.5715)
						)
					)
					(width 0)
					(fill yes)
				)
			)
		)
	)
	(footprint ""
		(layer "F.Cu")
		(at 431.546 -16.764 180)
		(property "Reference" "R842"
			(at 0 0 180)
			(layer "F.SilkS")
			(hide yes)
			(effects
				(font
					(size 1.27 1.27)
				)
			)
		)
		(property "Value" "4K7R2J-2-GP"
			(at 0.064008 -3.993896 180)
			(unlocked yes)
			(layer "F.Fab")
			(hide yes)
			(effects
				(font
					(size 1.016 1.016)
					(thickness 0.1524)
				)
			)
		)
		(property "Device Type" "R402H16"
			(at 0.064008 -5.517896 180)
			(unlocked yes)
			(layer "F.Fab")
			(hide yes)
			(effects
				(font
					(size 1.016 1.016)
					(thickness 0.1524)
				)
			)
		)
		(duplicate_pad_numbers_are_jumpers no)
		(fp_line
			(start 0.508 -0.9398)
			(end -0.508 -0.9398)
			(stroke
				(width 0.1524)
				(type default)
			)
			(layer "F.SilkS")
		)
		(fp_line
			(start -0.508 -0.9398)
			(end -0.508 0.9398)
			(stroke
				(width 0.1524)
				(type default)
			)
			(layer "F.SilkS")
		)
		(fp_rect
			(start -0.508 0.9398)
			(end 0.508 -0.9398)
			(stroke
				(width 0)
				(type default)
			)
			(fill no)
			(layer "F.CrtYd")
		)
		(fp_rect
			(start -0.508 0.9398)
			(end 0.508 -0.9398)
			(stroke
				(width 0)
				(type default)
			)
			(fill no)
			(layer "F.Fab")
		)
		(pad "1" smd custom
			(at 0 -0.4445 180)
			(size 0.1397 0.1397)
			(layers "F.Cu" "F.Mask" "F.Paste")
			(net "P12V_B")
			(options
				(clearance outline)
				(anchor circle)
			)
			(primitives
				(gr_poly
					(pts
						(arc
							(start -0.1778 -0.2794)
							(mid -0.249642 -0.249642)
							(end -0.2794 -0.1778)
						)
						(arc
							(start -0.2794 0.1778)
							(mid -0.249642 0.249642)
							(end -0.1778 0.2794)
						)
						(arc
							(start 0.1778 0.2794)
							(mid 0.249642 0.249642)
							(end 0.2794 0.1778)
						)
						(arc
							(start 0.2794 -0.1778)
							(mid 0.249642 -0.249642)
							(end 0.1778 -0.2794)
						)
					)
					(width 0)
					(fill yes)
				)
			)
		)
		(pad "2" smd custom
			(at 0 0.4445 180)
			(size 0.1397 0.1397)
			(layers "F.Cu" "F.Mask" "F.Paste")
			(net "SW_HDD_R33")
			(options
				(clearance outline)
				(anchor circle)
			)
			(primitives
				(gr_poly
					(pts
						(arc
							(start -0.1778 -0.2794)
							(mid -0.249642 -0.249642)
							(end -0.2794 -0.1778)
						)
						(arc
							(start -0.2794 0.1778)
							(mid -0.249642 0.249642)
							(end -0.1778 0.2794)
						)
						(arc
							(start 0.1778 0.2794)
							(mid 0.249642 0.249642)
							(end 0.2794 0.1778)
						)
						(arc
							(start 0.2794 -0.1778)
							(mid 0.249642 -0.249642)
							(end 0.1778 -0.2794)
						)
					)
					(width 0)
					(fill yes)
				)
			)
		)
	)
	(footprint ""
		(layer "F.Cu")
		(at 209.03946 -167.43426 -90)
		(property "Reference" "R53"
			(at 0 0 270)
			(layer "F.SilkS")
			(hide yes)
			(effects
				(font
					(size 1.27 1.27)
				)
			)
		)
		(property "Value" "4K7R2F-GP"
			(at 0.064008 -3.993896 270)
			(unlocked yes)
			(layer "F.Fab")
			(hide yes)
			(effects
				(font
					(size 1.016 1.016)
					(thickness 0.1524)
				)
			)
		)
		(property "Device Type" "R402H16"
			(at 0.064008 -5.517896 270)
			(unlocked yes)
			(layer "F.Fab")
			(hide yes)
			(effects
				(font
					(size 1.016 1.016)
					(thickness 0.1524)
				)
			)
		)
		(duplicate_pad_numbers_are_jumpers no)
		(fp_line
			(start -0.508 -0.9398)
			(end -0.508 0.9398)
			(stroke
				(width 0.1524)
				(type default)
			)
			(layer "F.SilkS")
		)
		(fp_line
			(start 0.508 -0.9398)
			(end -0.508 -0.9398)
			(stroke
				(width 0.1524)
				(type default)
			)
			(layer "F.SilkS")
		)
		(fp_rect
			(start -0.508 0.9398)
			(end 0.508 -0.9398)
			(stroke
				(width 0)
				(type default)
			)
			(fill no)
			(layer "F.CrtYd")
		)
		(fp_rect
			(start -0.508 0.9398)
			(end 0.508 -0.9398)
			(stroke
				(width 0)
				(type default)
			)
			(fill no)
			(layer "F.Fab")
		)
		(pad "1" smd custom
			(at 0 -0.4445 270)
			(size 0.1397 0.1397)
			(layers "F.Cu" "F.Mask" "F.Paste")
			(net "IO_EXP6_A0")
			(options
				(clearance outline)
				(anchor circle)
			)
			(primitives
				(gr_poly
					(pts
						(arc
							(start -0.1778 -0.2794)
							(mid -0.249642 -0.249642)
							(end -0.2794 -0.1778)
						)
						(arc
							(start -0.2794 0.1778)
							(mid -0.249642 0.249642)
							(end -0.1778 0.2794)
						)
						(arc
							(start 0.1778 0.2794)
							(mid 0.249642 0.249642)
							(end 0.2794 0.1778)
						)
						(arc
							(start 0.2794 -0.1778)
							(mid 0.249642 -0.249642)
							(end 0.1778 -0.2794)
						)
					)
					(width 0)
					(fill yes)
				)
			)
		)
		(pad "2" smd custom
			(at 0 0.4445 270)
			(size 0.1397 0.1397)
			(layers "F.Cu" "F.Mask" "F.Paste")
			(net "GND")
			(options
				(clearance outline)
				(anchor circle)
			)
			(primitives
				(gr_poly
					(pts
						(arc
							(start -0.1778 -0.2794)
							(mid -0.249642 -0.249642)
							(end -0.2794 -0.1778)
						)
						(arc
							(start -0.2794 0.1778)
							(mid -0.249642 0.249642)
							(end -0.1778 0.2794)
						)
						(arc
							(start 0.1778 0.2794)
							(mid 0.249642 0.249642)
							(end 0.2794 0.1778)
						)
						(arc
							(start 0.2794 -0.1778)
							(mid 0.249642 -0.249642)
							(end 0.1778 -0.2794)
						)
					)
					(width 0)
					(fill yes)
				)
			)
		)
	)
	(footprint ""
		(layer "F.Cu")
		(at 174.498 -253.111 90)
		(property "Reference" "R243"
			(at 0 0 90)
			(layer "F.SilkS")
			(hide yes)
			(effects
				(font
					(size 1.27 1.27)
				)
			)
		)
		(property "Value" "4K7R2J-2-GP"
			(at 0.064008 -3.993896 90)
			(unlocked yes)
			(layer "F.Fab")
			(hide yes)
			(effects
				(font
					(size 1.016 1.016)
					(thickness 0.1524)
				)
			)
		)
		(property "Device Type" "R402H16"
			(at 0.064008 -5.517896 90)
			(unlocked yes)
			(layer "F.Fab")
			(hide yes)
			(effects
				(font
					(size 1.016 1.016)
					(thickness 0.1524)
				)
			)
		)
		(duplicate_pad_numbers_are_jumpers no)
		(fp_line
			(start 0.508 -0.9398)
			(end -0.508 -0.9398)
			(stroke
				(width 0.1524)
				(type default)
			)
			(layer "F.SilkS")
		)
		(fp_line
			(start -0.508 -0.9398)
			(end -0.508 0.9398)
			(stroke
				(width 0.1524)
				(type default)
			)
			(layer "F.SilkS")
		)
		(fp_rect
			(start -0.508 0.9398)
			(end 0.508 -0.9398)
			(stroke
				(width 0)
				(type default)
			)
			(fill no)
			(layer "F.CrtYd")
		)
		(fp_rect
			(start -0.508 0.9398)
			(end 0.508 -0.9398)
			(stroke
				(width 0)
				(type default)
			)
			(fill no)
			(layer "F.Fab")
		)
		(pad "1" smd custom
			(at 0 -0.4445 90)
			(size 0.1397 0.1397)
			(layers "F.Cu" "F.Mask" "F.Paste")
			(net "P12V_B")
			(options
				(clearance outline)
				(anchor circle)
			)
			(primitives
				(gr_poly
					(pts
						(arc
							(start -0.1778 -0.2794)
							(mid -0.249642 -0.249642)
							(end -0.2794 -0.1778)
						)
						(arc
							(start -0.2794 0.1778)
							(mid -0.249642 0.249642)
							(end -0.1778 0.2794)
						)
						(arc
							(start 0.1778 0.2794)
							(mid 0.249642 0.249642)
							(end 0.2794 0.1778)
						)
						(arc
							(start 0.2794 -0.1778)
							(mid 0.249642 -0.249642)
							(end 0.1778 -0.2794)
						)
					)
					(width 0)
					(fill yes)
				)
			)
		)
		(pad "2" smd custom
			(at 0 0.4445 90)
			(size 0.1397 0.1397)
			(layers "F.Cu" "F.Mask" "F.Paste")
			(net "SW_HDD_P5")
			(options
				(clearance outline)
				(anchor circle)
			)
			(primitives
				(gr_poly
					(pts
						(arc
							(start -0.1778 -0.2794)
							(mid -0.249642 -0.249642)
							(end -0.2794 -0.1778)
						)
						(arc
							(start -0.2794 0.1778)
							(mid -0.249642 0.249642)
							(end -0.1778 0.2794)
						)
						(arc
							(start 0.1778 0.2794)
							(mid 0.249642 0.249642)
							(end 0.2794 0.1778)
						)
						(arc
							(start 0.2794 -0.1778)
							(mid 0.249642 -0.249642)
							(end 0.1778 -0.2794)
						)
					)
					(width 0)
					(fill yes)
				)
			)
		)
	)
	(footprint ""
		(layer "F.Cu")
		(at 336.931 -246.761 180)
		(property "Reference" "R264"
			(at 0 0 180)
			(layer "F.SilkS")
			(hide yes)
			(effects
				(font
					(size 1.27 1.27)
				)
			)
		)
		(property "Value" "4K7R2J-2-GP"
			(at 0.064008 -3.993896 180)
			(unlocked yes)
			(layer "F.Fab")
			(hide yes)
			(effects
				(font
					(size 1.016 1.016)
					(thickness 0.1524)
				)
			)
		)
		(property "Device Type" "R402H16"
			(at 0.064008 -5.517896 180)
			(unlocked yes)
			(layer "F.Fab")
			(hide yes)
			(effects
				(font
					(size 1.016 1.016)
					(thickness 0.1524)
				)
			)
		)
		(duplicate_pad_numbers_are_jumpers no)
		(fp_line
			(start 0.508 -0.9398)
			(end -0.508 -0.9398)
			(stroke
				(width 0.1524)
				(type default)
			)
			(layer "F.SilkS")
		)
		(fp_line
			(start -0.508 -0.9398)
			(end -0.508 0.9398)
			(stroke
				(width 0.1524)
				(type default)
			)
			(layer "F.SilkS")
		)
		(fp_rect
			(start -0.508 0.9398)
			(end 0.508 -0.9398)
			(stroke
				(width 0)
				(type default)
			)
			(fill no)
			(layer "F.CrtYd")
		)
		(fp_rect
			(start -0.508 0.9398)
			(end 0.508 -0.9398)
			(stroke
				(width 0)
				(type default)
			)
			(fill no)
			(layer "F.Fab")
		)
		(pad "1" smd custom
			(at 0 -0.4445 180)
			(size 0.1397 0.1397)
			(layers "F.Cu" "F.Mask" "F.Paste")
			(net "P12V_B")
			(options
				(clearance outline)
				(anchor circle)
			)
			(primitives
				(gr_poly
					(pts
						(arc
							(start -0.1778 -0.2794)
							(mid -0.249642 -0.249642)
							(end -0.2794 -0.1778)
						)
						(arc
							(start -0.2794 0.1778)
							(mid -0.249642 0.249642)
							(end -0.1778 0.2794)
						)
						(arc
							(start 0.1778 0.2794)
							(mid 0.249642 0.249642)
							(end 0.2794 0.1778)
						)
						(arc
							(start 0.2794 -0.1778)
							(mid 0.249642 -0.249642)
							(end 0.1778 -0.2794)
						)
					)
					(width 0)
					(fill yes)
				)
			)
		)
		(pad "2" smd custom
			(at 0 0.4445 180)
			(size 0.1397 0.1397)
			(layers "F.Cu" "F.Mask" "F.Paste")
			(net "SW_HDD_R6")
			(options
				(clearance outline)
				(anchor circle)
			)
			(primitives
				(gr_poly
					(pts
						(arc
							(start -0.1778 -0.2794)
							(mid -0.249642 -0.249642)
							(end -0.2794 -0.1778)
						)
						(arc
							(start -0.2794 0.1778)
							(mid -0.249642 0.249642)
							(end -0.1778 0.2794)
						)
						(arc
							(start 0.1778 0.2794)
							(mid 0.249642 0.249642)
							(end 0.2794 0.1778)
						)
						(arc
							(start 0.2794 -0.1778)
							(mid 0.249642 -0.249642)
							(end 0.1778 -0.2794)
						)
					)
					(width 0)
					(fill yes)
				)
			)
		)
	)
	(footprint ""
		(layer "F.Cu")
		(at 178.435 -141.224 180)
		(property "Reference" "Q75"
			(at 0 0 180)
			(layer "F.SilkS")
			(hide yes)
			(effects
				(font
					(size 1.27 1.27)
				)
			)
		)
		(property "Value" "AO4406AL-GP"
			(at -3.707384 -1.5367 180)
			(unlocked yes)
			(layer "F.Fab")
			(hide yes)
			(effects
				(font
					(size 1.016 1.016)
					(thickness 0.1524)
				)
			)
		)
		(property "Device Type" "SOIC8H69"
			(at -3.707384 -3.0607 180)
			(unlocked yes)
			(layer "F.Fab")
			(hide yes)
			(effects
				(font
					(size 1.016 1.016)
					(thickness 0.1524)
				)
			)
		)
		(duplicate_pad_numbers_are_jumpers no)
		(fp_line
			(start 2.1336 1.4224)
			(end 2.1336 -1.4224)
			(stroke
				(width 0.1524)
				(type default)
			)
			(layer "F.SilkS")
		)
		(fp_line
			(start 2.1336 -1.4224)
			(end -2.7432 -1.4224)
			(stroke
				(width 0.1524)
				(type default)
			)
			(layer "F.SilkS")
		)
		(fp_line
			(start -2.1844 -0.0508)
			(end -2.7178 0.508)
			(stroke
				(width 0.1524)
				(type default)
			)
			(layer "F.SilkS")
		)
		(fp_line
			(start -2.6289 3.4417)
			(end -2.6289 1.4732)
			(stroke
				(width 0.381)
				(type default)
			)
			(layer "F.SilkS")
		)
		(fp_line
			(start -2.7178 -0.508)
			(end -2.1844 -0.0508)
			(stroke
				(width 0.1524)
				(type default)
			)
			(layer "F.SilkS")
		)
		(fp_line
			(start -2.7432 1.4224)
			(end 2.1336 1.4224)
			(stroke
				(width 0.1524)
				(type default)
			)
			(layer "F.SilkS")
		)
		(fp_line
			(start -2.7432 1.4224)
			(end -2.6416 1.4224)
			(stroke
				(width 0.1524)
				(type default)
			)
			(layer "F.SilkS")
		)
		(fp_line
			(start -2.7432 -1.4224)
			(end -2.7432 1.4224)
			(stroke
				(width 0.1524)
				(type default)
			)
			(layer "F.SilkS")
		)
		(fp_poly
			(pts
				(xy -2.2098 -1.4224) (xy -2.2098 1.4224) (xy 2.2098 1.4224) (xy 2.2098 -1.4224)
			)
			(stroke
				(width 0)
				(type default)
			)
			(fill yes)
			(layer "F.SilkS")
		)
		(fp_rect
			(start -2.450084 2.999994)
			(end 2.450084 -2.999994)
			(stroke
				(width 0)
				(type default)
			)
			(fill no)
			(layer "F.CrtYd")
		)
		(fp_poly
			(pts
				(xy -2.8194 3.6322) (xy -2.8194 -3.6322) (xy 2.8194 -3.6322) (xy 2.8194 1.18364) (xy 2.450084 1.18364)
				(xy 2.450084 -2.999994) (xy -2.450084 -2.999994) (xy -2.450084 2.999994) (xy 2.450084 2.999994)
				(xy 2.450084 1.18618) (xy 2.8194 1.18618) (xy 2.8194 3.6322)
			)
			(stroke
				(width 0)
				(type default)
			)
			(fill no)
			(layer "F.CrtYd")
		)
		(fp_rect
			(start -2.8194 3.6322)
			(end 2.8194 -3.6322)
			(stroke
				(width 0)
				(type default)
			)
			(fill no)
			(layer "F.Fab")
		)
		(pad "1" smd rect
			(at -1.905 2.54 180)
			(size 0.635 1.651)
			(layers "F.Cu" "F.Mask" "F.Paste")
			(net "P5V_HDD17")
		)
		(pad "2" smd rect
			(at -0.635 2.54 180)
			(size 0.635 1.651)
			(layers "F.Cu" "F.Mask" "F.Paste")
			(net "P5V_HDD17")
		)
		(pad "3" smd rect
			(at 0.635 2.54 180)
			(size 0.635 1.651)
			(layers "F.Cu" "F.Mask" "F.Paste")
			(net "P5V_HDD17")
		)
		(pad "4" smd rect
			(at 1.905 2.54 180)
			(size 0.635 1.651)
			(layers "F.Cu" "F.Mask" "F.Paste")
			(net "SW_HDD_P17")
		)
		(pad "5" smd rect
			(at 1.905 -2.54 180)
			(size 0.635 1.651)
			(layers "F.Cu" "F.Mask" "F.Paste")
			(net "P5V_B_2")
		)
		(pad "6" smd rect
			(at 0.635 -2.54 180)
			(size 0.635 1.651)
			(layers "F.Cu" "F.Mask" "F.Paste")
			(net "P5V_B_2")
		)
		(pad "7" smd rect
			(at -0.635 -2.54 180)
			(size 0.635 1.651)
			(layers "F.Cu" "F.Mask" "F.Paste")
			(net "P5V_B_2")
		)
		(pad "8" smd rect
			(at -1.905 -2.54 180)
			(size 0.635 1.651)
			(layers "F.Cu" "F.Mask" "F.Paste")
			(net "P5V_B_2")
		)
	)
	(footprint ""
		(layer "F.Cu")
		(at 243.205 -215.265)
		(property "Reference" "R81"
			(at 0 0 0)
			(layer "F.SilkS")
			(hide yes)
			(effects
				(font
					(size 1.27 1.27)
				)
			)
		)
		(property "Value" "4K7R2F-GP"
			(at 0.064008 -3.993896 0)
			(unlocked yes)
			(layer "F.Fab")
			(hide yes)
			(effects
				(font
					(size 1.016 1.016)
					(thickness 0.1524)
				)
			)
		)
		(property "Device Type" "R402H16"
			(at 0.064008 -5.517896 0)
			(unlocked yes)
			(layer "F.Fab")
			(hide yes)
			(effects
				(font
					(size 1.016 1.016)
					(thickness 0.1524)
				)
			)
		)
		(duplicate_pad_numbers_are_jumpers no)
		(fp_line
			(start -0.508 -0.9398)
			(end -0.508 0.9398)
			(stroke
				(width 0.1524)
				(type default)
			)
			(layer "F.SilkS")
		)
		(fp_line
			(start 0.508 -0.9398)
			(end -0.508 -0.9398)
			(stroke
				(width 0.1524)
				(type default)
			)
			(layer "F.SilkS")
		)
		(fp_rect
			(start -0.508 0.9398)
			(end 0.508 -0.9398)
			(stroke
				(width 0)
				(type default)
			)
			(fill no)
			(layer "F.CrtYd")
		)
		(fp_rect
			(start -0.508 0.9398)
			(end 0.508 -0.9398)
			(stroke
				(width 0)
				(type default)
			)
			(fill no)
			(layer "F.Fab")
		)
		(pad "1" smd custom
			(at 0 -0.4445)
			(size 0.1397 0.1397)
			(layers "F.Cu" "F.Mask" "F.Paste")
			(net "IO_EXP3_A1")
			(options
				(clearance outline)
				(anchor circle)
			)
			(primitives
				(gr_poly
					(pts
						(arc
							(start -0.1778 -0.2794)
							(mid -0.249642 -0.249642)
							(end -0.2794 -0.1778)
						)
						(arc
							(start -0.2794 0.1778)
							(mid -0.249642 0.249642)
							(end -0.1778 0.2794)
						)
						(arc
							(start 0.1778 0.2794)
							(mid 0.249642 0.249642)
							(end 0.2794 0.1778)
						)
						(arc
							(start 0.2794 -0.1778)
							(mid 0.249642 -0.249642)
							(end 0.1778 -0.2794)
						)
					)
					(width 0)
					(fill yes)
				)
			)
		)
		(pad "2" smd custom
			(at 0 0.4445)
			(size 0.1397 0.1397)
			(layers "F.Cu" "F.Mask" "F.Paste")
			(net "GND")
			(options
				(clearance outline)
				(anchor circle)
			)
			(primitives
				(gr_poly
					(pts
						(arc
							(start -0.1778 -0.2794)
							(mid -0.249642 -0.249642)
							(end -0.2794 -0.1778)
						)
						(arc
							(start -0.2794 0.1778)
							(mid -0.249642 0.249642)
							(end -0.1778 0.2794)
						)
						(arc
							(start 0.1778 0.2794)
							(mid 0.249642 0.249642)
							(end 0.2794 0.1778)
						)
						(arc
							(start 0.2794 -0.1778)
							(mid 0.249642 -0.249642)
							(end 0.1778 -0.2794)
						)
					)
					(width 0)
					(fill yes)
				)
			)
		)
	)
	(footprint ""
		(layer "F.Cu")
		(at 458.0636 -13.2334)
		(property "Reference" "R137"
			(at 0 0 0)
			(layer "F.SilkS")
			(hide yes)
			(effects
				(font
					(size 1.27 1.27)
				)
			)
		)
		(property "Value" "0R2J-2-GP"
			(at 0.064008 -3.993896 0)
			(unlocked yes)
			(layer "F.Fab")
			(hide yes)
			(effects
				(font
					(size 1.016 1.016)
					(thickness 0.1524)
				)
			)
		)
		(property "Device Type" "R402H16"
			(at 0.064008 -5.517896 0)
			(unlocked yes)
			(layer "F.Fab")
			(hide yes)
			(effects
				(font
					(size 1.016 1.016)
					(thickness 0.1524)
				)
			)
		)
		(duplicate_pad_numbers_are_jumpers no)
		(fp_line
			(start -0.508 -0.9398)
			(end -0.508 0.9398)
			(stroke
				(width 0.1524)
				(type default)
			)
			(layer "F.SilkS")
		)
		(fp_line
			(start 0.508 -0.9398)
			(end -0.508 -0.9398)
			(stroke
				(width 0.1524)
				(type default)
			)
			(layer "F.SilkS")
		)
		(fp_rect
			(start -0.508 0.9398)
			(end 0.508 -0.9398)
			(stroke
				(width 0)
				(type default)
			)
			(fill no)
			(layer "F.CrtYd")
		)
		(fp_rect
			(start -0.508 0.9398)
			(end 0.508 -0.9398)
			(stroke
				(width 0)
				(type default)
			)
			(fill no)
			(layer "F.Fab")
		)
		(pad "1" smd custom
			(at 0 -0.4445)
			(size 0.1397 0.1397)
			(layers "F.Cu" "F.Mask" "F.Paste")
			(net "I2C_DPB_B_SCL_BUF")
			(options
				(clearance outline)
				(anchor circle)
			)
			(primitives
				(gr_poly
					(pts
						(arc
							(start -0.1778 -0.2794)
							(mid -0.249642 -0.249642)
							(end -0.2794 -0.1778)
						)
						(arc
							(start -0.2794 0.1778)
							(mid -0.249642 0.249642)
							(end -0.1778 0.2794)
						)
						(arc
							(start 0.1778 0.2794)
							(mid 0.249642 0.249642)
							(end 0.2794 0.1778)
						)
						(arc
							(start 0.2794 -0.1778)
							(mid 0.249642 -0.249642)
							(end 0.1778 -0.2794)
						)
					)
					(width 0)
					(fill yes)
				)
			)
		)
		(pad "2" smd custom
			(at 0 0.4445)
			(size 0.1397 0.1397)
			(layers "F.Cu" "F.Mask" "F.Paste")
			(net "TEMP2_SCL")
			(options
				(clearance outline)
				(anchor circle)
			)
			(primitives
				(gr_poly
					(pts
						(arc
							(start -0.1778 -0.2794)
							(mid -0.249642 -0.249642)
							(end -0.2794 -0.1778)
						)
						(arc
							(start -0.2794 0.1778)
							(mid -0.249642 0.249642)
							(end -0.1778 0.2794)
						)
						(arc
							(start 0.1778 0.2794)
							(mid 0.249642 0.249642)
							(end 0.2794 0.1778)
						)
						(arc
							(start 0.2794 -0.1778)
							(mid 0.249642 -0.249642)
							(end 0.1778 -0.2794)
						)
					)
					(width 0)
					(fill yes)
				)
			)
		)
	)
	(footprint ""
		(layer "F.Cu")
		(at 190.213488 -245.219474 90)
		(property "Reference" "C94"
			(at 0 0 90)
			(layer "F.SilkS")
			(hide yes)
			(effects
				(font
					(size 1.27 1.27)
				)
			)
		)
		(property "Value" "SCD01U16V1KX-GP"
			(at -2.8321 -1.7399 90)
			(unlocked yes)
			(layer "F.Fab")
			(hide yes)
			(effects
				(font
					(size 1.016 1.016)
					(thickness 0.1524)
				)
			)
		)
		(property "Device Type" "C0201H13"
			(at -2.8321 -3.2639 90)
			(unlocked yes)
			(layer "F.Fab")
			(hide yes)
			(effects
				(font
					(size 1.016 1.016)
					(thickness 0.1524)
				)
			)
		)
		(duplicate_pad_numbers_are_jumpers no)
		(fp_rect
			(start -0.2794 0.6477)
			(end 0.2794 -0.6477)
			(stroke
				(width 0)
				(type default)
			)
			(fill no)
			(layer "F.CrtYd")
		)
		(fp_rect
			(start -0.2794 0.6477)
			(end 0.2794 -0.6477)
			(stroke
				(width 0)
				(type default)
			)
			(fill no)
			(layer "F.Fab")
		)
		(pad "1" smd custom
			(at 0 -0.2794 90)
			(size 0.0762 0.0762)
			(layers "F.Cu" "F.Mask" "F.Paste")
			(net "SAS_HDD_RX_N5")
			(options
				(clearance outline)
				(anchor circle)
			)
			(primitives
				(gr_poly
					(pts
						(arc
							(start 0.1524 -0.127)
							(mid 0.137521 -0.162921)
							(end 0.1016 -0.1778)
						)
						(arc
							(start -0.1016 -0.1778)
							(mid -0.137521 -0.162921)
							(end -0.1524 -0.127)
						)
						(arc
							(start -0.1524 0.127)
							(mid -0.137521 0.162921)
							(end -0.1016 0.1778)
						)
						(arc
							(start 0.1016 0.1778)
							(mid 0.137521 0.162921)
							(end 0.1524 0.127)
						)
					)
					(width 0)
					(fill yes)
				)
			)
		)
		(pad "2" smd custom
			(at 0 0.2794 90)
			(size 0.0762 0.0762)
			(layers "F.Cu" "F.Mask" "F.Paste")
			(net "PHY_SCC_B_TO_DRV_B_5_DN")
			(options
				(clearance outline)
				(anchor circle)
			)
			(primitives
				(gr_poly
					(pts
						(arc
							(start 0.1524 -0.127)
							(mid 0.137521 -0.162921)
							(end 0.1016 -0.1778)
						)
						(arc
							(start -0.1016 -0.1778)
							(mid -0.137521 -0.162921)
							(end -0.1524 -0.127)
						)
						(arc
							(start -0.1524 0.127)
							(mid -0.137521 0.162921)
							(end -0.1016 0.1778)
						)
						(arc
							(start 0.1016 0.1778)
							(mid 0.137521 0.162921)
							(end 0.1524 0.127)
						)
					)
					(width 0)
					(fill yes)
				)
			)
		)
	)
	(footprint ""
		(layer "F.Cu")
		(at 161.925 -266.065 90)
		(property "Reference" "R225"
			(at 0 0 90)
			(layer "F.SilkS")
			(hide yes)
			(effects
				(font
					(size 1.27 1.27)
				)
			)
		)
		(property "Value" "220R3F-1-GP"
			(at -0.0254 -2.5146 90)
			(unlocked yes)
			(layer "F.Fab")
			(hide yes)
			(effects
				(font
					(size 1.016 1.016)
					(thickness 0.1524)
				)
			)
		)
		(property "Device Type" "R603H22"
			(at -0.0254 -4.0386 90)
			(unlocked yes)
			(layer "F.Fab")
			(hide yes)
			(effects
				(font
					(size 1.016 1.016)
					(thickness 0.1524)
				)
			)
		)
		(duplicate_pad_numbers_are_jumpers no)
		(fp_line
			(start 0.2032 0)
			(end 0.4826 0)
			(stroke
				(width 0.2032)
				(type default)
			)
			(layer "F.SilkS")
		)
		(fp_line
			(start -0.4826 0)
			(end -0.2032 0)
			(stroke
				(width 0.2032)
				(type default)
			)
			(layer "F.SilkS")
		)
		(fp_rect
			(start -0.5842 1.3335)
			(end 0.5842 -1.3335)
			(stroke
				(width 0)
				(type default)
			)
			(fill no)
			(layer "F.CrtYd")
		)
		(fp_rect
			(start -0.5842 1.3335)
			(end 0.5842 -1.3335)
			(stroke
				(width 0)
				(type default)
			)
			(fill no)
			(layer "F.Fab")
		)
		(pad "1" smd custom
			(at 0 -0.762 90)
			(size 0.2159 0.2159)
			(layers "F.Cu" "F.Mask" "F.Paste")
			(net "HDD_PRSNT_4")
			(options
				(clearance outline)
				(anchor circle)
			)
			(primitives
				(gr_poly
					(pts
						(arc
							(start -0.3302 -0.4318)
							(mid -0.402042 -0.402042)
							(end -0.4318 -0.3302)
						)
						(arc
							(start -0.4318 0.3302)
							(mid -0.402042 0.402042)
							(end -0.3302 0.4318)
						)
						(arc
							(start 0.3302 0.4318)
							(mid 0.402042 0.402042)
							(end 0.4318 0.3302)
						)
						(arc
							(start 0.4318 -0.3302)
							(mid 0.402042 -0.402042)
							(end 0.3302 -0.4318)
						)
					)
					(width 0)
					(fill yes)
				)
			)
		)
		(pad "2" smd custom
			(at 0 0.762 90)
			(size 0.2159 0.2159)
			(layers "F.Cu" "F.Mask" "F.Paste")
			(net "DRIVE_B_4_INS")
			(options
				(clearance outline)
				(anchor circle)
			)
			(primitives
				(gr_poly
					(pts
						(arc
							(start -0.3302 -0.4318)
							(mid -0.402042 -0.402042)
							(end -0.4318 -0.3302)
						)
						(arc
							(start -0.4318 0.3302)
							(mid -0.402042 0.402042)
							(end -0.3302 0.4318)
						)
						(arc
							(start 0.3302 0.4318)
							(mid 0.402042 0.402042)
							(end 0.4318 0.3302)
						)
						(arc
							(start 0.4318 -0.3302)
							(mid 0.402042 -0.402042)
							(end 0.3302 -0.4318)
						)
					)
					(width 0)
					(fill yes)
				)
			)
		)
	)
	(footprint ""
		(layer "F.Cu")
		(at 187.891928 -372.423436 90)
		(property "Reference" "R178"
			(at 0 0 90)
			(layer "F.SilkS")
			(hide yes)
			(effects
				(font
					(size 1.27 1.27)
				)
			)
		)
		(property "Value" "4K7R2F-GP"
			(at 0.064008 -3.993896 90)
			(unlocked yes)
			(layer "F.Fab")
			(hide yes)
			(effects
				(font
					(size 1.016 1.016)
					(thickness 0.1524)
				)
			)
		)
		(property "Device Type" "R402H16"
			(at 0.064008 -5.517896 90)
			(unlocked yes)
			(layer "F.Fab")
			(hide yes)
			(effects
				(font
					(size 1.016 1.016)
					(thickness 0.1524)
				)
			)
		)
		(duplicate_pad_numbers_are_jumpers no)
		(fp_line
			(start 0.508 -0.9398)
			(end -0.508 -0.9398)
			(stroke
				(width 0.1524)
				(type default)
			)
			(layer "F.SilkS")
		)
		(fp_line
			(start -0.508 -0.9398)
			(end -0.508 0.9398)
			(stroke
				(width 0.1524)
				(type default)
			)
			(layer "F.SilkS")
		)
		(fp_rect
			(start -0.508 0.9398)
			(end 0.508 -0.9398)
			(stroke
				(width 0)
				(type default)
			)
			(fill no)
			(layer "F.CrtYd")
		)
		(fp_rect
			(start -0.508 0.9398)
			(end 0.508 -0.9398)
			(stroke
				(width 0)
				(type default)
			)
			(fill no)
			(layer "F.Fab")
		)
		(pad "1" smd custom
			(at 0 -0.4445 90)
			(size 0.1397 0.1397)
			(layers "F.Cu" "F.Mask" "F.Paste")
			(net "FAN_BLUE_LED1")
			(options
				(clearance outline)
				(anchor circle)
			)
			(primitives
				(gr_poly
					(pts
						(arc
							(start -0.1778 -0.2794)
							(mid -0.249642 -0.249642)
							(end -0.2794 -0.1778)
						)
						(arc
							(start -0.2794 0.1778)
							(mid -0.249642 0.249642)
							(end -0.1778 0.2794)
						)
						(arc
							(start 0.1778 0.2794)
							(mid 0.249642 0.249642)
							(end 0.2794 0.1778)
						)
						(arc
							(start 0.2794 -0.1778)
							(mid 0.249642 -0.249642)
							(end 0.1778 -0.2794)
						)
					)
					(width 0)
					(fill yes)
				)
			)
		)
		(pad "2" smd custom
			(at 0 0.4445 90)
			(size 0.1397 0.1397)
			(layers "F.Cu" "F.Mask" "F.Paste")
			(net "P12V_IN")
			(options
				(clearance outline)
				(anchor circle)
			)
			(primitives
				(gr_poly
					(pts
						(arc
							(start -0.1778 -0.2794)
							(mid -0.249642 -0.249642)
							(end -0.2794 -0.1778)
						)
						(arc
							(start -0.2794 0.1778)
							(mid -0.249642 0.249642)
							(end -0.1778 0.2794)
						)
						(arc
							(start 0.1778 0.2794)
							(mid 0.249642 0.249642)
							(end 0.2794 0.1778)
						)
						(arc
							(start 0.2794 -0.1778)
							(mid 0.249642 -0.249642)
							(end 0.1778 -0.2794)
						)
					)
					(width 0)
					(fill yes)
				)
			)
		)
	)
	(footprint ""
		(layer "F.Cu")
		(at 117.602 -133.4262 -90)
		(property "Reference" "R423"
			(at 0 0 270)
			(layer "F.SilkS")
			(hide yes)
			(effects
				(font
					(size 1.27 1.27)
				)
			)
		)
		(property "Value" "1KR2F-3-GP"
			(at 0.064008 -3.993896 270)
			(unlocked yes)
			(layer "F.Fab")
			(hide yes)
			(effects
				(font
					(size 1.016 1.016)
					(thickness 0.1524)
				)
			)
		)
		(property "Device Type" "R402H16"
			(at 0.064008 -5.517896 270)
			(unlocked yes)
			(layer "F.Fab")
			(hide yes)
			(effects
				(font
					(size 1.016 1.016)
					(thickness 0.1524)
				)
			)
		)
		(duplicate_pad_numbers_are_jumpers no)
		(fp_line
			(start -0.508 -0.9398)
			(end -0.508 0.9398)
			(stroke
				(width 0.1524)
				(type default)
			)
			(layer "F.SilkS")
		)
		(fp_line
			(start 0.508 -0.9398)
			(end -0.508 -0.9398)
			(stroke
				(width 0.1524)
				(type default)
			)
			(layer "F.SilkS")
		)
		(fp_rect
			(start -0.508 0.9398)
			(end 0.508 -0.9398)
			(stroke
				(width 0)
				(type default)
			)
			(fill no)
			(layer "F.CrtYd")
		)
		(fp_rect
			(start -0.508 0.9398)
			(end 0.508 -0.9398)
			(stroke
				(width 0)
				(type default)
			)
			(fill no)
			(layer "F.Fab")
		)
		(pad "1" smd custom
			(at 0 -0.4445 270)
			(size 0.1397 0.1397)
			(layers "F.Cu" "F.Mask" "F.Paste")
			(net "P3V3_STBY_B")
			(options
				(clearance outline)
				(anchor circle)
			)
			(primitives
				(gr_poly
					(pts
						(arc
							(start -0.1778 -0.2794)
							(mid -0.249642 -0.249642)
							(end -0.2794 -0.1778)
						)
						(arc
							(start -0.2794 0.1778)
							(mid -0.249642 0.249642)
							(end -0.1778 0.2794)
						)
						(arc
							(start 0.1778 0.2794)
							(mid 0.249642 0.249642)
							(end 0.2794 0.1778)
						)
						(arc
							(start 0.2794 -0.1778)
							(mid 0.249642 -0.249642)
							(end 0.1778 -0.2794)
						)
					)
					(width 0)
					(fill yes)
				)
			)
		)
		(pad "2" smd custom
			(at 0 0.4445 270)
			(size 0.1397 0.1397)
			(layers "F.Cu" "F.Mask" "F.Paste")
			(net "SW_PWR_R_HDD15")
			(options
				(clearance outline)
				(anchor circle)
			)
			(primitives
				(gr_poly
					(pts
						(arc
							(start -0.1778 -0.2794)
							(mid -0.249642 -0.249642)
							(end -0.2794 -0.1778)
						)
						(arc
							(start -0.2794 0.1778)
							(mid -0.249642 0.249642)
							(end -0.1778 0.2794)
						)
						(arc
							(start 0.1778 0.2794)
							(mid 0.249642 0.249642)
							(end 0.2794 0.1778)
						)
						(arc
							(start 0.2794 -0.1778)
							(mid 0.249642 -0.249642)
							(end 0.1778 -0.2794)
						)
					)
					(width 0)
					(fill yes)
				)
			)
		)
	)
	(footprint ""
		(layer "F.Cu")
		(at 395.605 -10.16 180)
		(property "Reference" "R814"
			(at 0 0 180)
			(layer "F.SilkS")
			(hide yes)
			(effects
				(font
					(size 1.27 1.27)
				)
			)
		)
		(property "Value" "100KR2F-L1-GP"
			(at 0.064008 -3.993896 180)
			(unlocked yes)
			(layer "F.Fab")
			(hide yes)
			(effects
				(font
					(size 1.016 1.016)
					(thickness 0.1524)
				)
			)
		)
		(property "Device Type" "R402H16"
			(at 0.064008 -5.517896 180)
			(unlocked yes)
			(layer "F.Fab")
			(hide yes)
			(effects
				(font
					(size 1.016 1.016)
					(thickness 0.1524)
				)
			)
		)
		(duplicate_pad_numbers_are_jumpers no)
		(fp_line
			(start 0.508 -0.9398)
			(end -0.508 -0.9398)
			(stroke
				(width 0.1524)
				(type default)
			)
			(layer "F.SilkS")
		)
		(fp_line
			(start -0.508 -0.9398)
			(end -0.508 0.9398)
			(stroke
				(width 0.1524)
				(type default)
			)
			(layer "F.SilkS")
		)
		(fp_rect
			(start -0.508 0.9398)
			(end 0.508 -0.9398)
			(stroke
				(width 0)
				(type default)
			)
			(fill no)
			(layer "F.CrtYd")
		)
		(fp_rect
			(start -0.508 0.9398)
			(end 0.508 -0.9398)
			(stroke
				(width 0)
				(type default)
			)
			(fill no)
			(layer "F.Fab")
		)
		(pad "1" smd custom
			(at 0 -0.4445 180)
			(size 0.1397 0.1397)
			(layers "F.Cu" "F.Mask" "F.Paste")
			(net "P3V3_STBY_B")
			(options
				(clearance outline)
				(anchor circle)
			)
			(primitives
				(gr_poly
					(pts
						(arc
							(start -0.1778 -0.2794)
							(mid -0.249642 -0.249642)
							(end -0.2794 -0.1778)
						)
						(arc
							(start -0.2794 0.1778)
							(mid -0.249642 0.249642)
							(end -0.1778 0.2794)
						)
						(arc
							(start 0.1778 0.2794)
							(mid 0.249642 0.249642)
							(end 0.2794 0.1778)
						)
						(arc
							(start 0.2794 -0.1778)
							(mid 0.249642 -0.249642)
							(end 0.1778 -0.2794)
						)
					)
					(width 0)
					(fill yes)
				)
			)
		)
		(pad "2" smd custom
			(at 0 0.4445 180)
			(size 0.1397 0.1397)
			(layers "F.Cu" "F.Mask" "F.Paste")
			(net "SW_PWR_R_HDD32")
			(options
				(clearance outline)
				(anchor circle)
			)
			(primitives
				(gr_poly
					(pts
						(arc
							(start -0.1778 -0.2794)
							(mid -0.249642 -0.249642)
							(end -0.2794 -0.1778)
						)
						(arc
							(start -0.2794 0.1778)
							(mid -0.249642 0.249642)
							(end -0.1778 0.2794)
						)
						(arc
							(start 0.1778 0.2794)
							(mid 0.249642 0.249642)
							(end 0.2794 0.1778)
						)
						(arc
							(start 0.2794 -0.1778)
							(mid 0.249642 -0.249642)
							(end 0.1778 -0.2794)
						)
					)
					(width 0)
					(fill yes)
				)
			)
		)
	)
	(footprint ""
		(layer "F.Cu")
		(at 460.883 -7.3406 90)
		(property "Reference" "C31"
			(at 0 0 90)
			(layer "F.SilkS")
			(hide yes)
			(effects
				(font
					(size 1.27 1.27)
				)
			)
		)
		(property "Value" "SC1U16V3KX-5GP"
			(at 0 -2.8194 90)
			(unlocked yes)
			(layer "F.Fab")
			(hide yes)
			(effects
				(font
					(size 1.016 1.016)
					(thickness 0.1524)
				)
			)
		)
		(property "Device Type" "C603H36"
			(at 0 -4.3434 90)
			(unlocked yes)
			(layer "F.Fab")
			(hide yes)
			(effects
				(font
					(size 1.016 1.016)
					(thickness 0.1524)
				)
			)
		)
		(duplicate_pad_numbers_are_jumpers no)
		(fp_line
			(start 0.508 0)
			(end -0.508 0)
			(stroke
				(width 0.2032)
				(type default)
			)
			(layer "F.SilkS")
		)
		(fp_rect
			(start -0.5842 1.3335)
			(end 0.5842 -1.3335)
			(stroke
				(width 0)
				(type default)
			)
			(fill no)
			(layer "F.CrtYd")
		)
		(fp_rect
			(start -0.5842 1.3335)
			(end 0.5842 -1.3335)
			(stroke
				(width 0)
				(type default)
			)
			(fill no)
			(layer "F.Fab")
		)
		(pad "1" smd custom
			(at 0 -0.762 90)
			(size 0.2159 0.2159)
			(layers "F.Cu" "F.Mask" "F.Paste")
			(net "P3V3_STBY_B")
			(options
				(clearance outline)
				(anchor circle)
			)
			(primitives
				(gr_poly
					(pts
						(arc
							(start -0.3302 -0.4318)
							(mid -0.402042 -0.402042)
							(end -0.4318 -0.3302)
						)
						(arc
							(start -0.4318 0.3302)
							(mid -0.402042 0.402042)
							(end -0.3302 0.4318)
						)
						(arc
							(start 0.3302 0.4318)
							(mid 0.402042 0.402042)
							(end 0.4318 0.3302)
						)
						(arc
							(start 0.4318 -0.3302)
							(mid 0.402042 -0.402042)
							(end 0.3302 -0.4318)
						)
					)
					(width 0)
					(fill yes)
				)
			)
		)
		(pad "2" smd custom
			(at 0 0.762 90)
			(size 0.2159 0.2159)
			(layers "F.Cu" "F.Mask" "F.Paste")
			(net "GND")
			(options
				(clearance outline)
				(anchor circle)
			)
			(primitives
				(gr_poly
					(pts
						(arc
							(start -0.3302 -0.4318)
							(mid -0.402042 -0.402042)
							(end -0.4318 -0.3302)
						)
						(arc
							(start -0.4318 0.3302)
							(mid -0.402042 0.402042)
							(end -0.3302 0.4318)
						)
						(arc
							(start 0.3302 0.4318)
							(mid 0.402042 0.402042)
							(end 0.4318 0.3302)
						)
						(arc
							(start 0.4318 -0.3302)
							(mid 0.402042 -0.402042)
							(end 0.3302 -0.4318)
						)
					)
					(width 0)
					(fill yes)
				)
			)
		)
	)
	(footprint ""
		(layer "F.Cu")
		(at 458.722476 -221.58325 -90)
		(property "Reference" "R1143"
			(at 0 0 270)
			(layer "F.SilkS")
			(hide yes)
			(effects
				(font
					(size 1.27 1.27)
				)
			)
		)
		(property "Value" "3D01R5F-GP"
			(at 0 -8.9535 270)
			(unlocked yes)
			(layer "F.Fab")
			(hide yes)
			(effects
				(font
					(size 1.27 1.016)
					(thickness 0.1524)
				)
			)
		)
		(property "Device Type" "R805H24"
			(at 0 -10.6299 270)
			(unlocked yes)
			(layer "F.Fab")
			(hide yes)
			(effects
				(font
					(size 1.27 1.016)
					(thickness 0.1524)
				)
			)
		)
		(duplicate_pad_numbers_are_jumpers no)
		(fp_line
			(start -0.889 1.7018)
			(end 0.889 1.7018)
			(stroke
				(width 0.1524)
				(type default)
			)
			(layer "F.SilkS")
		)
		(fp_line
			(start 0.889 1.7018)
			(end 0.889 -0.508)
			(stroke
				(width 0.1524)
				(type default)
			)
			(layer "F.SilkS")
		)
		(fp_line
			(start -0.889 0.0762)
			(end -0.889 1.7018)
			(stroke
				(width 0.1524)
				(type default)
			)
			(layer "F.SilkS")
		)
		(fp_line
			(start -0.889 -1.7018)
			(end -0.889 0.2794)
			(stroke
				(width 0.1524)
				(type default)
			)
			(layer "F.SilkS")
		)
		(fp_line
			(start 0.889 -1.7018)
			(end 0.889 -0.381)
			(stroke
				(width 0.1524)
				(type default)
			)
			(layer "F.SilkS")
		)
		(fp_line
			(start 0.889 -1.7018)
			(end -0.889 -1.7018)
			(stroke
				(width 0.1524)
				(type default)
			)
			(layer "F.SilkS")
		)
		(fp_poly
			(pts
				(xy 0.9652 -1.778) (xy 0.9652 1.778) (xy -0.9652 1.778) (xy -0.9652 -1.778)
			)
			(stroke
				(width 0)
				(type default)
			)
			(fill no)
			(layer "F.CrtYd")
		)
		(fp_rect
			(start -0.9652 1.778)
			(end 0.9652 -1.778)
			(stroke
				(width 0)
				(type default)
			)
			(fill no)
			(layer "F.Fab")
		)
		(pad "1" smd rect
			(at 0 -0.9652 270)
			(size 1.397 1.143)
			(layers "F.Cu" "F.Mask" "F.Paste")
			(net "P5V_B_3_SNB")
		)
		(pad "2" smd rect
			(at 0 0.9652 270)
			(size 1.397 1.143)
			(layers "F.Cu" "F.Mask" "F.Paste")
			(net "GND")
		)
	)
	(footprint ""
		(layer "F.Cu")
		(at 287.83661 -144.694402 -90)
		(property "Reference" "PCIE1"
			(at 0 0 270)
			(layer "F.SilkS")
			(hide yes)
			(effects
				(font
					(size 1.27 1.27)
				)
			)
		)
		(property "Value" "AMP-CONN76-8R-5-GP"
			(at -8.9408 -15.1892 270)
			(unlocked yes)
			(layer "F.Fab")
			(hide yes)
			(effects
				(font
					(size 1.016 1.016)
					(thickness 0.1524)
				)
			)
		)
		(property "Device Type" "PREFIT-76P-165151H483"
			(at -8.9408 -16.7132 270)
			(unlocked yes)
			(layer "F.Fab")
			(hide yes)
			(effects
				(font
					(size 1.016 1.016)
					(thickness 0.1524)
				)
			)
		)
		(duplicate_pad_numbers_are_jumpers no)
		(fp_line
			(start -1.905 13.0048)
			(end -1.905 -2.6162)
			(stroke
				(width 0.1524)
				(type default)
			)
			(layer "F.SilkS")
		)
		(fp_line
			(start 15.0876 13.0048)
			(end -1.905 13.0048)
			(stroke
				(width 0.1524)
				(type default)
			)
			(layer "F.SilkS")
		)
		(fp_line
			(start 0.0508 -2.032)
			(end 1.1176 -2.032)
			(stroke
				(width 0.1524)
				(type default)
			)
			(layer "F.SilkS")
		)
		(fp_line
			(start 1.1176 -2.032)
			(end 1.1176 -2.6162)
			(stroke
				(width 0.1524)
				(type default)
			)
			(layer "F.SilkS")
		)
		(fp_line
			(start -1.905 -2.6162)
			(end 0.0508 -2.6162)
			(stroke
				(width 0.1524)
				(type default)
			)
			(layer "F.SilkS")
		)
		(fp_line
			(start 0.0508 -2.6162)
			(end 0.0508 -2.032)
			(stroke
				(width 0.1524)
				(type default)
			)
			(layer "F.SilkS")
		)
		(fp_line
			(start 1.1176 -2.6162)
			(end 0.0508 -2.6162)
			(stroke
				(width 0.1524)
				(type default)
			)
			(layer "F.SilkS")
		)
		(fp_line
			(start 1.1176 -2.6162)
			(end 15.0876 -2.6162)
			(stroke
				(width 0.1524)
				(type default)
			)
			(layer "F.SilkS")
		)
		(fp_line
			(start 15.0876 -2.6162)
			(end 15.0876 13.0048)
			(stroke
				(width 0.1524)
				(type default)
			)
			(layer "F.SilkS")
		)
		(fp_poly
			(pts
				(xy -1.905 13.0048) (xy -1.905 -0.00762) (xy -0.635 -0.00762) (xy -0.635 12.954) (xy 13.234924 12.954)
				(xy 13.234924 -2.1336) (xy 2.4892 -2.1336) (xy 2.4892 -0.735076) (xy -0.635 -0.735076) (xy -0.635 -0.01016)
				(xy -1.905 -0.01016) (xy -1.905 -2.6162) (xy 0.0508 -2.6162) (xy 0.0508 -2.032) (xy 1.1176 -2.032)
				(xy 1.1176 -2.6162) (xy 15.0876 -2.6162) (xy 15.0876 13.0048)
			)
			(stroke
				(width 0)
				(type default)
			)
			(fill yes)
			(layer "F.SilkS")
		)
		(fp_poly
			(pts
				(arc
					(start 0.3302 12.401804)
					(mid 0 12.732004)
					(end -0.3302 12.401804)
				)
				(arc
					(start -0.3302 11.639804)
					(mid 0 11.309604)
					(end 0.3302 11.639804)
				)
			)
			(stroke
				(width 0)
				(type default)
			)
			(fill yes)
			(layer "F.SilkS")
		)
		(fp_poly
			(pts
				(arc
					(start 2.130298 12.401804)
					(mid 1.800098 12.732004)
					(end 1.469898 12.401804)
				)
				(arc
					(start 1.469898 11.639804)
					(mid 1.800098 11.309604)
					(end 2.130298 11.639804)
				)
			)
			(stroke
				(width 0)
				(type default)
			)
			(fill yes)
			(layer "F.SilkS")
		)
		(fp_poly
			(pts
				(arc
					(start 3.930142 12.401804)
					(mid 3.599942 12.732004)
					(end 3.269742 12.401804)
				)
				(arc
					(start 3.269742 11.639804)
					(mid 3.599942 11.309604)
					(end 3.930142 11.639804)
				)
			)
			(stroke
				(width 0)
				(type default)
			)
			(fill yes)
			(layer "F.SilkS")
		)
		(fp_poly
			(pts
				(arc
					(start 5.73024 12.401804)
					(mid 5.40004 12.732004)
					(end 5.06984 12.401804)
				)
				(arc
					(start 5.06984 11.639804)
					(mid 5.40004 11.309604)
					(end 5.73024 11.639804)
				)
			)
			(stroke
				(width 0)
				(type default)
			)
			(fill yes)
			(layer "F.SilkS")
		)
		(fp_poly
			(pts
				(arc
					(start 7.530084 12.401804)
					(mid 7.199884 12.732004)
					(end 6.869684 12.401804)
				)
				(arc
					(start 6.869684 11.639804)
					(mid 7.199884 11.309604)
					(end 7.530084 11.639804)
				)
			)
			(stroke
				(width 0)
				(type default)
			)
			(fill yes)
			(layer "F.SilkS")
		)
		(fp_poly
			(pts
				(arc
					(start 9.330182 12.401804)
					(mid 8.999982 12.732004)
					(end 8.669782 12.401804)
				)
				(arc
					(start 8.669782 11.639804)
					(mid 8.999982 11.309604)
					(end 9.330182 11.639804)
				)
			)
			(stroke
				(width 0)
				(type default)
			)
			(fill yes)
			(layer "F.SilkS")
		)
		(fp_poly
			(pts
				(arc
					(start 11.130026 12.401804)
					(mid 10.799826 12.732004)
					(end 10.469626 12.401804)
				)
				(arc
					(start 10.469626 11.639804)
					(mid 10.799826 11.309604)
					(end 11.130026 11.639804)
				)
			)
			(stroke
				(width 0)
				(type default)
			)
			(fill yes)
			(layer "F.SilkS")
		)
		(fp_poly
			(pts
				(arc
					(start 12.930124 12.401804)
					(mid 12.599924 12.732004)
					(end 12.269724 12.401804)
				)
				(arc
					(start 12.269724 11.639804)
					(mid 12.599924 11.309604)
					(end 12.930124 11.639804)
				)
			)
			(stroke
				(width 0)
				(type default)
			)
			(fill yes)
			(layer "F.SilkS")
		)
		(fp_rect
			(start -5.3848 16.0782)
			(end 17.9832 -5.4864)
			(stroke
				(width 0)
				(type default)
			)
			(fill no)
			(layer "B.CrtYd")
		)
		(fp_rect
			(start -1.651 12.7508)
			(end 14.8336 -2.3622)
			(stroke
				(width 0)
				(type default)
			)
			(fill no)
			(layer "F.CrtYd")
		)
		(fp_poly
			(pts
				(xy -6.6548 17.7546) (xy -6.6548 -7.366) (xy 19.8374 -7.366) (xy 19.8374 0) (xy 15.3416 0) (xy 15.3416 -2.8702)
				(xy -2.159 -2.8702) (xy -2.159 13.2588) (xy 15.3416 13.2588) (xy 15.3416 0.0127) (xy 19.8374 0.0127)
				(xy 19.8374 17.7546)
			)
			(stroke
				(width 0)
				(type default)
			)
			(fill no)
			(layer "F.CrtYd")
		)
		(fp_poly
			(pts
				(xy -2.159 13.2588) (xy -2.159 -2.8702) (xy 15.3416 -2.8702) (xy 15.3416 0) (xy 14.8336 0) (xy 14.8336 -2.3622)
				(xy -1.651 -2.3622) (xy -1.651 12.7508) (xy 14.8336 12.7508) (xy 14.8336 0.0127) (xy 15.3416 0.0127)
				(xy 15.3416 13.2588)
			)
			(stroke
				(width 0)
				(type default)
			)
			(fill no)
			(layer "F.CrtYd")
		)
		(fp_rect
			(start -10.3886 21.082)
			(end 22.987 -10.4902)
			(stroke
				(width 0)
				(type default)
			)
			(fill no)
			(layer "B.Fab")
		)
		(fp_rect
			(start -5.3848 16.0782)
			(end 17.9832 -5.4864)
			(stroke
				(width 0)
				(type default)
			)
			(fill no)
			(layer "B.Fab")
		)
		(fp_rect
			(start -11.6586 22.7584)
			(end 24.8412 -12.3698)
			(stroke
				(width 0)
				(type default)
			)
			(fill no)
			(layer "F.Fab")
		)
		(fp_rect
			(start -6.6548 17.7546)
			(end 19.8374 -7.366)
			(stroke
				(width 0)
				(type default)
			)
			(fill no)
			(layer "F.Fab")
		)
		(fp_rect
			(start -2.159 13.2588)
			(end 15.3416 -2.8702)
			(stroke
				(width 0)
				(type default)
			)
			(fill no)
			(layer "F.Fab")
		)
		(fp_text user "Press Fit"
			(at 2.751836 -1.2573 270)
			(unlocked yes)
			(layer "F.SilkS")
			(effects
				(font
					(size 1.016 1.016)
					(thickness 0.1524)
				)
				(justify left)
			)
		)
		(fp_text user "Can not place BGA,CSP,Wave Solder Component"
			(at -18.7452 17.6403 270)
			(unlocked yes)
			(layer "B.Fab")
			(effects
				(font
					(size 1.016 1.016)
					(thickness 0.1524)
				)
				(justify left)
			)
		)
		(fp_text user "Can not place BGA,CSP,Wave Solder Component"
			(at -18.8468 20.0787 270)
			(unlocked yes)
			(layer "F.Fab")
			(effects
				(font
					(size 1.016 1.016)
					(thickness 0.1524)
				)
				(justify left)
			)
		)
		(fp_text user "High Limit 2mm"
			(at -1.4478 15.9512 270)
			(unlocked yes)
			(layer "F.Fab")
			(effects
				(font
					(size 1.016 1.016)
					(thickness 0.1524)
				)
				(justify left)
			)
		)
		(pad "A1" thru_hole circle
			(at 0 0 270)
			(size 0.762 0.762)
			(drill 0.359918)
			(layers "*.Cu" "*.Mask")
			(remove_unused_layers no)
			(net "PCIE_COMP_B_TO_SCC_B_0_DP")
			(clearance 0.1651)
			(thermal_gap 0.1651)
		)
		(pad "A2" thru_hole circle
			(at 1.800098 0.999998 270)
			(size 0.762 0.762)
			(drill 0.359918)
			(layers "*.Cu" "*.Mask")
			(remove_unused_layers no)
			(net "PCIE_COMP_B_TO_SCC_B_1_DP")
			(clearance 0.1651)
			(thermal_gap 0.1651)
		)
		(pad "A3" thru_hole circle
			(at 3.599942 0 270)
			(size 0.762 0.762)
			(drill 0.359918)
			(layers "*.Cu" "*.Mask")
			(remove_unused_layers no)
			(net "PCIE_COMP_B_TO_SCC_B_2_DP")
			(clearance 0.1651)
			(thermal_gap 0.1651)
		)
		(pad "A4" thru_hole circle
			(at 5.40004 0.999998 270)
			(size 0.762 0.762)
			(drill 0.359918)
			(layers "*.Cu" "*.Mask")
			(remove_unused_layers no)
			(net "PCIE_COMP_B_TO_SCC_B_3_DP")
			(clearance 0.1651)
			(thermal_gap 0.1651)
		)
		(pad "A5" thru_hole circle
			(at 7.199884 0 270)
			(size 0.762 0.762)
			(drill 0.359918)
			(layers "*.Cu" "*.Mask")
			(remove_unused_layers no)
			(net "PCIE_COMP_B_TO_SCC_B_4_DP")
			(clearance 0.1651)
			(thermal_gap 0.1651)
		)
		(pad "A6" thru_hole circle
			(at 8.999982 0.999998 270)
			(size 0.762 0.762)
			(drill 0.359918)
			(layers "*.Cu" "*.Mask")
			(remove_unused_layers no)
			(net "PCIE_COMP_B_TO_SCC_B_5_DP")
			(clearance 0.1651)
			(thermal_gap 0.1651)
		)
		(pad "A7" thru_hole circle
			(at 10.80008 0 270)
			(size 0.762 0.762)
			(drill 0.359918)
			(layers "*.Cu" "*.Mask")
			(remove_unused_layers no)
			(net "PCIE_COMP_B_TO_SCC_B_6_DP")
			(clearance 0.1651)
			(thermal_gap 0.1651)
		)
		(pad "A8" thru_hole circle
			(at 12.599924 0.999998 270)
			(size 0.762 0.762)
			(drill 0.359918)
			(layers "*.Cu" "*.Mask")
			(remove_unused_layers no)
			(net "PCIE_COMP_B_TO_SCC_B_7_DP")
			(clearance 0.1651)
			(thermal_gap 0.1651)
		)
		(pad "B1" thru_hole circle
			(at 0 1.400048 270)
			(size 0.762 0.762)
			(drill 0.359918)
			(layers "*.Cu" "*.Mask")
			(remove_unused_layers no)
			(net "PCIE_COMP_B_TO_SCC_B_0_DN")
			(clearance 0.1651)
			(thermal_gap 0.1651)
		)
		(pad "B2" thru_hole circle
			(at 1.800098 2.400046 270)
			(size 0.762 0.762)
			(drill 0.359918)
			(layers "*.Cu" "*.Mask")
			(remove_unused_layers no)
			(net "PCIE_COMP_B_TO_SCC_B_1_DN")
			(clearance 0.1651)
			(thermal_gap 0.1651)
		)
		(pad "B3" thru_hole circle
			(at 3.599942 1.400048 270)
			(size 0.762 0.762)
			(drill 0.359918)
			(layers "*.Cu" "*.Mask")
			(remove_unused_layers no)
			(net "PCIE_COMP_B_TO_SCC_B_2_DN")
			(clearance 0.1651)
			(thermal_gap 0.1651)
		)
		(pad "B4" thru_hole circle
			(at 5.40004 2.400046 270)
			(size 0.762 0.762)
			(drill 0.359918)
			(layers "*.Cu" "*.Mask")
			(remove_unused_layers no)
			(net "PCIE_COMP_B_TO_SCC_B_3_DN")
			(clearance 0.1651)
			(thermal_gap 0.1651)
		)
		(pad "B5" thru_hole circle
			(at 7.199884 1.400048 270)
			(size 0.762 0.762)
			(drill 0.359918)
			(layers "*.Cu" "*.Mask")
			(remove_unused_layers no)
			(net "PCIE_COMP_B_TO_SCC_B_4_DN")
			(clearance 0.1651)
			(thermal_gap 0.1651)
		)
		(pad "B6" thru_hole circle
			(at 8.999982 2.400046 270)
			(size 0.762 0.762)
			(drill 0.359918)
			(layers "*.Cu" "*.Mask")
			(remove_unused_layers no)
			(net "PCIE_COMP_B_TO_SCC_B_5_DN")
			(clearance 0.1651)
			(thermal_gap 0.1651)
		)
		(pad "B7" thru_hole circle
			(at 10.80008 1.400048 270)
			(size 0.762 0.762)
			(drill 0.359918)
			(layers "*.Cu" "*.Mask")
			(remove_unused_layers no)
			(net "PCIE_COMP_B_TO_SCC_B_6_DN")
			(clearance 0.1651)
			(thermal_gap 0.1651)
		)
		(pad "B8" thru_hole circle
			(at 12.599924 2.400046 270)
			(size 0.762 0.762)
			(drill 0.359918)
			(layers "*.Cu" "*.Mask")
			(remove_unused_layers no)
			(net "PCIE_COMP_B_TO_SCC_B_7_DN")
			(clearance 0.1651)
			(thermal_gap 0.1651)
		)
		(pad "C1" thru_hole circle
			(at 0 3.599942 270)
			(size 0.762 0.762)
			(drill 0.359918)
			(layers "*.Cu" "*.Mask")
			(remove_unused_layers no)
			(net "PCIE_COMP_B_TO_SCC_B_CLK_0_DP")
			(clearance 0.1651)
			(thermal_gap 0.1651)
		)
		(pad "C2" thru_hole circle
			(at 1.800098 4.59994 270)
			(size 0.762 0.762)
			(drill 0.359918)
			(layers "*.Cu" "*.Mask")
			(remove_unused_layers no)
			(net "I2C_BMC_A_EXP_B_SCL")
			(clearance 0.1651)
			(thermal_gap 0.1651)
		)
		(pad "C3" thru_hole circle
			(at 3.599942 3.599942 270)
			(size 0.762 0.762)
			(drill 0.359918)
			(layers "*.Cu" "*.Mask")
			(remove_unused_layers no)
			(net "I2C_SCC_B_SCL_BUF")
			(clearance 0.1651)
			(thermal_gap 0.1651)
		)
		(pad "C4" thru_hole circle
			(at 5.40004 4.59994 270)
			(size 0.762 0.762)
			(drill 0.359918)
			(layers "*.Cu" "*.Mask")
			(remove_unused_layers no)
			(net "COMP_B_EXP_B_SPARE_0")
			(clearance 0.1651)
			(thermal_gap 0.1651)
		)
		(pad "C5" thru_hole circle
			(at 7.199884 3.599942 270)
			(size 0.762 0.762)
			(drill 0.359918)
			(layers "*.Cu" "*.Mask")
			(remove_unused_layers no)
			(net "UART_IOC_B_TX")
			(clearance 0.1651)
			(thermal_gap 0.1651)
		)
		(pad "C6" thru_hole circle
			(at 8.999982 4.59994 270)
			(size 0.762 0.762)
			(drill 0.359918)
			(layers "*.Cu" "*.Mask")
			(remove_unused_layers no)
			(net "BMC_B_EXP_B_SPARE_0")
			(clearance 0.1651)
			(thermal_gap 0.1651)
		)
		(pad "C7" thru_hole circle
			(at 10.80008 3.599942 270)
			(size 0.762 0.762)
			(drill 0.359918)
			(layers "*.Cu" "*.Mask")
			(remove_unused_layers no)
			(net "PCIE_COMP_B_TO_SCC_B_RST_0")
			(clearance 0.1651)
			(thermal_gap 0.1651)
		)
		(pad "C8" thru_hole circle
			(at 12.599924 4.59994 270)
			(size 0.762 0.762)
			(drill 0.359918)
			(layers "*.Cu" "*.Mask")
			(remove_unused_layers no)
			(net "I2C_BMC_B_EXP_B_SCL")
			(clearance 0.1651)
			(thermal_gap 0.1651)
		)
		(pad "D1" thru_hole circle
			(at 0 4.99999 270)
			(size 0.762 0.762)
			(drill 0.359918)
			(layers "*.Cu" "*.Mask")
			(remove_unused_layers no)
			(net "PCIE_COMP_B_TO_SCC_B_CLK_0_DN")
			(clearance 0.1651)
			(thermal_gap 0.1651)
		)
		(pad "D2" thru_hole circle
			(at 1.800098 5.999988 270)
			(size 0.762 0.762)
			(drill 0.359918)
			(layers "*.Cu" "*.Mask")
			(remove_unused_layers no)
			(net "I2C_BMC_A_EXP_B_SDA")
			(clearance 0.1651)
			(thermal_gap 0.1651)
		)
		(pad "D3" thru_hole circle
			(at 3.599942 4.99999 270)
			(size 0.762 0.762)
			(drill 0.359918)
			(layers "*.Cu" "*.Mask")
			(remove_unused_layers no)
			(net "I2C_SCC_B_SDA_BUF")
			(clearance 0.1651)
			(thermal_gap 0.1651)
		)
		(pad "D4" thru_hole circle
			(at 5.40004 5.999988 270)
			(size 0.762 0.762)
			(drill 0.359918)
			(layers "*.Cu" "*.Mask")
			(remove_unused_layers no)
			(net "Net_15")
			(clearance 0.1651)
			(thermal_gap 0.1651)
		)
		(pad "D5" thru_hole circle
			(at 7.199884 4.99999 270)
			(size 0.762 0.762)
			(drill 0.359918)
			(layers "*.Cu" "*.Mask")
			(remove_unused_layers no)
			(net "UART_IOC_B_RX")
			(clearance 0.1651)
			(thermal_gap 0.1651)
		)
		(pad "D6" thru_hole circle
			(at 8.999982 5.999988 270)
			(size 0.762 0.762)
			(drill 0.359918)
			(layers "*.Cu" "*.Mask")
			(remove_unused_layers no)
			(net "BMC_B_EXP_B_SPARE_1")
			(clearance 0.1651)
			(thermal_gap 0.1651)
		)
		(pad "D7" thru_hole circle
			(at 10.80008 4.99999 270)
			(size 0.762 0.762)
			(drill 0.359918)
			(layers "*.Cu" "*.Mask")
			(remove_unused_layers no)
			(net "BMC_A_HEARTBEAT")
			(clearance 0.1651)
			(thermal_gap 0.1651)
		)
		(pad "D8" thru_hole circle
			(at 12.599924 5.999988 270)
			(size 0.762 0.762)
			(drill 0.359918)
			(layers "*.Cu" "*.Mask")
			(remove_unused_layers no)
			(net "I2C_BMC_B_EXP_B_SDA")
			(clearance 0.1651)
			(thermal_gap 0.1651)
		)
		(pad "E1" thru_hole circle
			(at 0 7.199884 270)
			(size 0.762 0.762)
			(drill 0.359918)
			(layers "*.Cu" "*.Mask")
			(remove_unused_layers no)
			(net "PCIE_SCC_B_TO_COMP_B_0_DP")
			(clearance 0.1651)
			(thermal_gap 0.1651)
		)
		(pad "E2" thru_hole circle
			(at 1.800098 8.199882 270)
			(size 0.762 0.762)
			(drill 0.359918)
			(layers "*.Cu" "*.Mask")
			(remove_unused_layers no)
			(net "PCIE_SCC_B_TO_COMP_B_1_DP")
			(clearance 0.1651)
			(thermal_gap 0.1651)
		)
		(pad "E3" thru_hole circle
			(at 3.599942 7.199884 270)
			(size 0.762 0.762)
			(drill 0.359918)
			(layers "*.Cu" "*.Mask")
			(remove_unused_layers no)
			(net "PCIE_SCC_B_TO_COMP_B_2_DP")
			(clearance 0.1651)
			(thermal_gap 0.1651)
		)
		(pad "E4" thru_hole circle
			(at 5.40004 8.199882 270)
			(size 0.762 0.762)
			(drill 0.359918)
			(layers "*.Cu" "*.Mask")
			(remove_unused_layers no)
			(net "PCIE_SCC_B_TO_COMP_B_3_DP")
			(clearance 0.1651)
			(thermal_gap 0.1651)
		)
		(pad "E5" thru_hole circle
			(at 7.199884 7.199884 270)
			(size 0.762 0.762)
			(drill 0.359918)
			(layers "*.Cu" "*.Mask")
			(remove_unused_layers no)
			(net "PCIE_SCC_B_TO_COMP_B_4_DP")
			(clearance 0.1651)
			(thermal_gap 0.1651)
		)
		(pad "E6" thru_hole circle
			(at 8.999982 8.199882 270)
			(size 0.762 0.762)
			(drill 0.359918)
			(layers "*.Cu" "*.Mask")
			(remove_unused_layers no)
			(net "PCIE_SCC_B_TO_COMP_B_5_DP")
			(clearance 0.1651)
			(thermal_gap 0.1651)
		)
		(pad "E7" thru_hole circle
			(at 10.80008 7.199884 270)
			(size 0.762 0.762)
			(drill 0.359918)
			(layers "*.Cu" "*.Mask")
			(remove_unused_layers no)
			(net "PCIE_SCC_B_TO_COMP_B_6_DP")
			(clearance 0.1651)
			(thermal_gap 0.1651)
		)
		(pad "E8" thru_hole circle
			(at 12.599924 8.199882 270)
			(size 0.762 0.762)
			(drill 0.359918)
			(layers "*.Cu" "*.Mask")
			(remove_unused_layers no)
			(net "PCIE_SCC_B_TO_COMP_B_7_DP")
			(clearance 0.1651)
			(thermal_gap 0.1651)
		)
		(pad "F1" thru_hole circle
			(at 0 8.599932 270)
			(size 0.762 0.762)
			(drill 0.359918)
			(layers "*.Cu" "*.Mask")
			(remove_unused_layers no)
			(net "PCIE_SCC_B_TO_COMP_B_0_DN")
			(clearance 0.1651)
			(thermal_gap 0.1651)
		)
		(pad "F2" thru_hole circle
			(at 1.800098 9.59993 270)
			(size 0.762 0.762)
			(drill 0.359918)
			(layers "*.Cu" "*.Mask")
			(remove_unused_layers no)
			(net "PCIE_SCC_B_TO_COMP_B_1_DN")
			(clearance 0.1651)
			(thermal_gap 0.1651)
		)
		(pad "F3" thru_hole circle
			(at 3.599942 8.599932 270)
			(size 0.762 0.762)
			(drill 0.359918)
			(layers "*.Cu" "*.Mask")
			(remove_unused_layers no)
			(net "PCIE_SCC_B_TO_COMP_B_2_DN")
			(clearance 0.1651)
			(thermal_gap 0.1651)
		)
		(pad "F4" thru_hole circle
			(at 5.40004 9.59993 270)
			(size 0.762 0.762)
			(drill 0.359918)
			(layers "*.Cu" "*.Mask")
			(remove_unused_layers no)
			(net "PCIE_SCC_B_TO_COMP_B_3_DN")
			(clearance 0.1651)
			(thermal_gap 0.1651)
		)
		(pad "F5" thru_hole circle
			(at 7.199884 8.599932 270)
			(size 0.762 0.762)
			(drill 0.359918)
			(layers "*.Cu" "*.Mask")
			(remove_unused_layers no)
			(net "PCIE_SCC_B_TO_COMP_B_4_DN")
			(clearance 0.1651)
			(thermal_gap 0.1651)
		)
		(pad "F6" thru_hole circle
			(at 8.999982 9.59993 270)
			(size 0.762 0.762)
			(drill 0.359918)
			(layers "*.Cu" "*.Mask")
			(remove_unused_layers no)
			(net "PCIE_SCC_B_TO_COMP_B_5_DN")
			(clearance 0.1651)
			(thermal_gap 0.1651)
		)
		(pad "F7" thru_hole circle
			(at 10.80008 8.599932 270)
			(size 0.762 0.762)
			(drill 0.359918)
			(layers "*.Cu" "*.Mask")
			(remove_unused_layers no)
			(net "PCIE_SCC_B_TO_COMP_B_6_DN")
			(clearance 0.1651)
			(thermal_gap 0.1651)
		)
		(pad "F8" thru_hole circle
			(at 12.599924 9.59993 270)
			(size 0.762 0.762)
			(drill 0.359918)
			(layers "*.Cu" "*.Mask")
			(remove_unused_layers no)
			(net "PCIE_SCC_B_TO_COMP_B_7_DN")
			(clearance 0.1651)
			(thermal_gap 0.1651)
		)
		(pad "GND1" thru_hole circle
			(at 0 2.500122 270)
			(size 0.762 0.762)
			(drill 0.359918)
			(layers "*.Cu" "*.Mask")
			(remove_unused_layers no)
			(net "GND")
			(clearance 0.1651)
			(thermal_gap 0.1651)
		)
		(pad "GND2" thru_hole circle
			(at 0 6.100064 270)
			(size 0.762 0.762)
			(drill 0.359918)
			(layers "*.Cu" "*.Mask")
			(remove_unused_layers no)
			(net "GND")
			(clearance 0.1651)
			(thermal_gap 0.1651)
		)
		(pad "GND3" thru_hole circle
			(at 0 9.700006 270)
			(size 0.762 0.762)
			(drill 0.359918)
			(layers "*.Cu" "*.Mask")
			(remove_unused_layers no)
			(net "GND")
			(clearance 0.1651)
			(thermal_gap 0.1651)
		)
		(pad "GND4" thru_hole circle
			(at 1.800098 -0.100076 270)
			(size 0.762 0.762)
			(drill 0.359918)
			(layers "*.Cu" "*.Mask")
			(remove_unused_layers no)
			(net "GND")
			(clearance 0.1651)
			(thermal_gap 0.1651)
		)
		(pad "GND5" thru_hole circle
			(at 1.800098 3.50012 270)
			(size 0.762 0.762)
			(drill 0.359918)
			(layers "*.Cu" "*.Mask")
			(remove_unused_layers no)
			(net "GND")
			(clearance 0.1651)
			(thermal_gap 0.1651)
		)
		(pad "GND6" thru_hole circle
			(at 1.800098 7.100062 270)
			(size 0.762 0.762)
			(drill 0.359918)
			(layers "*.Cu" "*.Mask")
			(remove_unused_layers no)
			(net "GND")
			(clearance 0.1651)
			(thermal_gap 0.1651)
		)
		(pad "GND7" thru_hole circle
			(at 1.800098 10.700004 270)
			(size 0.762 0.762)
			(drill 0.359918)
			(layers "*.Cu" "*.Mask")
			(remove_unused_layers no)
			(net "GND")
			(clearance 0.1651)
			(thermal_gap 0.1651)
		)
		(pad "GND8" thru_hole circle
			(at 3.599942 2.500122 270)
			(size 0.762 0.762)
			(drill 0.359918)
			(layers "*.Cu" "*.Mask")
			(remove_unused_layers no)
			(net "GND")
			(clearance 0.1651)
			(thermal_gap 0.1651)
		)
		(pad "GND9" thru_hole circle
			(at 3.599942 6.100064 270)
			(size 0.762 0.762)
			(drill 0.359918)
			(layers "*.Cu" "*.Mask")
			(remove_unused_layers no)
			(net "GND")
			(clearance 0.1651)
			(thermal_gap 0.1651)
		)
		(pad "GND10" thru_hole circle
			(at 3.599942 9.700006 270)
			(size 0.762 0.762)
			(drill 0.359918)
			(layers "*.Cu" "*.Mask")
			(remove_unused_layers no)
			(net "GND")
			(clearance 0.1651)
			(thermal_gap 0.1651)
		)
		(pad "GND11" thru_hole circle
			(at 5.40004 -0.100076 270)
			(size 0.762 0.762)
			(drill 0.359918)
			(layers "*.Cu" "*.Mask")
			(remove_unused_layers no)
			(net "GND")
			(clearance 0.1651)
			(thermal_gap 0.1651)
		)
		(pad "GND12" thru_hole circle
			(at 5.40004 3.50012 270)
			(size 0.762 0.762)
			(drill 0.359918)
			(layers "*.Cu" "*.Mask")
			(remove_unused_layers no)
			(net "GND")
			(clearance 0.1651)
			(thermal_gap 0.1651)
		)
		(pad "GND13" thru_hole circle
			(at 5.40004 7.100062 270)
			(size 0.762 0.762)
			(drill 0.359918)
			(layers "*.Cu" "*.Mask")
			(remove_unused_layers no)
			(net "GND")
			(clearance 0.1651)
			(thermal_gap 0.1651)
		)
		(pad "GND14" thru_hole circle
			(at 5.40004 10.700004 270)
			(size 0.762 0.762)
			(drill 0.359918)
			(layers "*.Cu" "*.Mask")
			(remove_unused_layers no)
			(net "GND")
			(clearance 0.1651)
			(thermal_gap 0.1651)
		)
		(pad "GND15" thru_hole circle
			(at 7.199884 2.500122 270)
			(size 0.762 0.762)
			(drill 0.359918)
			(layers "*.Cu" "*.Mask")
			(remove_unused_layers no)
			(net "GND")
			(clearance 0.1651)
			(thermal_gap 0.1651)
		)
		(pad "GND16" thru_hole circle
			(at 7.199884 6.100064 270)
			(size 0.762 0.762)
			(drill 0.359918)
			(layers "*.Cu" "*.Mask")
			(remove_unused_layers no)
			(net "GND")
			(clearance 0.1651)
			(thermal_gap 0.1651)
		)
		(pad "GND17" thru_hole circle
			(at 7.199884 9.700006 270)
			(size 0.762 0.762)
			(drill 0.359918)
			(layers "*.Cu" "*.Mask")
			(remove_unused_layers no)
			(net "GND")
			(clearance 0.1651)
			(thermal_gap 0.1651)
		)
		(pad "GND18" thru_hole circle
			(at 8.999982 -0.100076 270)
			(size 0.762 0.762)
			(drill 0.359918)
			(layers "*.Cu" "*.Mask")
			(remove_unused_layers no)
			(net "GND")
			(clearance 0.1651)
			(thermal_gap 0.1651)
		)
		(pad "GND19" thru_hole circle
			(at 8.999982 3.50012 270)
			(size 0.762 0.762)
			(drill 0.359918)
			(layers "*.Cu" "*.Mask")
			(remove_unused_layers no)
			(net "GND")
			(clearance 0.1651)
			(thermal_gap 0.1651)
		)
		(pad "GND20" thru_hole circle
			(at 8.999982 7.100062 270)
			(size 0.762 0.762)
			(drill 0.359918)
			(layers "*.Cu" "*.Mask")
			(remove_unused_layers no)
			(net "GND")
			(clearance 0.1651)
			(thermal_gap 0.1651)
		)
		(pad "GND21" thru_hole circle
			(at 8.999982 10.700004 270)
			(size 0.762 0.762)
			(drill 0.359918)
			(layers "*.Cu" "*.Mask")
			(remove_unused_layers no)
			(net "GND")
			(clearance 0.1651)
			(thermal_gap 0.1651)
		)
		(pad "GND22" thru_hole circle
			(at 10.80008 2.500122 270)
			(size 0.762 0.762)
			(drill 0.359918)
			(layers "*.Cu" "*.Mask")
			(remove_unused_layers no)
			(net "GND")
			(clearance 0.1651)
			(thermal_gap 0.1651)
		)
		(pad "GND23" thru_hole circle
			(at 10.80008 6.100064 270)
			(size 0.762 0.762)
			(drill 0.359918)
			(layers "*.Cu" "*.Mask")
			(remove_unused_layers no)
			(net "GND")
			(clearance 0.1651)
			(thermal_gap 0.1651)
		)
		(pad "GND24" thru_hole circle
			(at 10.80008 9.700006 270)
			(size 0.762 0.762)
			(drill 0.359918)
			(layers "*.Cu" "*.Mask")
			(remove_unused_layers no)
			(net "GND")
			(clearance 0.1651)
			(thermal_gap 0.1651)
		)
		(pad "GND25" thru_hole circle
			(at 12.599924 -0.100076 270)
			(size 0.762 0.762)
			(drill 0.359918)
			(layers "*.Cu" "*.Mask")
			(remove_unused_layers no)
			(net "GND")
			(clearance 0.1651)
			(thermal_gap 0.1651)
		)
		(pad "GND26" thru_hole circle
			(at 12.599924 3.50012 270)
			(size 0.762 0.762)
			(drill 0.359918)
			(layers "*.Cu" "*.Mask")
			(remove_unused_layers no)
			(net "GND")
			(clearance 0.1651)
			(thermal_gap 0.1651)
		)
		(pad "GND27" thru_hole circle
			(at 12.599924 7.100062 270)
			(size 0.762 0.762)
			(drill 0.359918)
			(layers "*.Cu" "*.Mask")
			(remove_unused_layers no)
			(net "GND")
			(clearance 0.1651)
			(thermal_gap 0.1651)
		)
		(pad "GND28" thru_hole circle
			(at 12.599924 10.700004 270)
			(size 0.762 0.762)
			(drill 0.359918)
			(layers "*.Cu" "*.Mask")
			(remove_unused_layers no)
			(net "GND")
			(clearance 0.1651)
			(thermal_gap 0.1651)
		)
	)
	(footprint ""
		(layer "F.Cu")
		(at 462.452212 -20.558506 -90)
		(property "Reference" "R869"
			(at 0 0 270)
			(layer "F.SilkS")
			(hide yes)
			(effects
				(font
					(size 1.27 1.27)
				)
			)
		)
		(property "Value" "0R2J-2-GP"
			(at 0.064008 -3.993896 270)
			(unlocked yes)
			(layer "F.Fab")
			(hide yes)
			(effects
				(font
					(size 1.016 1.016)
					(thickness 0.1524)
				)
			)
		)
		(property "Device Type" "R402H16"
			(at 0.064008 -5.517896 270)
			(unlocked yes)
			(layer "F.Fab")
			(hide yes)
			(effects
				(font
					(size 1.016 1.016)
					(thickness 0.1524)
				)
			)
		)
		(duplicate_pad_numbers_are_jumpers no)
		(fp_line
			(start -0.508 -0.9398)
			(end -0.508 0.9398)
			(stroke
				(width 0.1524)
				(type default)
			)
			(layer "F.SilkS")
		)
		(fp_line
			(start 0.508 -0.9398)
			(end -0.508 -0.9398)
			(stroke
				(width 0.1524)
				(type default)
			)
			(layer "F.SilkS")
		)
		(fp_rect
			(start -0.508 0.9398)
			(end 0.508 -0.9398)
			(stroke
				(width 0)
				(type default)
			)
			(fill no)
			(layer "F.CrtYd")
		)
		(fp_rect
			(start -0.508 0.9398)
			(end 0.508 -0.9398)
			(stroke
				(width 0)
				(type default)
			)
			(fill no)
			(layer "F.Fab")
		)
		(pad "1" smd custom
			(at 0 -0.4445 270)
			(size 0.1397 0.1397)
			(layers "F.Cu" "F.Mask" "F.Paste")
			(net "SW_HDD_G34")
			(options
				(clearance outline)
				(anchor circle)
			)
			(primitives
				(gr_poly
					(pts
						(arc
							(start -0.1778 -0.2794)
							(mid -0.249642 -0.249642)
							(end -0.2794 -0.1778)
						)
						(arc
							(start -0.2794 0.1778)
							(mid -0.249642 0.249642)
							(end -0.1778 0.2794)
						)
						(arc
							(start 0.1778 0.2794)
							(mid 0.249642 0.249642)
							(end 0.2794 0.1778)
						)
						(arc
							(start 0.2794 -0.1778)
							(mid 0.249642 -0.249642)
							(end 0.1778 -0.2794)
						)
					)
					(width 0)
					(fill yes)
				)
			)
		)
		(pad "2" smd custom
			(at 0 0.4445 270)
			(size 0.1397 0.1397)
			(layers "F.Cu" "F.Mask" "F.Paste")
			(net "SW_HDD_R34")
			(options
				(clearance outline)
				(anchor circle)
			)
			(primitives
				(gr_poly
					(pts
						(arc
							(start -0.1778 -0.2794)
							(mid -0.249642 -0.249642)
							(end -0.2794 -0.1778)
						)
						(arc
							(start -0.2794 0.1778)
							(mid -0.249642 0.249642)
							(end -0.1778 0.2794)
						)
						(arc
							(start 0.1778 0.2794)
							(mid 0.249642 0.249642)
							(end 0.2794 0.1778)
						)
						(arc
							(start 0.2794 -0.1778)
							(mid 0.249642 -0.249642)
							(end 0.1778 -0.2794)
						)
					)
					(width 0)
					(fill yes)
				)
			)
		)
	)
	(footprint ""
		(layer "F.Cu")
		(at 469.773 -150.622 -90)
		(property "Reference" "C333"
			(at 0 0 270)
			(layer "F.SilkS")
			(hide yes)
			(effects
				(font
					(size 1.27 1.27)
				)
			)
		)
		(property "Value" "SC4D7U25V5KX-1-GP"
			(at -0.0762 -6.1214 270)
			(unlocked yes)
			(layer "F.Fab")
			(hide yes)
			(effects
				(font
					(size 1.016 1.016)
					(thickness 0.1524)
				)
			)
		)
		(property "Device Type" "C805H58"
			(at -0.0762 -8.1534 270)
			(unlocked yes)
			(layer "F.Fab")
			(hide yes)
			(effects
				(font
					(size 1.016 1.016)
					(thickness 0.1524)
				)
			)
		)
		(duplicate_pad_numbers_are_jumpers no)
		(fp_line
			(start 0.635 0)
			(end -0.635 0)
			(stroke
				(width 0.508)
				(type default)
			)
			(layer "F.SilkS")
		)
		(fp_rect
			(start -0.9652 1.778)
			(end 0.9652 -1.778)
			(stroke
				(width 0)
				(type default)
			)
			(fill no)
			(layer "F.CrtYd")
		)
		(fp_poly
			(pts
				(xy -0.9652 -1.778) (xy 0.9652 -1.778) (xy 0.9652 1.778) (xy -0.9652 1.778)
			)
			(stroke
				(width 0)
				(type default)
			)
			(fill no)
			(layer "F.Fab")
		)
		(pad "1" smd rect
			(at 0 -0.9652 270)
			(size 1.397 1.143)
			(layers "F.Cu" "F.Mask" "F.Paste")
			(net "P12V_HDD23")
		)
		(pad "2" smd rect
			(at 0 0.9652 270)
			(size 1.397 1.143)
			(layers "F.Cu" "F.Mask" "F.Paste")
			(net "GND")
		)
	)
	(footprint ""
		(layer "F.Cu")
		(at 166.596568 -214.784178 90)
		(property "Reference" "Q248"
			(at 0 0 90)
			(layer "F.SilkS")
			(hide yes)
			(effects
				(font
					(size 1.27 1.27)
				)
			)
		)
		(property "Value" "SSM3K324R-GP"
			(at 0.127 -8.9662 90)
			(unlocked yes)
			(layer "F.Fab")
			(hide yes)
			(effects
				(font
					(size 1.016 1.016)
					(thickness 0.1524)
				)
			)
		)
		(property "Device Type" "SOT23DGS2D4H35"
			(at 0.127 -10.4902 90)
			(unlocked yes)
			(layer "F.Fab")
			(hide yes)
			(effects
				(font
					(size 1.016 1.016)
					(thickness 0.1524)
				)
			)
		)
		(duplicate_pad_numbers_are_jumpers no)
		(fp_line
			(start 1.651 -1.778)
			(end -1.651 -1.778)
			(stroke
				(width 0.1524)
				(type default)
			)
			(layer "F.SilkS")
		)
		(fp_line
			(start -1.651 -1.778)
			(end -1.651 1.778)
			(stroke
				(width 0.1524)
				(type default)
			)
			(layer "F.SilkS")
		)
		(fp_line
			(start 1.651 1.778)
			(end 1.651 -1.778)
			(stroke
				(width 0.1524)
				(type default)
			)
			(layer "F.SilkS")
		)
		(fp_line
			(start -1.651 1.778)
			(end 1.651 1.778)
			(stroke
				(width 0.1524)
				(type default)
			)
			(layer "F.SilkS")
		)
		(fp_poly
			(pts
				(xy -1.778 1.8796) (xy -1.778 -1.8796) (xy 1.778 -1.8796) (xy 1.778 1.8796)
			)
			(stroke
				(width 0)
				(type default)
			)
			(fill no)
			(layer "F.CrtYd")
		)
		(fp_poly
			(pts
				(xy -1.778 1.8796) (xy -1.778 -1.8796) (xy 1.778 -1.8796) (xy 1.778 1.8796)
			)
			(stroke
				(width 0)
				(type default)
			)
			(fill no)
			(layer "F.Fab")
		)
		(pad "D" smd custom
			(at 0 -0.9525 90)
			(size 0.1905 0.1905)
			(layers "F.Cu" "F.Mask" "F.Paste")
			(net "DRV_ACT_5_N")
			(options
				(clearance outline)
				(anchor circle)
			)
			(primitives
				(gr_poly
					(pts
						(arc
							(start -0.1778 0.5715)
							(mid -0.321484 0.511984)
							(end -0.381 0.3683)
						)
						(arc
							(start -0.381 -0.3683)
							(mid -0.321484 -0.511984)
							(end -0.1778 -0.5715)
						)
						(arc
							(start 0.1778 -0.5715)
							(mid 0.321484 -0.511984)
							(end 0.381 -0.3683)
						)
						(arc
							(start 0.381 0.3683)
							(mid 0.321484 0.511984)
							(end 0.1778 0.5715)
						)
					)
					(width 0)
					(fill yes)
				)
			)
		)
		(pad "G" smd custom
			(at -0.98425 0.9525 90)
			(size 0.1905 0.1905)
			(layers "F.Cu" "F.Mask" "F.Paste")
			(net "DRIVE_B_5_ACT")
			(options
				(clearance outline)
				(anchor circle)
			)
			(primitives
				(gr_poly
					(pts
						(arc
							(start -0.1778 0.5715)
							(mid -0.321484 0.511984)
							(end -0.381 0.3683)
						)
						(arc
							(start -0.381 -0.3683)
							(mid -0.321484 -0.511984)
							(end -0.1778 -0.5715)
						)
						(arc
							(start 0.1778 -0.5715)
							(mid 0.321484 -0.511984)
							(end 0.381 -0.3683)
						)
						(arc
							(start 0.381 0.3683)
							(mid 0.321484 0.511984)
							(end 0.1778 0.5715)
						)
					)
					(width 0)
					(fill yes)
				)
			)
		)
		(pad "S" smd custom
			(at 0.98425 0.9525 90)
			(size 0.1905 0.1905)
			(layers "F.Cu" "F.Mask" "F.Paste")
			(net "GND")
			(options
				(clearance outline)
				(anchor circle)
			)
			(primitives
				(gr_poly
					(pts
						(arc
							(start -0.1778 0.5715)
							(mid -0.321484 0.511984)
							(end -0.381 0.3683)
						)
						(arc
							(start -0.381 -0.3683)
							(mid -0.321484 -0.511984)
							(end -0.1778 -0.5715)
						)
						(arc
							(start 0.1778 -0.5715)
							(mid 0.321484 -0.511984)
							(end 0.381 -0.3683)
						)
						(arc
							(start 0.381 0.3683)
							(mid 0.321484 0.511984)
							(end 0.1778 0.5715)
						)
					)
					(width 0)
					(fill yes)
				)
			)
		)
	)
	(footprint ""
		(layer "F.Cu")
		(at 34.285682 -14.990826 90)
		(property "Reference" "VIA49"
			(at 0 0 90)
			(layer "F.SilkS")
			(hide yes)
			(effects
				(font
					(size 1.27 1.27)
				)
			)
		)
		(property "Value" "100OHM-8L-2D36MM-L18-GP"
			(at 3.8989 0.5715 90)
			(unlocked yes)
			(layer "F.Fab")
			(hide yes)
			(effects
				(font
					(size 1.016 1.016)
					(thickness 0.1524)
				)
			)
		)
		(property "Device Type" "VIA-PCIE-4P-414097"
			(at 3.8989 -0.9525 90)
			(unlocked yes)
			(layer "F.Fab")
			(hide yes)
			(effects
				(font
					(size 1.016 1.016)
					(thickness 0.1524)
				)
			)
		)
		(duplicate_pad_numbers_are_jumpers no)
		(fp_rect
			(start -2.0701 0.4826)
			(end 2.0701 -0.4826)
			(stroke
				(width 0)
				(type default)
			)
			(fill no)
			(layer "F.CrtYd")
		)
		(fp_rect
			(start -2.0701 0.4826)
			(end 2.0701 -0.4826)
			(stroke
				(width 0)
				(type default)
			)
			(fill no)
			(layer "F.Fab")
		)
		(pad "1" thru_hole circle
			(at -1.5875 0 90)
			(size 0.508 0.508)
			(drill 0.254)
			(layers "*.Cu" "*.Mask")
			(remove_unused_layers no)
			(net "GND")
			(clearance 0.2286)
			(thermal_gap 0.2286)
		)
		(pad "2" thru_hole circle
			(at -0.5715 0 90)
			(size 0.508 0.508)
			(drill 0.254)
			(layers "*.Cu" "*.Mask")
			(remove_unused_layers no)
			(net "PHY_SCC_B_TO_DRV_B_24_DP")
			(clearance 0.2286)
			(thermal_gap 0.2286)
		)
		(pad "3" thru_hole circle
			(at 0.5715 0 90)
			(size 0.508 0.508)
			(drill 0.254)
			(layers "*.Cu" "*.Mask")
			(remove_unused_layers no)
			(net "PHY_SCC_B_TO_DRV_B_24_DN")
			(clearance 0.2286)
			(thermal_gap 0.2286)
		)
		(pad "4" thru_hole circle
			(at 1.5875 0 90)
			(size 0.508 0.508)
			(drill 0.254)
			(layers "*.Cu" "*.Mask")
			(remove_unused_layers no)
			(net "GND")
			(clearance 0.2286)
			(thermal_gap 0.2286)
		)
	)
	(footprint ""
		(layer "F.Cu")
		(at 301.371 -225.044 -90)
		(property "Reference" "R6"
			(at 0 0 270)
			(layer "F.SilkS")
			(hide yes)
			(effects
				(font
					(size 1.27 1.27)
				)
			)
		)
		(property "Value" "10KR2F-2-GP"
			(at 0.064008 -3.993896 270)
			(unlocked yes)
			(layer "F.Fab")
			(hide yes)
			(effects
				(font
					(size 1.016 1.016)
					(thickness 0.1524)
				)
			)
		)
		(property "Device Type" "R402H16"
			(at 0.064008 -5.517896 270)
			(unlocked yes)
			(layer "F.Fab")
			(hide yes)
			(effects
				(font
					(size 1.016 1.016)
					(thickness 0.1524)
				)
			)
		)
		(duplicate_pad_numbers_are_jumpers no)
		(fp_line
			(start -0.508 -0.9398)
			(end -0.508 0.9398)
			(stroke
				(width 0.1524)
				(type default)
			)
			(layer "F.SilkS")
		)
		(fp_line
			(start 0.508 -0.9398)
			(end -0.508 -0.9398)
			(stroke
				(width 0.1524)
				(type default)
			)
			(layer "F.SilkS")
		)
		(fp_rect
			(start -0.508 0.9398)
			(end 0.508 -0.9398)
			(stroke
				(width 0)
				(type default)
			)
			(fill no)
			(layer "F.CrtYd")
		)
		(fp_rect
			(start -0.508 0.9398)
			(end 0.508 -0.9398)
			(stroke
				(width 0)
				(type default)
			)
			(fill no)
			(layer "F.Fab")
		)
		(pad "1" smd custom
			(at 0 -0.4445 270)
			(size 0.1397 0.1397)
			(layers "F.Cu" "F.Mask" "F.Paste")
			(net "P3V3_STBY_B")
			(options
				(clearance outline)
				(anchor circle)
			)
			(primitives
				(gr_poly
					(pts
						(arc
							(start -0.1778 -0.2794)
							(mid -0.249642 -0.249642)
							(end -0.2794 -0.1778)
						)
						(arc
							(start -0.2794 0.1778)
							(mid -0.249642 0.249642)
							(end -0.1778 0.2794)
						)
						(arc
							(start 0.1778 0.2794)
							(mid 0.249642 0.249642)
							(end 0.2794 0.1778)
						)
						(arc
							(start 0.2794 -0.1778)
							(mid 0.249642 -0.249642)
							(end 0.1778 -0.2794)
						)
					)
					(width 0)
					(fill yes)
				)
			)
		)
		(pad "2" smd custom
			(at 0 0.4445 270)
			(size 0.1397 0.1397)
			(layers "F.Cu" "F.Mask" "F.Paste")
			(net "SCC_B_TYPE_2")
			(options
				(clearance outline)
				(anchor circle)
			)
			(primitives
				(gr_poly
					(pts
						(arc
							(start -0.1778 -0.2794)
							(mid -0.249642 -0.249642)
							(end -0.2794 -0.1778)
						)
						(arc
							(start -0.2794 0.1778)
							(mid -0.249642 0.249642)
							(end -0.1778 0.2794)
						)
						(arc
							(start 0.1778 0.2794)
							(mid 0.249642 0.249642)
							(end 0.2794 0.1778)
						)
						(arc
							(start 0.2794 -0.1778)
							(mid 0.249642 -0.249642)
							(end 0.1778 -0.2794)
						)
					)
					(width 0)
					(fill yes)
				)
			)
		)
	)
	(footprint ""
		(layer "F.Cu")
		(at 55.499 -157.226)
		(property "Reference" "C204"
			(at 0 0 0)
			(layer "F.SilkS")
			(hide yes)
			(effects
				(font
					(size 1.27 1.27)
				)
			)
		)
		(property "Value" "SC4D7U25V5KX-1-GP"
			(at -0.0762 -6.1214 0)
			(unlocked yes)
			(layer "F.Fab")
			(hide yes)
			(effects
				(font
					(size 1.016 1.016)
					(thickness 0.1524)
				)
			)
		)
		(property "Device Type" "C805H58"
			(at -0.0762 -8.1534 0)
			(unlocked yes)
			(layer "F.Fab")
			(hide yes)
			(effects
				(font
					(size 1.016 1.016)
					(thickness 0.1524)
				)
			)
		)
		(duplicate_pad_numbers_are_jumpers no)
		(fp_line
			(start 0.635 0)
			(end -0.635 0)
			(stroke
				(width 0.508)
				(type default)
			)
			(layer "F.SilkS")
		)
		(fp_rect
			(start -0.9652 1.778)
			(end 0.9652 -1.778)
			(stroke
				(width 0)
				(type default)
			)
			(fill no)
			(layer "F.CrtYd")
		)
		(fp_poly
			(pts
				(xy -0.9652 -1.778) (xy 0.9652 -1.778) (xy 0.9652 1.778) (xy -0.9652 1.778)
			)
			(stroke
				(width 0)
				(type default)
			)
			(fill no)
			(layer "F.Fab")
		)
		(pad "1" smd rect
			(at 0 -0.9652)
			(size 1.397 1.143)
			(layers "F.Cu" "F.Mask" "F.Paste")
			(net "P12V_HDD13")
		)
		(pad "2" smd rect
			(at 0 0.9652)
			(size 1.397 1.143)
			(layers "F.Cu" "F.Mask" "F.Paste")
			(net "GND")
		)
	)
	(footprint ""
		(layer "F.Cu")
		(at 113.538 -265.684 90)
		(property "Reference" "R208"
			(at 0 0 90)
			(layer "F.SilkS")
			(hide yes)
			(effects
				(font
					(size 1.27 1.27)
				)
			)
		)
		(property "Value" "2R6F-GP"
			(at -0.0508 -4.8514 90)
			(unlocked yes)
			(layer "F.Fab")
			(hide yes)
			(effects
				(font
					(size 1.016 1.016)
					(thickness 0.1524)
				)
			)
		)
		(property "Device Type" "R1206H26"
			(at 0 -6.3754 90)
			(unlocked yes)
			(layer "F.Fab")
			(hide yes)
			(effects
				(font
					(size 1.016 1.016)
					(thickness 0.1524)
				)
			)
		)
		(duplicate_pad_numbers_are_jumpers no)
		(fp_line
			(start 1.016 -2.2352)
			(end 1.016 2.2352)
			(stroke
				(width 0.1524)
				(type default)
			)
			(layer "F.SilkS")
		)
		(fp_line
			(start -1.016 -2.2352)
			(end 1.016 -2.2352)
			(stroke
				(width 0.1524)
				(type default)
			)
			(layer "F.SilkS")
		)
		(fp_line
			(start 1.016 2.2352)
			(end -1.016 2.2352)
			(stroke
				(width 0.1524)
				(type default)
			)
			(layer "F.SilkS")
		)
		(fp_line
			(start -1.016 2.2352)
			(end -1.016 -2.2352)
			(stroke
				(width 0.1524)
				(type default)
			)
			(layer "F.SilkS")
		)
		(fp_rect
			(start -1.0922 2.3114)
			(end 1.0922 -2.3114)
			(stroke
				(width 0)
				(type default)
			)
			(fill no)
			(layer "F.CrtYd")
		)
		(fp_poly
			(pts
				(xy -1.0922 -2.3114) (xy 1.0922 -2.3114) (xy 1.0922 2.3114) (xy -1.0922 2.3114)
			)
			(stroke
				(width 0)
				(type default)
			)
			(fill no)
			(layer "F.Fab")
		)
		(pad "1" smd rect
			(at 0 -1.397 90)
			(size 1.651 1.27)
			(layers "F.Cu" "F.Mask" "F.Paste")
			(net "P12V_HDD3")
		)
		(pad "2" smd rect
			(at 0 1.397 90)
			(size 1.651 1.27)
			(layers "F.Cu" "F.Mask" "F.Paste")
			(net "12V_PRE_3")
		)
	)
	(footprint ""
		(layer "F.Cu")
		(at 326.738996 -375.92 90)
		(property "Reference" "R944"
			(at 0 0 90)
			(layer "F.SilkS")
			(hide yes)
			(effects
				(font
					(size 1.27 1.27)
				)
			)
		)
		(property "Value" "100KR2F-L1-GP"
			(at 0.064008 -3.993896 90)
			(unlocked yes)
			(layer "F.Fab")
			(hide yes)
			(effects
				(font
					(size 1.016 1.016)
					(thickness 0.1524)
				)
			)
		)
		(property "Device Type" "R402H16"
			(at 0.064008 -5.517896 90)
			(unlocked yes)
			(layer "F.Fab")
			(hide yes)
			(effects
				(font
					(size 1.016 1.016)
					(thickness 0.1524)
				)
			)
		)
		(duplicate_pad_numbers_are_jumpers no)
		(fp_line
			(start 0.508 -0.9398)
			(end -0.508 -0.9398)
			(stroke
				(width 0.1524)
				(type default)
			)
			(layer "F.SilkS")
		)
		(fp_line
			(start -0.508 -0.9398)
			(end -0.508 0.9398)
			(stroke
				(width 0.1524)
				(type default)
			)
			(layer "F.SilkS")
		)
		(fp_rect
			(start -0.508 0.9398)
			(end 0.508 -0.9398)
			(stroke
				(width 0)
				(type default)
			)
			(fill no)
			(layer "F.CrtYd")
		)
		(fp_rect
			(start -0.508 0.9398)
			(end 0.508 -0.9398)
			(stroke
				(width 0)
				(type default)
			)
			(fill no)
			(layer "F.Fab")
		)
		(pad "1" smd custom
			(at 0 -0.4445 90)
			(size 0.1397 0.1397)
			(layers "F.Cu" "F.Mask" "F.Paste")
			(net "P3V3_IN")
			(options
				(clearance outline)
				(anchor circle)
			)
			(primitives
				(gr_poly
					(pts
						(arc
							(start -0.1778 -0.2794)
							(mid -0.249642 -0.249642)
							(end -0.2794 -0.1778)
						)
						(arc
							(start -0.2794 0.1778)
							(mid -0.249642 0.249642)
							(end -0.1778 0.2794)
						)
						(arc
							(start 0.1778 0.2794)
							(mid 0.249642 0.249642)
							(end 0.2794 0.1778)
						)
						(arc
							(start 0.2794 -0.1778)
							(mid 0.249642 -0.249642)
							(end 0.1778 -0.2794)
						)
					)
					(width 0)
					(fill yes)
				)
			)
		)
		(pad "2" smd custom
			(at 0 0.4445 90)
			(size 0.1397 0.1397)
			(layers "F.Cu" "F.Mask" "F.Paste")
			(net "FAN_2_INS_N")
			(options
				(clearance outline)
				(anchor circle)
			)
			(primitives
				(gr_poly
					(pts
						(arc
							(start -0.1778 -0.2794)
							(mid -0.249642 -0.249642)
							(end -0.2794 -0.1778)
						)
						(arc
							(start -0.2794 0.1778)
							(mid -0.249642 0.249642)
							(end -0.1778 0.2794)
						)
						(arc
							(start 0.1778 0.2794)
							(mid 0.249642 0.249642)
							(end 0.2794 0.1778)
						)
						(arc
							(start 0.2794 -0.1778)
							(mid 0.249642 -0.249642)
							(end 0.1778 -0.2794)
						)
					)
					(width 0)
					(fill yes)
				)
			)
		)
	)
	(footprint ""
		(layer "F.Cu")
		(at 22.987 -247.015 -90)
		(property "Reference" "R906"
			(at 0 0 270)
			(layer "F.SilkS")
			(hide yes)
			(effects
				(font
					(size 1.27 1.27)
				)
			)
		)
		(property "Value" "1KR2F-3-GP"
			(at 0.064008 -3.993896 270)
			(unlocked yes)
			(layer "F.Fab")
			(hide yes)
			(effects
				(font
					(size 1.016 1.016)
					(thickness 0.1524)
				)
			)
		)
		(property "Device Type" "R402H16"
			(at 0.064008 -5.517896 270)
			(unlocked yes)
			(layer "F.Fab")
			(hide yes)
			(effects
				(font
					(size 1.016 1.016)
					(thickness 0.1524)
				)
			)
		)
		(duplicate_pad_numbers_are_jumpers no)
		(fp_line
			(start -0.508 -0.9398)
			(end -0.508 0.9398)
			(stroke
				(width 0.1524)
				(type default)
			)
			(layer "F.SilkS")
		)
		(fp_line
			(start 0.508 -0.9398)
			(end -0.508 -0.9398)
			(stroke
				(width 0.1524)
				(type default)
			)
			(layer "F.SilkS")
		)
		(fp_rect
			(start -0.508 0.9398)
			(end 0.508 -0.9398)
			(stroke
				(width 0)
				(type default)
			)
			(fill no)
			(layer "F.CrtYd")
		)
		(fp_rect
			(start -0.508 0.9398)
			(end 0.508 -0.9398)
			(stroke
				(width 0)
				(type default)
			)
			(fill no)
			(layer "F.Fab")
		)
		(pad "1" smd custom
			(at 0 -0.4445 270)
			(size 0.1397 0.1397)
			(layers "F.Cu" "F.Mask" "F.Paste")
			(net "P3V3_STBY_B")
			(options
				(clearance outline)
				(anchor circle)
			)
			(primitives
				(gr_poly
					(pts
						(arc
							(start -0.1778 -0.2794)
							(mid -0.249642 -0.249642)
							(end -0.2794 -0.1778)
						)
						(arc
							(start -0.2794 0.1778)
							(mid -0.249642 0.249642)
							(end -0.1778 0.2794)
						)
						(arc
							(start 0.1778 0.2794)
							(mid 0.249642 0.249642)
							(end 0.2794 0.1778)
						)
						(arc
							(start 0.2794 -0.1778)
							(mid 0.249642 -0.249642)
							(end 0.1778 -0.2794)
						)
					)
					(width 0)
					(fill yes)
				)
			)
		)
		(pad "2" smd custom
			(at 0 0.4445 270)
			(size 0.1397 0.1397)
			(layers "F.Cu" "F.Mask" "F.Paste")
			(net "SW_PWR_R_HDD0")
			(options
				(clearance outline)
				(anchor circle)
			)
			(primitives
				(gr_poly
					(pts
						(arc
							(start -0.1778 -0.2794)
							(mid -0.249642 -0.249642)
							(end -0.2794 -0.1778)
						)
						(arc
							(start -0.2794 0.1778)
							(mid -0.249642 0.249642)
							(end -0.1778 0.2794)
						)
						(arc
							(start 0.1778 0.2794)
							(mid 0.249642 0.249642)
							(end 0.2794 0.1778)
						)
						(arc
							(start 0.2794 -0.1778)
							(mid 0.249642 -0.249642)
							(end 0.1778 -0.2794)
						)
					)
					(width 0)
					(fill yes)
				)
			)
		)
	)
	(footprint ""
		(layer "F.Cu")
		(at 363.601 -246.253 -90)
		(property "Reference" "Q27"
			(at 0 0 270)
			(layer "F.SilkS")
			(hide yes)
			(effects
				(font
					(size 1.27 1.27)
				)
			)
		)
		(property "Value" "2N7002KDW-GP"
			(at -2.3622 -8.2042 270)
			(unlocked yes)
			(layer "F.Fab")
			(hide yes)
			(effects
				(font
					(size 1.016 1.016)
					(thickness 0.1524)
				)
			)
		)
		(property "Device Type" "SOT-363H44"
			(at -2.3622 -10.1092 270)
			(unlocked yes)
			(layer "F.Fab")
			(hide yes)
			(effects
				(font
					(size 1.016 1.016)
					(thickness 0.1524)
				)
			)
		)
		(duplicate_pad_numbers_are_jumpers no)
		(fp_line
			(start -1.4478 1.7018)
			(end 1.4478 1.7018)
			(stroke
				(width 0.1524)
				(type default)
			)
			(layer "F.SilkS")
		)
		(fp_line
			(start 1.4478 1.7018)
			(end 1.4478 -1.7018)
			(stroke
				(width 0.1524)
				(type default)
			)
			(layer "F.SilkS")
		)
		(fp_line
			(start -1.27 1.524)
			(end -1.27 0.6604)
			(stroke
				(width 0.4826)
				(type default)
			)
			(layer "F.SilkS")
		)
		(fp_line
			(start -1.4478 -1.7018)
			(end -1.4478 1.7018)
			(stroke
				(width 0.1524)
				(type default)
			)
			(layer "F.SilkS")
		)
		(fp_line
			(start 1.4478 -1.7018)
			(end -1.4478 -1.7018)
			(stroke
				(width 0.1524)
				(type default)
			)
			(layer "F.SilkS")
		)
		(fp_poly
			(pts
				(xy -1.524 -1.778) (xy 1.524 -1.778) (xy 1.524 1.778) (xy -1.524 1.778)
			)
			(stroke
				(width 0)
				(type default)
			)
			(fill no)
			(layer "F.CrtYd")
		)
		(fp_poly
			(pts
				(xy -1.524 -1.778) (xy 1.524 -1.778) (xy 1.524 1.778) (xy -1.524 1.778)
			)
			(stroke
				(width 0)
				(type default)
			)
			(fill no)
			(layer "F.Fab")
		)
		(pad "1" smd rect
			(at -0.65024 0.9398 270)
			(size 0.4064 1.016)
			(layers "F.Cu" "F.Mask" "F.Paste")
			(net "GND")
		)
		(pad "2" smd rect
			(at 0 0.9398 270)
			(size 0.4064 1.016)
			(layers "F.Cu" "F.Mask" "F.Paste")
			(net "SW_PWR_R_HDD7")
		)
		(pad "3" smd rect
			(at 0.65024 0.9398 270)
			(size 0.4064 1.016)
			(layers "F.Cu" "F.Mask" "F.Paste")
			(net "SW_HDD_P7")
		)
		(pad "4" smd rect
			(at 0.65024 -0.9398 270)
			(size 0.4064 1.016)
			(layers "F.Cu" "F.Mask" "F.Paste")
			(net "GND")
		)
		(pad "5" smd rect
			(at 0 -0.9398 270)
			(size 0.4064 1.016)
			(layers "F.Cu" "F.Mask" "F.Paste")
			(net "SW_HDD_G7")
		)
		(pad "6" smd rect
			(at -0.65024 -0.9398 270)
			(size 0.4064 1.016)
			(layers "F.Cu" "F.Mask" "F.Paste")
			(net "SW_HDD_R7")
		)
	)
	(footprint ""
		(layer "F.Cu")
		(at 180.721 -134.493 90)
		(property "Reference" "R473"
			(at 0 0 90)
			(layer "F.SilkS")
			(hide yes)
			(effects
				(font
					(size 1.27 1.27)
				)
			)
		)
		(property "Value" "4K7R2F-GP"
			(at 0.064008 -3.993896 90)
			(unlocked yes)
			(layer "F.Fab")
			(hide yes)
			(effects
				(font
					(size 1.016 1.016)
					(thickness 0.1524)
				)
			)
		)
		(property "Device Type" "R402H16"
			(at 0.064008 -5.517896 90)
			(unlocked yes)
			(layer "F.Fab")
			(hide yes)
			(effects
				(font
					(size 1.016 1.016)
					(thickness 0.1524)
				)
			)
		)
		(duplicate_pad_numbers_are_jumpers no)
		(fp_line
			(start 0.508 -0.9398)
			(end -0.508 -0.9398)
			(stroke
				(width 0.1524)
				(type default)
			)
			(layer "F.SilkS")
		)
		(fp_line
			(start -0.508 -0.9398)
			(end -0.508 0.9398)
			(stroke
				(width 0.1524)
				(type default)
			)
			(layer "F.SilkS")
		)
		(fp_rect
			(start -0.508 0.9398)
			(end 0.508 -0.9398)
			(stroke
				(width 0)
				(type default)
			)
			(fill no)
			(layer "F.CrtYd")
		)
		(fp_rect
			(start -0.508 0.9398)
			(end 0.508 -0.9398)
			(stroke
				(width 0)
				(type default)
			)
			(fill no)
			(layer "F.Fab")
		)
		(pad "1" smd custom
			(at 0 -0.4445 90)
			(size 0.1397 0.1397)
			(layers "F.Cu" "F.Mask" "F.Paste")
			(net "SW_PWR_R_HDD17")
			(options
				(clearance outline)
				(anchor circle)
			)
			(primitives
				(gr_poly
					(pts
						(arc
							(start -0.1778 -0.2794)
							(mid -0.249642 -0.249642)
							(end -0.2794 -0.1778)
						)
						(arc
							(start -0.2794 0.1778)
							(mid -0.249642 0.249642)
							(end -0.1778 0.2794)
						)
						(arc
							(start 0.1778 0.2794)
							(mid 0.249642 0.249642)
							(end 0.2794 0.1778)
						)
						(arc
							(start 0.2794 -0.1778)
							(mid 0.249642 -0.249642)
							(end 0.1778 -0.2794)
						)
					)
					(width 0)
					(fill yes)
				)
			)
		)
		(pad "2" smd custom
			(at 0 0.4445 90)
			(size 0.1397 0.1397)
			(layers "F.Cu" "F.Mask" "F.Paste")
			(net "GND")
			(options
				(clearance outline)
				(anchor circle)
			)
			(primitives
				(gr_poly
					(pts
						(arc
							(start -0.1778 -0.2794)
							(mid -0.249642 -0.249642)
							(end -0.2794 -0.1778)
						)
						(arc
							(start -0.2794 0.1778)
							(mid -0.249642 0.249642)
							(end -0.1778 0.2794)
						)
						(arc
							(start 0.1778 0.2794)
							(mid 0.249642 0.249642)
							(end 0.2794 0.1778)
						)
						(arc
							(start 0.2794 -0.1778)
							(mid 0.249642 -0.249642)
							(end 0.1778 -0.2794)
						)
					)
					(width 0)
					(fill yes)
				)
			)
		)
	)
	(footprint ""
		(layer "F.Cu")
		(at 252.339602 -133.720078 -90)
		(property "Reference" "R418"
			(at 0 0 270)
			(layer "F.SilkS")
			(hide yes)
			(effects
				(font
					(size 1.27 1.27)
				)
			)
		)
		(property "Value" "1KR2J-1-GP"
			(at 0.064008 -3.993896 270)
			(unlocked yes)
			(layer "F.Fab")
			(hide yes)
			(effects
				(font
					(size 1.016 1.016)
					(thickness 0.1524)
				)
			)
		)
		(property "Device Type" "R402H16"
			(at 0.064008 -5.517896 270)
			(unlocked yes)
			(layer "F.Fab")
			(hide yes)
			(effects
				(font
					(size 1.016 1.016)
					(thickness 0.1524)
				)
			)
		)
		(duplicate_pad_numbers_are_jumpers no)
		(fp_line
			(start -0.508 -0.9398)
			(end -0.508 0.9398)
			(stroke
				(width 0.1524)
				(type default)
			)
			(layer "F.SilkS")
		)
		(fp_line
			(start 0.508 -0.9398)
			(end -0.508 -0.9398)
			(stroke
				(width 0.1524)
				(type default)
			)
			(layer "F.SilkS")
		)
		(fp_rect
			(start -0.508 0.9398)
			(end 0.508 -0.9398)
			(stroke
				(width 0)
				(type default)
			)
			(fill no)
			(layer "F.CrtYd")
		)
		(fp_rect
			(start -0.508 0.9398)
			(end 0.508 -0.9398)
			(stroke
				(width 0)
				(type default)
			)
			(fill no)
			(layer "F.Fab")
		)
		(pad "1" smd custom
			(at 0 -0.4445 270)
			(size 0.1397 0.1397)
			(layers "F.Cu" "F.Mask" "F.Paste")
			(net "P3V3_STBY_B")
			(options
				(clearance outline)
				(anchor circle)
			)
			(primitives
				(gr_poly
					(pts
						(arc
							(start -0.1778 -0.2794)
							(mid -0.249642 -0.249642)
							(end -0.2794 -0.1778)
						)
						(arc
							(start -0.2794 0.1778)
							(mid -0.249642 0.249642)
							(end -0.1778 0.2794)
						)
						(arc
							(start 0.1778 0.2794)
							(mid 0.249642 0.249642)
							(end 0.2794 0.1778)
						)
						(arc
							(start 0.2794 -0.1778)
							(mid 0.249642 -0.249642)
							(end 0.1778 -0.2794)
						)
					)
					(width 0)
					(fill yes)
				)
			)
		)
		(pad "2" smd custom
			(at 0 0.4445 270)
			(size 0.1397 0.1397)
			(layers "F.Cu" "F.Mask" "F.Paste")
			(net "I2C_DPB_B_SDA_BUF")
			(options
				(clearance outline)
				(anchor circle)
			)
			(primitives
				(gr_poly
					(pts
						(arc
							(start -0.1778 -0.2794)
							(mid -0.249642 -0.249642)
							(end -0.2794 -0.1778)
						)
						(arc
							(start -0.2794 0.1778)
							(mid -0.249642 0.249642)
							(end -0.1778 0.2794)
						)
						(arc
							(start 0.1778 0.2794)
							(mid 0.249642 0.249642)
							(end 0.2794 0.1778)
						)
						(arc
							(start 0.2794 -0.1778)
							(mid 0.249642 -0.249642)
							(end 0.1778 -0.2794)
						)
					)
					(width 0)
					(fill yes)
				)
			)
		)
	)
	(footprint ""
		(layer "F.Cu")
		(at 400.05 -246.761 180)
		(property "Reference" "R296"
			(at 0 0 180)
			(layer "F.SilkS")
			(hide yes)
			(effects
				(font
					(size 1.27 1.27)
				)
			)
		)
		(property "Value" "4K7R2J-2-GP"
			(at 0.064008 -3.993896 180)
			(unlocked yes)
			(layer "F.Fab")
			(hide yes)
			(effects
				(font
					(size 1.016 1.016)
					(thickness 0.1524)
				)
			)
		)
		(property "Device Type" "R402H16"
			(at 0.064008 -5.517896 180)
			(unlocked yes)
			(layer "F.Fab")
			(hide yes)
			(effects
				(font
					(size 1.016 1.016)
					(thickness 0.1524)
				)
			)
		)
		(duplicate_pad_numbers_are_jumpers no)
		(fp_line
			(start 0.508 -0.9398)
			(end -0.508 -0.9398)
			(stroke
				(width 0.1524)
				(type default)
			)
			(layer "F.SilkS")
		)
		(fp_line
			(start -0.508 -0.9398)
			(end -0.508 0.9398)
			(stroke
				(width 0.1524)
				(type default)
			)
			(layer "F.SilkS")
		)
		(fp_rect
			(start -0.508 0.9398)
			(end 0.508 -0.9398)
			(stroke
				(width 0)
				(type default)
			)
			(fill no)
			(layer "F.CrtYd")
		)
		(fp_rect
			(start -0.508 0.9398)
			(end 0.508 -0.9398)
			(stroke
				(width 0)
				(type default)
			)
			(fill no)
			(layer "F.Fab")
		)
		(pad "1" smd custom
			(at 0 -0.4445 180)
			(size 0.1397 0.1397)
			(layers "F.Cu" "F.Mask" "F.Paste")
			(net "P12V_B")
			(options
				(clearance outline)
				(anchor circle)
			)
			(primitives
				(gr_poly
					(pts
						(arc
							(start -0.1778 -0.2794)
							(mid -0.249642 -0.249642)
							(end -0.2794 -0.1778)
						)
						(arc
							(start -0.2794 0.1778)
							(mid -0.249642 0.249642)
							(end -0.1778 0.2794)
						)
						(arc
							(start 0.1778 0.2794)
							(mid 0.249642 0.249642)
							(end 0.2794 0.1778)
						)
						(arc
							(start 0.2794 -0.1778)
							(mid 0.249642 -0.249642)
							(end 0.1778 -0.2794)
						)
					)
					(width 0)
					(fill yes)
				)
			)
		)
		(pad "2" smd custom
			(at 0 0.4445 180)
			(size 0.1397 0.1397)
			(layers "F.Cu" "F.Mask" "F.Paste")
			(net "SW_HDD_R8")
			(options
				(clearance outline)
				(anchor circle)
			)
			(primitives
				(gr_poly
					(pts
						(arc
							(start -0.1778 -0.2794)
							(mid -0.249642 -0.249642)
							(end -0.2794 -0.1778)
						)
						(arc
							(start -0.2794 0.1778)
							(mid -0.249642 0.249642)
							(end -0.1778 0.2794)
						)
						(arc
							(start 0.1778 0.2794)
							(mid 0.249642 0.249642)
							(end 0.2794 0.1778)
						)
						(arc
							(start 0.2794 -0.1778)
							(mid 0.249642 -0.249642)
							(end 0.1778 -0.2794)
						)
					)
					(width 0)
					(fill yes)
				)
			)
		)
	)
	(footprint ""
		(layer "F.Cu")
		(at 28.200096 -28.910026 -90)
		(property "Reference" "HDDSAS24"
			(at 0 0 270)
			(layer "F.SilkS")
			(hide yes)
			(effects
				(font
					(size 1.27 1.27)
				)
			)
		)
		(property "Value" "SKT-SAS15P-14P-45-GP"
			(at -20.7645 -8.9789 270)
			(unlocked yes)
			(layer "F.Fab")
			(hide yes)
			(effects
				(font
					(size 1.016 1.016)
					(thickness 0.1524)
				)
			)
		)
		(property "Device Type" "10120818-001C-TRLF"
			(at -20.7645 -10.5029 270)
			(unlocked yes)
			(layer "F.Fab")
			(hide yes)
			(effects
				(font
					(size 1.016 1.016)
					(thickness 0.1524)
				)
			)
		)
		(duplicate_pad_numbers_are_jumpers no)
		(fp_line
			(start 1.651 4.2926)
			(end 1.651 3.0099)
			(stroke
				(width 0.1524)
				(type default)
			)
			(layer "F.SilkS")
		)
		(fp_line
			(start 8.509 4.2926)
			(end 1.651 4.2926)
			(stroke
				(width 0.1524)
				(type default)
			)
			(layer "F.SilkS")
		)
		(fp_line
			(start -23.4188 3.0099)
			(end -23.4188 -3.2512)
			(stroke
				(width 0.1524)
				(type default)
			)
			(layer "F.SilkS")
		)
		(fp_line
			(start 1.651 3.0099)
			(end -23.4188 3.0099)
			(stroke
				(width 0.1524)
				(type default)
			)
			(layer "F.SilkS")
		)
		(fp_line
			(start 8.509 3.0099)
			(end 8.509 4.2926)
			(stroke
				(width 0.1524)
				(type default)
			)
			(layer "F.SilkS")
		)
		(fp_line
			(start 23.4188 3.0099)
			(end 8.509 3.0099)
			(stroke
				(width 0.1524)
				(type default)
			)
			(layer "F.SilkS")
		)
		(fp_line
			(start -23.4188 -3.2512)
			(end 23.4188 -3.2512)
			(stroke
				(width 0.1524)
				(type default)
			)
			(layer "F.SilkS")
		)
		(fp_line
			(start 23.4188 -3.2512)
			(end 23.4188 3.0099)
			(stroke
				(width 0.1524)
				(type default)
			)
			(layer "F.SilkS")
		)
		(fp_line
			(start 15.5067 -3.3401)
			(end 16.2687 -3.3401)
			(stroke
				(width 0.3302)
				(type default)
			)
			(layer "F.SilkS")
		)
		(fp_poly
			(pts
				(xy 15.868904 -3.230372) (xy 16.503904 -3.865372) (xy 15.233904 -3.865372)
			)
			(stroke
				(width 0)
				(type default)
			)
			(fill yes)
			(layer "F.SilkS")
		)
		(fp_poly
			(pts
				(xy -22.8727 -2.7559) (xy 22.8727 -2.7559) (xy 22.8727 2.7559) (xy 8.255 2.7559) (xy 8.255 3.5179)
				(xy 1.905 3.5179) (xy 1.905 2.7559) (xy -22.8727 2.7559)
			)
			(stroke
				(width 0)
				(type default)
			)
			(fill no)
			(layer "F.CrtYd")
		)
		(fp_poly
			(pts
				(xy 1.397 4.5466) (xy 1.397 3.2639) (xy -23.6728 3.2639) (xy -23.6728 -3.5052) (xy 23.6728 -3.5052)
				(xy 23.6728 -0.00635) (xy 22.8727 -0.00635) (xy 22.8727 -2.7559) (xy -22.8727 -2.7559) (xy -22.8727 2.7559)
				(xy 1.905 2.7559) (xy 1.905 3.5179) (xy 8.255 3.5179) (xy 8.255 2.7559) (xy 22.8727 2.7559) (xy 22.8727 0.00635)
				(xy 23.6728 0.00635) (xy 23.6728 3.2639) (xy 8.763 3.2639) (xy 8.763 4.5466)
			)
			(stroke
				(width 0)
				(type default)
			)
			(fill no)
			(layer "F.CrtYd")
		)
		(fp_poly
			(pts
				(xy 1.397 4.5466) (xy 1.397 3.2639) (xy -23.6728 3.2639) (xy -23.6728 -3.5052) (xy 23.6728 -3.5052)
				(xy 23.6728 3.2639) (xy 8.763 3.2639) (xy 8.763 4.5466)
			)
			(stroke
				(width 0)
				(type default)
			)
			(fill no)
			(layer "F.Fab")
		)
		(pad "" np_thru_hole circle
			(at -18.874994 0 270)
			(size 0.254 0.254)
			(drill 1.3462)
			(layers "*.Cu" "*.Mask")
			(clearance 0.9017)
			(thermal_gap 0.9017)
		)
		(pad "" np_thru_hole circle
			(at 18.874994 0 270)
			(size 0.254 0.254)
			(drill 0.9398)
			(layers "*.Cu" "*.Mask")
			(clearance 0.6985)
			(thermal_gap 0.6985)
		)
		(pad "G1" smd rect
			(at 21.874988 0 270)
			(size 2.5908 2.5908)
			(layers "F.Cu" "F.Mask" "F.Paste")
			(net "GND")
		)
		(pad "G2" smd rect
			(at -21.874988 0 270)
			(size 2.5908 2.5908)
			(layers "F.Cu" "F.Mask" "F.Paste")
			(net "GND")
		)
		(pad "P1" smd rect
			(at 1.905 -1.82499 270)
			(size 0.6096 2.3622)
			(layers "F.Cu" "F.Mask" "F.Paste")
			(net "Net_1679")
		)
		(pad "P2" smd rect
			(at 0.635 -1.82499 270)
			(size 0.6096 2.3622)
			(layers "F.Cu" "F.Mask" "F.Paste")
			(net "Net_1680")
		)
		(pad "P3" smd rect
			(at -0.635 -1.82499 270)
			(size 0.6096 2.3622)
			(layers "F.Cu" "F.Mask" "F.Paste")
			(net "Net_1681")
		)
		(pad "P4" smd rect
			(at -1.905 -1.82499 270)
			(size 0.6096 2.3622)
			(layers "F.Cu" "F.Mask" "F.Paste")
			(net "GND")
		)
		(pad "P5" smd rect
			(at -3.175 -1.82499 270)
			(size 0.6096 2.3622)
			(layers "F.Cu" "F.Mask" "F.Paste")
			(net "HDD_PRSNT_24")
		)
		(pad "P6" smd rect
			(at -4.445 -1.82499 270)
			(size 0.6096 2.3622)
			(layers "F.Cu" "F.Mask" "F.Paste")
			(net "GND")
		)
		(pad "P7" smd rect
			(at -5.715 -1.82499 270)
			(size 0.6096 2.3622)
			(layers "F.Cu" "F.Mask" "F.Paste")
			(net "5V_PRE_24")
		)
		(pad "P8" smd rect
			(at -6.985 -1.82499 270)
			(size 0.6096 2.3622)
			(layers "F.Cu" "F.Mask" "F.Paste")
			(net "P5V_HDD24")
		)
		(pad "P9" smd rect
			(at -8.255 -1.82499 270)
			(size 0.6096 2.3622)
			(layers "F.Cu" "F.Mask" "F.Paste")
			(net "P5V_HDD24")
		)
		(pad "P10" smd rect
			(at -9.525 -1.82499 270)
			(size 0.6096 2.3622)
			(layers "F.Cu" "F.Mask" "F.Paste")
			(net "GND")
		)
		(pad "P11" smd rect
			(at -10.795 -1.82499 270)
			(size 0.6096 2.3622)
			(layers "F.Cu" "F.Mask" "F.Paste")
			(net "ACT_HDD_24")
		)
		(pad "P12" smd rect
			(at -12.065 -1.82499 270)
			(size 0.6096 2.3622)
			(layers "F.Cu" "F.Mask" "F.Paste")
			(net "GND")
		)
		(pad "P13" smd rect
			(at -13.335 -1.82499 270)
			(size 0.6096 2.3622)
			(layers "F.Cu" "F.Mask" "F.Paste")
			(net "12V_PRE_24")
		)
		(pad "P14" smd rect
			(at -14.605 -1.82499 270)
			(size 0.6096 2.3622)
			(layers "F.Cu" "F.Mask" "F.Paste")
			(net "P12V_HDD24")
		)
		(pad "P15" smd rect
			(at -15.875 -1.82499 270)
			(size 0.6096 2.3622)
			(layers "F.Cu" "F.Mask" "F.Paste")
			(net "P12V_HDD24")
		)
		(pad "S1" smd rect
			(at 15.875 -1.82499 270)
			(size 0.6096 2.3622)
			(layers "F.Cu" "F.Mask" "F.Paste")
			(net "GND")
		)
		(pad "S2" smd rect
			(at 14.605 -1.82499 270)
			(size 0.6096 2.3622)
			(layers "F.Cu" "F.Mask" "F.Paste")
			(net "SAS_HDD_RX_P24")
		)
		(pad "S3" smd rect
			(at 13.335 -1.82499 270)
			(size 0.6096 2.3622)
			(layers "F.Cu" "F.Mask" "F.Paste")
			(net "SAS_HDD_RX_N24")
		)
		(pad "S4" smd rect
			(at 12.065 -1.82499 270)
			(size 0.6096 2.3622)
			(layers "F.Cu" "F.Mask" "F.Paste")
			(net "GND")
		)
		(pad "S5" smd rect
			(at 10.795 -1.82499 270)
			(size 0.6096 2.3622)
			(layers "F.Cu" "F.Mask" "F.Paste")
			(net "PHY_DRV_B_TO_SCC_B_24_DN")
		)
		(pad "S6" smd rect
			(at 9.525 -1.82499 270)
			(size 0.6096 2.3622)
			(layers "F.Cu" "F.Mask" "F.Paste")
			(net "PHY_DRV_B_TO_SCC_B_24_DP")
		)
		(pad "S7" smd rect
			(at 8.255 -1.82499 270)
			(size 0.6096 2.3622)
			(layers "F.Cu" "F.Mask" "F.Paste")
			(net "GND")
		)
		(pad "S8" smd rect
			(at 7.480046 2.845054 270)
			(size 0.508 2.3622)
			(layers "F.Cu" "F.Mask" "F.Paste")
			(net "GND")
		)
		(pad "S9" smd rect
			(at 6.679946 2.845054 270)
			(size 0.508 2.3622)
			(layers "F.Cu" "F.Mask" "F.Paste")
			(net "Net_448")
		)
		(pad "S10" smd rect
			(at 5.8801 2.845054 270)
			(size 0.508 2.3622)
			(layers "F.Cu" "F.Mask" "F.Paste")
			(net "Net_340")
		)
		(pad "S11" smd rect
			(at 5.08 2.845054 270)
			(size 0.508 2.3622)
			(layers "F.Cu" "F.Mask" "F.Paste")
			(net "GND")
		)
		(pad "S12" smd rect
			(at 4.2799 2.845054 270)
			(size 0.508 2.3622)
			(layers "F.Cu" "F.Mask" "F.Paste")
			(net "Net_376")
		)
		(pad "S13" smd rect
			(at 3.480054 2.845054 270)
			(size 0.508 2.3622)
			(layers "F.Cu" "F.Mask" "F.Paste")
			(net "Net_412")
		)
		(pad "S14" smd rect
			(at 2.679954 2.845054 270)
			(size 0.508 2.3622)
			(layers "F.Cu" "F.Mask" "F.Paste")
			(net "GND")
		)
		(zone
			(layer "F.Cu")
			(hatch none 0.5)
			(connect_pads
				(clearance 0)
			)
			(min_thickness 0.25)
			(keepout
				(tracks allowed)
				(vias not_allowed)
				(pads allowed)
				(copperpour not_allowed)
				(footprints allowed)
			)
			(placement
				(enabled no)
				(sheetname "")
			)
			(fill
				(thermal_gap 0.5)
				(thermal_bridge_width 0.5)
				(island_removal_mode 0)
			)
			(polygon
				(pts
					(xy 31.857696 -45.648626) (xy 24.783796 -45.648626) (xy 24.783796 -52.582826) (xy 25.888696 -52.582826)
					(xy 25.888696 -48.468026) (xy 30.511496 -48.468026) (xy 30.511496 -52.582826) (xy 31.857696 -52.582826)
				)
			)
		)
		(zone
			(layer "F.Cu")
			(hatch none 0.5)
			(connect_pads
				(clearance 0)
			)
			(min_thickness 0.25)
			(keepout
				(tracks not_allowed)
				(vias allowed)
				(pads allowed)
				(copperpour not_allowed)
				(footprints allowed)
			)
			(placement
				(enabled no)
				(sheetname "")
			)
			(fill
				(thermal_gap 0.5)
				(thermal_bridge_width 0.5)
				(island_removal_mode 0)
			)
			(polygon
				(pts
					(xy 31.857696 -45.648626) (xy 24.783796 -45.648626) (xy 24.783796 -52.582826) (xy 25.888696 -52.582826)
					(xy 25.888696 -48.468026) (xy 30.511496 -48.468026) (xy 30.511496 -52.582826) (xy 31.857696 -52.582826)
				)
			)
		)
		(zone
			(layer "F.Cu")
			(hatch none 0.5)
			(connect_pads
				(clearance 0)
			)
			(min_thickness 0.25)
			(keepout
				(tracks allowed)
				(vias not_allowed)
				(pads allowed)
				(copperpour not_allowed)
				(footprints allowed)
			)
			(placement
				(enabled no)
				(sheetname "")
			)
			(fill
				(thermal_gap 0.5)
				(thermal_bridge_width 0.5)
				(island_removal_mode 0)
			)
			(polygon
				(pts
					(xy 31.857696 -12.171426) (xy 24.783796 -12.171426) (xy 24.783796 -5.237226) (xy 25.888696 -5.237226)
					(xy 25.888696 -9.352026) (xy 30.511496 -9.352026) (xy 30.511496 -5.237226) (xy 31.857696 -5.237226)
				)
			)
		)
		(zone
			(layer "F.Cu")
			(hatch none 0.5)
			(connect_pads
				(clearance 0)
			)
			(min_thickness 0.25)
			(keepout
				(tracks not_allowed)
				(vias allowed)
				(pads allowed)
				(copperpour not_allowed)
				(footprints allowed)
			)
			(placement
				(enabled no)
				(sheetname "")
			)
			(fill
				(thermal_gap 0.5)
				(thermal_bridge_width 0.5)
				(island_removal_mode 0)
			)
			(polygon
				(pts
					(xy 31.857696 -12.171426) (xy 24.783796 -12.171426) (xy 24.783796 -5.237226) (xy 25.888696 -5.237226)
					(xy 25.888696 -9.352026) (xy 30.511496 -9.352026) (xy 30.511496 -5.237226) (xy 31.857696 -5.237226)
				)
			)
		)
		(zone
			(layers "F.Cu" "B.Cu" "In1.Cu" "In2.Cu" "In3.Cu" "In4.Cu" "In5.Cu" "In6.Cu")
			(hatch none 0.5)
			(connect_pads
				(clearance 0)
			)
			(min_thickness 0.25)
			(keepout
				(tracks not_allowed)
				(vias allowed)
				(pads allowed)
				(copperpour not_allowed)
				(footprints allowed)
			)
			(placement
				(enabled no)
				(sheetname "")
			)
			(fill
				(thermal_gap 0.5)
				(thermal_bridge_width 0.5)
				(island_removal_mode 0)
			)
			(polygon
				(pts
					(arc
						(start 28.974796 -10.035032)
						(mid 27.425396 -10.035032)
						(end 28.974796 -10.035032)
					)
				)
			)
		)
		(zone
			(layers "F.Cu" "B.Cu" "In1.Cu" "In2.Cu" "In3.Cu" "In4.Cu" "In5.Cu" "In6.Cu")
			(hatch none 0.5)
			(connect_pads
				(clearance 0)
			)
			(min_thickness 0.25)
			(keepout
				(tracks not_allowed)
				(vias allowed)
				(pads allowed)
				(copperpour not_allowed)
				(footprints allowed)
			)
			(placement
				(enabled no)
				(sheetname "")
			)
			(fill
				(thermal_gap 0.5)
				(thermal_bridge_width 0.5)
				(island_removal_mode 0)
			)
			(polygon
				(pts
					(arc
						(start 29.177996 -47.78502)
						(mid 27.222196 -47.78502)
						(end 29.177996 -47.78502)
					)
				)
			)
		)
	)
	(footprint ""
		(layer "F.Cu")
		(at 32.463486 -129.66065 90)
		(property "Reference" "C185"
			(at 0 0 90)
			(layer "F.SilkS")
			(hide yes)
			(effects
				(font
					(size 1.27 1.27)
				)
			)
		)
		(property "Value" "SCD01U16V1KX-GP"
			(at -2.8321 -1.7399 90)
			(unlocked yes)
			(layer "F.Fab")
			(hide yes)
			(effects
				(font
					(size 1.016 1.016)
					(thickness 0.1524)
				)
			)
		)
		(property "Device Type" "C0201H13"
			(at -2.8321 -3.2639 90)
			(unlocked yes)
			(layer "F.Fab")
			(hide yes)
			(effects
				(font
					(size 1.016 1.016)
					(thickness 0.1524)
				)
			)
		)
		(duplicate_pad_numbers_are_jumpers no)
		(fp_rect
			(start -0.2794 0.6477)
			(end 0.2794 -0.6477)
			(stroke
				(width 0)
				(type default)
			)
			(fill no)
			(layer "F.CrtYd")
		)
		(fp_rect
			(start -0.2794 0.6477)
			(end 0.2794 -0.6477)
			(stroke
				(width 0)
				(type default)
			)
			(fill no)
			(layer "F.Fab")
		)
		(pad "1" smd custom
			(at 0 -0.2794 90)
			(size 0.0762 0.0762)
			(layers "F.Cu" "F.Mask" "F.Paste")
			(net "SAS_HDD_RX_P12")
			(options
				(clearance outline)
				(anchor circle)
			)
			(primitives
				(gr_poly
					(pts
						(arc
							(start 0.1524 -0.127)
							(mid 0.137521 -0.162921)
							(end 0.1016 -0.1778)
						)
						(arc
							(start -0.1016 -0.1778)
							(mid -0.137521 -0.162921)
							(end -0.1524 -0.127)
						)
						(arc
							(start -0.1524 0.127)
							(mid -0.137521 0.162921)
							(end -0.1016 0.1778)
						)
						(arc
							(start 0.1016 0.1778)
							(mid 0.137521 0.162921)
							(end 0.1524 0.127)
						)
					)
					(width 0)
					(fill yes)
				)
			)
		)
		(pad "2" smd custom
			(at 0 0.2794 90)
			(size 0.0762 0.0762)
			(layers "F.Cu" "F.Mask" "F.Paste")
			(net "PHY_SCC_B_TO_DRV_B_12_DP")
			(options
				(clearance outline)
				(anchor circle)
			)
			(primitives
				(gr_poly
					(pts
						(arc
							(start 0.1524 -0.127)
							(mid 0.137521 -0.162921)
							(end 0.1016 -0.1778)
						)
						(arc
							(start -0.1016 -0.1778)
							(mid -0.137521 -0.162921)
							(end -0.1524 -0.127)
						)
						(arc
							(start -0.1524 0.127)
							(mid -0.137521 0.162921)
							(end -0.1016 0.1778)
						)
						(arc
							(start 0.1016 0.1778)
							(mid 0.137521 0.162921)
							(end 0.1524 0.127)
						)
					)
					(width 0)
					(fill yes)
				)
			)
		)
	)
	(footprint ""
		(layer "F.Cu")
		(at 143.002 -139.065 -90)
		(property "Reference" "C246"
			(at 0 0 270)
			(layer "F.SilkS")
			(hide yes)
			(effects
				(font
					(size 1.27 1.27)
				)
			)
		)
		(property "Value" "SCD033U25V2KX-GP"
			(at 1.1811 -2.7051 270)
			(unlocked yes)
			(layer "F.Fab")
			(hide yes)
			(effects
				(font
					(size 1.016 1.016)
					(thickness 0.1524)
				)
			)
		)
		(property "Device Type" "C402H22"
			(at 1.1811 -4.2291 270)
			(unlocked yes)
			(layer "F.Fab")
			(hide yes)
			(effects
				(font
					(size 1.016 1.016)
					(thickness 0.1524)
				)
			)
		)
		(duplicate_pad_numbers_are_jumpers no)
		(fp_rect
			(start -0.4318 0.9525)
			(end 0.4318 -0.9525)
			(stroke
				(width 0)
				(type default)
			)
			(fill no)
			(layer "F.CrtYd")
		)
		(fp_rect
			(start -0.4318 0.9525)
			(end 0.4318 -0.9525)
			(stroke
				(width 0)
				(type default)
			)
			(fill no)
			(layer "F.Fab")
		)
		(pad "1" smd custom
			(at 0 -0.4445 270)
			(size 0.1524 0.1524)
			(layers "F.Cu" "F.Mask" "F.Paste")
			(net "SW_HDD_P16")
			(options
				(clearance outline)
				(anchor circle)
			)
			(primitives
				(gr_poly
					(pts
						(arc
							(start 0.3048 -0.2032)
							(mid 0.275042 -0.275042)
							(end 0.2032 -0.3048)
						)
						(arc
							(start -0.2032 -0.3048)
							(mid -0.275042 -0.275042)
							(end -0.3048 -0.2032)
						)
						(arc
							(start -0.3048 0.2032)
							(mid -0.275042 0.275042)
							(end -0.2032 0.3048)
						)
						(arc
							(start 0.2032 0.3048)
							(mid 0.275042 0.275042)
							(end 0.3048 0.2032)
						)
					)
					(width 0)
					(fill yes)
				)
			)
		)
		(pad "2" smd custom
			(at 0 0.4445 270)
			(size 0.1524 0.1524)
			(layers "F.Cu" "F.Mask" "F.Paste")
			(net "GND")
			(options
				(clearance outline)
				(anchor circle)
			)
			(primitives
				(gr_poly
					(pts
						(arc
							(start 0.3048 -0.2032)
							(mid 0.275042 -0.275042)
							(end 0.2032 -0.3048)
						)
						(arc
							(start -0.2032 -0.3048)
							(mid -0.275042 -0.275042)
							(end -0.3048 -0.2032)
						)
						(arc
							(start -0.3048 0.2032)
							(mid -0.275042 0.275042)
							(end -0.2032 0.3048)
						)
						(arc
							(start 0.2032 0.3048)
							(mid 0.275042 0.275042)
							(end 0.3048 0.2032)
						)
					)
					(width 0)
					(fill yes)
				)
			)
		)
	)
	(footprint ""
		(layer "F.Cu")
		(at 326.992996 -368.935 -90)
		(property "Reference" "R947"
			(at 0 0 270)
			(layer "F.SilkS")
			(hide yes)
			(effects
				(font
					(size 1.27 1.27)
				)
			)
		)
		(property "Value" "10KR2F-2-GP"
			(at 0.064008 -3.993896 270)
			(unlocked yes)
			(layer "F.Fab")
			(hide yes)
			(effects
				(font
					(size 1.016 1.016)
					(thickness 0.1524)
				)
			)
		)
		(property "Device Type" "R402H16"
			(at 0.064008 -5.517896 270)
			(unlocked yes)
			(layer "F.Fab")
			(hide yes)
			(effects
				(font
					(size 1.016 1.016)
					(thickness 0.1524)
				)
			)
		)
		(duplicate_pad_numbers_are_jumpers no)
		(fp_line
			(start -0.508 -0.9398)
			(end -0.508 0.9398)
			(stroke
				(width 0.1524)
				(type default)
			)
			(layer "F.SilkS")
		)
		(fp_line
			(start 0.508 -0.9398)
			(end -0.508 -0.9398)
			(stroke
				(width 0.1524)
				(type default)
			)
			(layer "F.SilkS")
		)
		(fp_rect
			(start -0.508 0.9398)
			(end 0.508 -0.9398)
			(stroke
				(width 0)
				(type default)
			)
			(fill no)
			(layer "F.CrtYd")
		)
		(fp_rect
			(start -0.508 0.9398)
			(end 0.508 -0.9398)
			(stroke
				(width 0)
				(type default)
			)
			(fill no)
			(layer "F.Fab")
		)
		(pad "1" smd custom
			(at 0 -0.4445 270)
			(size 0.1397 0.1397)
			(layers "F.Cu" "F.Mask" "F.Paste")
			(net "GND")
			(options
				(clearance outline)
				(anchor circle)
			)
			(primitives
				(gr_poly
					(pts
						(arc
							(start -0.1778 -0.2794)
							(mid -0.249642 -0.249642)
							(end -0.2794 -0.1778)
						)
						(arc
							(start -0.2794 0.1778)
							(mid -0.249642 0.249642)
							(end -0.1778 0.2794)
						)
						(arc
							(start 0.1778 0.2794)
							(mid 0.249642 0.249642)
							(end 0.2794 0.1778)
						)
						(arc
							(start 0.2794 -0.1778)
							(mid 0.249642 -0.249642)
							(end 0.1778 -0.2794)
						)
					)
					(width 0)
					(fill yes)
				)
			)
		)
		(pad "2" smd custom
			(at 0 0.4445 270)
			(size 0.1397 0.1397)
			(layers "F.Cu" "F.Mask" "F.Paste")
			(net "FANTACH_R2")
			(options
				(clearance outline)
				(anchor circle)
			)
			(primitives
				(gr_poly
					(pts
						(arc
							(start -0.1778 -0.2794)
							(mid -0.249642 -0.249642)
							(end -0.2794 -0.1778)
						)
						(arc
							(start -0.2794 0.1778)
							(mid -0.249642 0.249642)
							(end -0.1778 0.2794)
						)
						(arc
							(start 0.1778 0.2794)
							(mid 0.249642 0.249642)
							(end 0.2794 0.1778)
						)
						(arc
							(start 0.2794 -0.1778)
							(mid 0.249642 -0.249642)
							(end 0.1778 -0.2794)
						)
					)
					(width 0)
					(fill yes)
				)
			)
		)
	)
	(footprint ""
		(layer "F.Cu")
		(at 20.447 -19.558 180)
		(property "Reference" "Q119"
			(at 0 0 180)
			(layer "F.SilkS")
			(hide yes)
			(effects
				(font
					(size 1.27 1.27)
				)
			)
		)
		(property "Value" "2N7002KDW-GP"
			(at -2.3622 -8.2042 180)
			(unlocked yes)
			(layer "F.Fab")
			(hide yes)
			(effects
				(font
					(size 1.016 1.016)
					(thickness 0.1524)
				)
			)
		)
		(property "Device Type" "SOT-363H44"
			(at -2.3622 -10.1092 180)
			(unlocked yes)
			(layer "F.Fab")
			(hide yes)
			(effects
				(font
					(size 1.016 1.016)
					(thickness 0.1524)
				)
			)
		)
		(duplicate_pad_numbers_are_jumpers no)
		(fp_line
			(start 1.4478 1.7018)
			(end 1.4478 -1.7018)
			(stroke
				(width 0.1524)
				(type default)
			)
			(layer "F.SilkS")
		)
		(fp_line
			(start 1.4478 -1.7018)
			(end -1.4478 -1.7018)
			(stroke
				(width 0.1524)
				(type default)
			)
			(layer "F.SilkS")
		)
		(fp_line
			(start -1.27 1.524)
			(end -1.27 0.6604)
			(stroke
				(width 0.4826)
				(type default)
			)
			(layer "F.SilkS")
		)
		(fp_line
			(start -1.4478 1.7018)
			(end 1.4478 1.7018)
			(stroke
				(width 0.1524)
				(type default)
			)
			(layer "F.SilkS")
		)
		(fp_line
			(start -1.4478 -1.7018)
			(end -1.4478 1.7018)
			(stroke
				(width 0.1524)
				(type default)
			)
			(layer "F.SilkS")
		)
		(fp_poly
			(pts
				(xy -1.524 -1.778) (xy 1.524 -1.778) (xy 1.524 1.778) (xy -1.524 1.778)
			)
			(stroke
				(width 0)
				(type default)
			)
			(fill no)
			(layer "F.CrtYd")
		)
		(fp_poly
			(pts
				(xy -1.524 -1.778) (xy 1.524 -1.778) (xy 1.524 1.778) (xy -1.524 1.778)
			)
			(stroke
				(width 0)
				(type default)
			)
			(fill no)
			(layer "F.Fab")
		)
		(pad "1" smd rect
			(at -0.65024 0.9398 180)
			(size 0.4064 1.016)
			(layers "F.Cu" "F.Mask" "F.Paste")
			(net "GND")
		)
		(pad "2" smd rect
			(at 0 0.9398 180)
			(size 0.4064 1.016)
			(layers "F.Cu" "F.Mask" "F.Paste")
			(net "SW_PWR_R_HDD24")
		)
		(pad "3" smd rect
			(at 0.65024 0.9398 180)
			(size 0.4064 1.016)
			(layers "F.Cu" "F.Mask" "F.Paste")
			(net "SW_HDD_P24")
		)
		(pad "4" smd rect
			(at 0.65024 -0.9398 180)
			(size 0.4064 1.016)
			(layers "F.Cu" "F.Mask" "F.Paste")
			(net "GND")
		)
		(pad "5" smd rect
			(at 0 -0.9398 180)
			(size 0.4064 1.016)
			(layers "F.Cu" "F.Mask" "F.Paste")
			(net "SW_HDD_G24")
		)
		(pad "6" smd rect
			(at -0.65024 -0.9398 180)
			(size 0.4064 1.016)
			(layers "F.Cu" "F.Mask" "F.Paste")
			(net "SW_HDD_R24")
		)
	)
	(footprint ""
		(layer "F.Cu")
		(at 48.514 -214.249)
		(property "Reference" "R220"
			(at 0 0 0)
			(layer "F.SilkS")
			(hide yes)
			(effects
				(font
					(size 1.27 1.27)
				)
			)
		)
		(property "Value" "130R3F-GP"
			(at -0.0254 -2.5146 0)
			(unlocked yes)
			(layer "F.Fab")
			(hide yes)
			(effects
				(font
					(size 1.016 1.016)
					(thickness 0.1524)
				)
			)
		)
		(property "Device Type" "R603H22"
			(at -0.0254 -4.0386 0)
			(unlocked yes)
			(layer "F.Fab")
			(hide yes)
			(effects
				(font
					(size 1.016 1.016)
					(thickness 0.1524)
				)
			)
		)
		(duplicate_pad_numbers_are_jumpers no)
		(fp_line
			(start -0.4826 0)
			(end -0.2032 0)
			(stroke
				(width 0.2032)
				(type default)
			)
			(layer "F.SilkS")
		)
		(fp_line
			(start 0.2032 0)
			(end 0.4826 0)
			(stroke
				(width 0.2032)
				(type default)
			)
			(layer "F.SilkS")
		)
		(fp_rect
			(start -0.5842 1.3335)
			(end 0.5842 -1.3335)
			(stroke
				(width 0)
				(type default)
			)
			(fill no)
			(layer "F.CrtYd")
		)
		(fp_rect
			(start -0.5842 1.3335)
			(end 0.5842 -1.3335)
			(stroke
				(width 0)
				(type default)
			)
			(fill no)
			(layer "F.Fab")
		)
		(pad "1" smd custom
			(at 0 -0.762)
			(size 0.2159 0.2159)
			(layers "F.Cu" "F.Mask" "F.Paste")
			(net "P5V_B_1")
			(options
				(clearance outline)
				(anchor circle)
			)
			(primitives
				(gr_poly
					(pts
						(arc
							(start -0.3302 -0.4318)
							(mid -0.402042 -0.402042)
							(end -0.4318 -0.3302)
						)
						(arc
							(start -0.4318 0.3302)
							(mid -0.402042 0.402042)
							(end -0.3302 0.4318)
						)
						(arc
							(start 0.3302 0.4318)
							(mid 0.402042 0.402042)
							(end 0.4318 0.3302)
						)
						(arc
							(start 0.4318 -0.3302)
							(mid 0.402042 -0.402042)
							(end 0.3302 -0.4318)
						)
					)
					(width 0)
					(fill yes)
				)
			)
		)
		(pad "2" smd custom
			(at 0 0.762)
			(size 0.2159 0.2159)
			(layers "F.Cu" "F.Mask" "F.Paste")
			(net "FLT_HDD1")
			(options
				(clearance outline)
				(anchor circle)
			)
			(primitives
				(gr_poly
					(pts
						(arc
							(start -0.3302 -0.4318)
							(mid -0.402042 -0.402042)
							(end -0.4318 -0.3302)
						)
						(arc
							(start -0.4318 0.3302)
							(mid -0.402042 0.402042)
							(end -0.3302 0.4318)
						)
						(arc
							(start 0.3302 0.4318)
							(mid 0.402042 0.402042)
							(end 0.4318 0.3302)
						)
						(arc
							(start 0.4318 -0.3302)
							(mid 0.402042 -0.402042)
							(end 0.3302 -0.4318)
						)
					)
					(width 0)
					(fill yes)
				)
			)
		)
	)
	(footprint ""
		(layer "F.Cu")
		(at 133.149594 -363.457236 180)
		(property "Reference" "C526"
			(at 0 0 180)
			(layer "F.SilkS")
			(hide yes)
			(effects
				(font
					(size 1.27 1.27)
				)
			)
		)
		(property "Value" "SCD1U25V2KX-2-GP"
			(at 1.1811 -2.7051 180)
			(unlocked yes)
			(layer "F.Fab")
			(hide yes)
			(effects
				(font
					(size 1.016 1.016)
					(thickness 0.1524)
				)
			)
		)
		(property "Device Type" "C402H22"
			(at 1.1811 -4.2291 180)
			(unlocked yes)
			(layer "F.Fab")
			(hide yes)
			(effects
				(font
					(size 1.016 1.016)
					(thickness 0.1524)
				)
			)
		)
		(duplicate_pad_numbers_are_jumpers no)
		(fp_rect
			(start -0.4318 0.9525)
			(end 0.4318 -0.9525)
			(stroke
				(width 0)
				(type default)
			)
			(fill no)
			(layer "F.CrtYd")
		)
		(fp_rect
			(start -0.4318 0.9525)
			(end 0.4318 -0.9525)
			(stroke
				(width 0)
				(type default)
			)
			(fill no)
			(layer "F.Fab")
		)
		(pad "1" smd custom
			(at 0 -0.4445 180)
			(size 0.1524 0.1524)
			(layers "F.Cu" "F.Mask" "F.Paste")
			(net "P12V_FAN1")
			(options
				(clearance outline)
				(anchor circle)
			)
			(primitives
				(gr_poly
					(pts
						(arc
							(start 0.3048 -0.2032)
							(mid 0.275042 -0.275042)
							(end 0.2032 -0.3048)
						)
						(arc
							(start -0.2032 -0.3048)
							(mid -0.275042 -0.275042)
							(end -0.3048 -0.2032)
						)
						(arc
							(start -0.3048 0.2032)
							(mid -0.275042 0.275042)
							(end -0.2032 0.3048)
						)
						(arc
							(start 0.2032 0.3048)
							(mid 0.275042 0.275042)
							(end 0.3048 0.2032)
						)
					)
					(width 0)
					(fill yes)
				)
			)
		)
		(pad "2" smd custom
			(at 0 0.4445 180)
			(size 0.1524 0.1524)
			(layers "F.Cu" "F.Mask" "F.Paste")
			(net "GND")
			(options
				(clearance outline)
				(anchor circle)
			)
			(primitives
				(gr_poly
					(pts
						(arc
							(start 0.3048 -0.2032)
							(mid 0.275042 -0.275042)
							(end 0.2032 -0.3048)
						)
						(arc
							(start -0.2032 -0.3048)
							(mid -0.275042 -0.275042)
							(end -0.3048 -0.2032)
						)
						(arc
							(start -0.3048 0.2032)
							(mid -0.275042 0.275042)
							(end -0.2032 0.3048)
						)
						(arc
							(start 0.2032 0.3048)
							(mid 0.275042 0.275042)
							(end 0.3048 0.2032)
						)
					)
					(width 0)
					(fill yes)
				)
			)
		)
	)
	(footprint ""
		(layer "F.Cu")
		(at 426.72 -131.318 -90)
		(property "Reference" "Q101"
			(at 0 0 270)
			(layer "F.SilkS")
			(hide yes)
			(effects
				(font
					(size 1.27 1.27)
				)
			)
		)
		(property "Value" "2N7002KDW-GP"
			(at -2.3622 -8.2042 270)
			(unlocked yes)
			(layer "F.Fab")
			(hide yes)
			(effects
				(font
					(size 1.016 1.016)
					(thickness 0.1524)
				)
			)
		)
		(property "Device Type" "SOT-363H44"
			(at -2.3622 -10.1092 270)
			(unlocked yes)
			(layer "F.Fab")
			(hide yes)
			(effects
				(font
					(size 1.016 1.016)
					(thickness 0.1524)
				)
			)
		)
		(duplicate_pad_numbers_are_jumpers no)
		(fp_line
			(start -1.4478 1.7018)
			(end 1.4478 1.7018)
			(stroke
				(width 0.1524)
				(type default)
			)
			(layer "F.SilkS")
		)
		(fp_line
			(start 1.4478 1.7018)
			(end 1.4478 -1.7018)
			(stroke
				(width 0.1524)
				(type default)
			)
			(layer "F.SilkS")
		)
		(fp_line
			(start -1.27 1.524)
			(end -1.27 0.6604)
			(stroke
				(width 0.4826)
				(type default)
			)
			(layer "F.SilkS")
		)
		(fp_line
			(start -1.4478 -1.7018)
			(end -1.4478 1.7018)
			(stroke
				(width 0.1524)
				(type default)
			)
			(layer "F.SilkS")
		)
		(fp_line
			(start 1.4478 -1.7018)
			(end -1.4478 -1.7018)
			(stroke
				(width 0.1524)
				(type default)
			)
			(layer "F.SilkS")
		)
		(fp_poly
			(pts
				(xy -1.524 -1.778) (xy 1.524 -1.778) (xy 1.524 1.778) (xy -1.524 1.778)
			)
			(stroke
				(width 0)
				(type default)
			)
			(fill no)
			(layer "F.CrtYd")
		)
		(fp_poly
			(pts
				(xy -1.524 -1.778) (xy 1.524 -1.778) (xy 1.524 1.778) (xy -1.524 1.778)
			)
			(stroke
				(width 0)
				(type default)
			)
			(fill no)
			(layer "F.Fab")
		)
		(pad "1" smd rect
			(at -0.65024 0.9398 270)
			(size 0.4064 1.016)
			(layers "F.Cu" "F.Mask" "F.Paste")
			(net "GND")
		)
		(pad "2" smd rect
			(at 0 0.9398 270)
			(size 0.4064 1.016)
			(layers "F.Cu" "F.Mask" "F.Paste")
			(net "SW_PWR_R_HDD21")
		)
		(pad "3" smd rect
			(at 0.65024 0.9398 270)
			(size 0.4064 1.016)
			(layers "F.Cu" "F.Mask" "F.Paste")
			(net "SW_HDD_P21")
		)
		(pad "4" smd rect
			(at 0.65024 -0.9398 270)
			(size 0.4064 1.016)
			(layers "F.Cu" "F.Mask" "F.Paste")
			(net "GND")
		)
		(pad "5" smd rect
			(at 0 -0.9398 270)
			(size 0.4064 1.016)
			(layers "F.Cu" "F.Mask" "F.Paste")
			(net "SW_HDD_G21")
		)
		(pad "6" smd rect
			(at -0.65024 -0.9398 270)
			(size 0.4064 1.016)
			(layers "F.Cu" "F.Mask" "F.Paste")
			(net "SW_HDD_R21")
		)
	)
	(footprint ""
		(layer "F.Cu")
		(at 415.3662 -31.6484 180)
		(property "Reference" "R829"
			(at 0 0 180)
			(layer "F.SilkS")
			(hide yes)
			(effects
				(font
					(size 1.27 1.27)
				)
			)
		)
		(property "Value" "10KR2F-2-GP"
			(at 0.064008 -3.993896 180)
			(unlocked yes)
			(layer "F.Fab")
			(hide yes)
			(effects
				(font
					(size 1.016 1.016)
					(thickness 0.1524)
				)
			)
		)
		(property "Device Type" "R402H16"
			(at 0.064008 -5.517896 180)
			(unlocked yes)
			(layer "F.Fab")
			(hide yes)
			(effects
				(font
					(size 1.016 1.016)
					(thickness 0.1524)
				)
			)
		)
		(duplicate_pad_numbers_are_jumpers no)
		(fp_line
			(start 0.508 -0.9398)
			(end -0.508 -0.9398)
			(stroke
				(width 0.1524)
				(type default)
			)
			(layer "F.SilkS")
		)
		(fp_line
			(start -0.508 -0.9398)
			(end -0.508 0.9398)
			(stroke
				(width 0.1524)
				(type default)
			)
			(layer "F.SilkS")
		)
		(fp_rect
			(start -0.508 0.9398)
			(end 0.508 -0.9398)
			(stroke
				(width 0)
				(type default)
			)
			(fill no)
			(layer "F.CrtYd")
		)
		(fp_rect
			(start -0.508 0.9398)
			(end 0.508 -0.9398)
			(stroke
				(width 0)
				(type default)
			)
			(fill no)
			(layer "F.Fab")
		)
		(pad "1" smd custom
			(at 0 -0.4445 180)
			(size 0.1397 0.1397)
			(layers "F.Cu" "F.Mask" "F.Paste")
			(net "P3V3_STBY_B")
			(options
				(clearance outline)
				(anchor circle)
			)
			(primitives
				(gr_poly
					(pts
						(arc
							(start -0.1778 -0.2794)
							(mid -0.249642 -0.249642)
							(end -0.2794 -0.1778)
						)
						(arc
							(start -0.2794 0.1778)
							(mid -0.249642 0.249642)
							(end -0.1778 0.2794)
						)
						(arc
							(start 0.1778 0.2794)
							(mid 0.249642 0.249642)
							(end 0.2794 0.1778)
						)
						(arc
							(start 0.2794 -0.1778)
							(mid 0.249642 -0.249642)
							(end 0.1778 -0.2794)
						)
					)
					(width 0)
					(fill yes)
				)
			)
		)
		(pad "2" smd custom
			(at 0 0.4445 180)
			(size 0.1397 0.1397)
			(layers "F.Cu" "F.Mask" "F.Paste")
			(net "HDD_PRSNT_33")
			(options
				(clearance outline)
				(anchor circle)
			)
			(primitives
				(gr_poly
					(pts
						(arc
							(start -0.1778 -0.2794)
							(mid -0.249642 -0.249642)
							(end -0.2794 -0.1778)
						)
						(arc
							(start -0.2794 0.1778)
							(mid -0.249642 0.249642)
							(end -0.1778 0.2794)
						)
						(arc
							(start 0.1778 0.2794)
							(mid 0.249642 0.249642)
							(end 0.2794 0.1778)
						)
						(arc
							(start 0.2794 -0.1778)
							(mid 0.249642 -0.249642)
							(end 0.1778 -0.2794)
						)
					)
					(width 0)
					(fill yes)
				)
			)
		)
	)
	(footprint ""
		(layer "F.Cu")
		(at 248.285 -310.134 -90)
		(property "Reference" "R1185"
			(at 0 0 270)
			(layer "F.SilkS")
			(hide yes)
			(effects
				(font
					(size 1.27 1.27)
				)
			)
		)
		(property "Value" "0R2J-2-GP"
			(at 0.064008 -3.993896 270)
			(unlocked yes)
			(layer "F.Fab")
			(hide yes)
			(effects
				(font
					(size 1.016 1.016)
					(thickness 0.1524)
				)
			)
		)
		(property "Device Type" "R402H16"
			(at 0.064008 -5.517896 270)
			(unlocked yes)
			(layer "F.Fab")
			(hide yes)
			(effects
				(font
					(size 1.016 1.016)
					(thickness 0.1524)
				)
			)
		)
		(duplicate_pad_numbers_are_jumpers no)
		(fp_line
			(start -0.508 -0.9398)
			(end -0.508 0.9398)
			(stroke
				(width 0.1524)
				(type default)
			)
			(layer "F.SilkS")
		)
		(fp_line
			(start 0.508 -0.9398)
			(end -0.508 -0.9398)
			(stroke
				(width 0.1524)
				(type default)
			)
			(layer "F.SilkS")
		)
		(fp_rect
			(start -0.508 0.9398)
			(end 0.508 -0.9398)
			(stroke
				(width 0)
				(type default)
			)
			(fill no)
			(layer "F.CrtYd")
		)
		(fp_rect
			(start -0.508 0.9398)
			(end 0.508 -0.9398)
			(stroke
				(width 0)
				(type default)
			)
			(fill no)
			(layer "F.Fab")
		)
		(pad "1" smd custom
			(at 0 -0.4445 270)
			(size 0.1397 0.1397)
			(layers "F.Cu" "F.Mask" "F.Paste")
			(net "P3V3_STBY_A")
			(options
				(clearance outline)
				(anchor circle)
			)
			(primitives
				(gr_poly
					(pts
						(arc
							(start -0.1778 -0.2794)
							(mid -0.249642 -0.249642)
							(end -0.2794 -0.1778)
						)
						(arc
							(start -0.2794 0.1778)
							(mid -0.249642 0.249642)
							(end -0.1778 0.2794)
						)
						(arc
							(start 0.1778 0.2794)
							(mid 0.249642 0.249642)
							(end 0.2794 0.1778)
						)
						(arc
							(start 0.2794 -0.1778)
							(mid 0.249642 -0.249642)
							(end 0.1778 -0.2794)
						)
					)
					(width 0)
					(fill yes)
				)
			)
		)
		(pad "2" smd custom
			(at 0 0.4445 270)
			(size 0.1397 0.1397)
			(layers "F.Cu" "F.Mask" "F.Paste")
			(net "MAX31790_A_PWM_ST1")
			(options
				(clearance outline)
				(anchor circle)
			)
			(primitives
				(gr_poly
					(pts
						(arc
							(start -0.1778 -0.2794)
							(mid -0.249642 -0.249642)
							(end -0.2794 -0.1778)
						)
						(arc
							(start -0.2794 0.1778)
							(mid -0.249642 0.249642)
							(end -0.1778 0.2794)
						)
						(arc
							(start 0.1778 0.2794)
							(mid 0.249642 0.249642)
							(end 0.2794 0.1778)
						)
						(arc
							(start 0.2794 -0.1778)
							(mid 0.249642 -0.249642)
							(end 0.1778 -0.2794)
						)
					)
					(width 0)
					(fill yes)
				)
			)
		)
	)
	(footprint ""
		(layer "F.Cu")
		(at 221.375224 -329.060556)
		(property "Reference" "C509"
			(at 0 0 0)
			(layer "F.SilkS")
			(hide yes)
			(effects
				(font
					(size 1.27 1.27)
				)
			)
		)
		(property "Value" "SC22U25V6KX-2-GP-U"
			(at -2.860802 -5.279644 0)
			(unlocked yes)
			(layer "F.Fab")
			(hide yes)
			(effects
				(font
					(size 1.016 1.016)
					(thickness 0.1524)
				)
			)
		)
		(property "Device Type" "C1206-TO0D3H75"
			(at -2.860802 -6.803644 0)
			(unlocked yes)
			(layer "F.Fab")
			(hide yes)
			(effects
				(font
					(size 1.016 1.016)
					(thickness 0.1524)
				)
			)
		)
		(duplicate_pad_numbers_are_jumpers no)
		(fp_line
			(start -1.3081 -2.3749)
			(end 1.3081 -2.3749)
			(stroke
				(width 0.1524)
				(type default)
			)
			(layer "F.SilkS")
		)
		(fp_line
			(start -1.3081 2.3749)
			(end -1.3081 -2.3749)
			(stroke
				(width 0.1524)
				(type default)
			)
			(layer "F.SilkS")
		)
		(fp_line
			(start 1.3081 -2.3749)
			(end 1.3081 2.3749)
			(stroke
				(width 0.1524)
				(type default)
			)
			(layer "F.SilkS")
		)
		(fp_line
			(start 1.3081 2.3749)
			(end -1.3081 2.3749)
			(stroke
				(width 0.1524)
				(type default)
			)
			(layer "F.SilkS")
		)
		(fp_rect
			(start -0.8001 1.6002)
			(end 0.8001 -1.6002)
			(stroke
				(width 0)
				(type default)
			)
			(fill no)
			(layer "F.CrtYd")
		)
		(fp_poly
			(pts
				(xy -1.5621 2.4511) (xy -1.5621 1.6002) (xy 0.8001 1.6002) (xy 0.8001 -1.6002) (xy -0.8001 -1.6002)
				(xy -0.8001 1.5875) (xy -1.5621 1.5875) (xy -1.5621 -2.4511) (xy 1.5621 -2.4511) (xy 1.5621 2.4511)
			)
			(stroke
				(width 0)
				(type default)
			)
			(fill no)
			(layer "F.CrtYd")
		)
		(fp_rect
			(start -1.5621 2.4511)
			(end 1.5621 -2.4511)
			(stroke
				(width 0)
				(type default)
			)
			(fill no)
			(layer "F.Fab")
		)
		(pad "1" smd rect
			(at 0 -1.392936)
			(size 2.1082 1.4478)
			(layers "F.Cu" "F.Mask" "F.Paste")
			(net "P12V_IN")
		)
		(pad "2" smd rect
			(at 0 1.392936)
			(size 2.1082 1.4478)
			(layers "F.Cu" "F.Mask" "F.Paste")
			(net "GND")
		)
	)
	(footprint ""
		(layer "F.Cu")
		(at 190.213488 -15.219426 90)
		(property "Reference" "C405"
			(at 0 0 90)
			(layer "F.SilkS")
			(hide yes)
			(effects
				(font
					(size 1.27 1.27)
				)
			)
		)
		(property "Value" "SCD01U16V1KX-GP"
			(at -2.8321 -1.7399 90)
			(unlocked yes)
			(layer "F.Fab")
			(hide yes)
			(effects
				(font
					(size 1.016 1.016)
					(thickness 0.1524)
				)
			)
		)
		(property "Device Type" "C0201H13"
			(at -2.8321 -3.2639 90)
			(unlocked yes)
			(layer "F.Fab")
			(hide yes)
			(effects
				(font
					(size 1.016 1.016)
					(thickness 0.1524)
				)
			)
		)
		(duplicate_pad_numbers_are_jumpers no)
		(fp_rect
			(start -0.2794 0.6477)
			(end 0.2794 -0.6477)
			(stroke
				(width 0)
				(type default)
			)
			(fill no)
			(layer "F.CrtYd")
		)
		(fp_rect
			(start -0.2794 0.6477)
			(end 0.2794 -0.6477)
			(stroke
				(width 0)
				(type default)
			)
			(fill no)
			(layer "F.Fab")
		)
		(pad "1" smd custom
			(at 0 -0.2794 90)
			(size 0.0762 0.0762)
			(layers "F.Cu" "F.Mask" "F.Paste")
			(net "SAS_HDD_RX_N29")
			(options
				(clearance outline)
				(anchor circle)
			)
			(primitives
				(gr_poly
					(pts
						(arc
							(start 0.1524 -0.127)
							(mid 0.137521 -0.162921)
							(end 0.1016 -0.1778)
						)
						(arc
							(start -0.1016 -0.1778)
							(mid -0.137521 -0.162921)
							(end -0.1524 -0.127)
						)
						(arc
							(start -0.1524 0.127)
							(mid -0.137521 0.162921)
							(end -0.1016 0.1778)
						)
						(arc
							(start 0.1016 0.1778)
							(mid 0.137521 0.162921)
							(end 0.1524 0.127)
						)
					)
					(width 0)
					(fill yes)
				)
			)
		)
		(pad "2" smd custom
			(at 0 0.2794 90)
			(size 0.0762 0.0762)
			(layers "F.Cu" "F.Mask" "F.Paste")
			(net "PHY_SCC_B_TO_DRV_B_29_DN")
			(options
				(clearance outline)
				(anchor circle)
			)
			(primitives
				(gr_poly
					(pts
						(arc
							(start 0.1524 -0.127)
							(mid 0.137521 -0.162921)
							(end 0.1016 -0.1778)
						)
						(arc
							(start -0.1016 -0.1778)
							(mid -0.137521 -0.162921)
							(end -0.1524 -0.127)
						)
						(arc
							(start -0.1524 0.127)
							(mid -0.137521 0.162921)
							(end -0.1016 0.1778)
						)
						(arc
							(start 0.1016 0.1778)
							(mid 0.137521 0.162921)
							(end 0.1524 0.127)
						)
					)
					(width 0)
					(fill yes)
				)
			)
		)
	)
	(footprint ""
		(layer "F.Cu")
		(at 285.016448 -347.541342 180)
		(property "Reference" "R1071"
			(at 0 0 180)
			(layer "F.SilkS")
			(hide yes)
			(effects
				(font
					(size 1.27 1.27)
				)
			)
		)
		(property "Value" "4K7R2F-GP"
			(at 0.064008 -3.993896 180)
			(unlocked yes)
			(layer "F.Fab")
			(hide yes)
			(effects
				(font
					(size 1.016 1.016)
					(thickness 0.1524)
				)
			)
		)
		(property "Device Type" "R402H16"
			(at 0.064008 -5.517896 180)
			(unlocked yes)
			(layer "F.Fab")
			(hide yes)
			(effects
				(font
					(size 1.016 1.016)
					(thickness 0.1524)
				)
			)
		)
		(duplicate_pad_numbers_are_jumpers no)
		(fp_line
			(start 0.508 -0.9398)
			(end -0.508 -0.9398)
			(stroke
				(width 0.1524)
				(type default)
			)
			(layer "F.SilkS")
		)
		(fp_line
			(start -0.508 -0.9398)
			(end -0.508 0.9398)
			(stroke
				(width 0.1524)
				(type default)
			)
			(layer "F.SilkS")
		)
		(fp_rect
			(start -0.508 0.9398)
			(end 0.508 -0.9398)
			(stroke
				(width 0)
				(type default)
			)
			(fill no)
			(layer "F.CrtYd")
		)
		(fp_rect
			(start -0.508 0.9398)
			(end 0.508 -0.9398)
			(stroke
				(width 0)
				(type default)
			)
			(fill no)
			(layer "F.Fab")
		)
		(pad "1" smd custom
			(at 0 -0.4445 180)
			(size 0.1397 0.1397)
			(layers "F.Cu" "F.Mask" "F.Paste")
			(net "P3V3_STBY_B")
			(options
				(clearance outline)
				(anchor circle)
			)
			(primitives
				(gr_poly
					(pts
						(arc
							(start -0.1778 -0.2794)
							(mid -0.249642 -0.249642)
							(end -0.2794 -0.1778)
						)
						(arc
							(start -0.2794 0.1778)
							(mid -0.249642 0.249642)
							(end -0.1778 0.2794)
						)
						(arc
							(start 0.1778 0.2794)
							(mid 0.249642 0.249642)
							(end 0.2794 0.1778)
						)
						(arc
							(start 0.2794 -0.1778)
							(mid 0.249642 -0.249642)
							(end 0.1778 -0.2794)
						)
					)
					(width 0)
					(fill yes)
				)
			)
		)
		(pad "2" smd custom
			(at 0 0.4445 180)
			(size 0.1397 0.1397)
			(layers "F.Cu" "F.Mask" "F.Paste")
			(net "MAX31790_B_ADD1")
			(options
				(clearance outline)
				(anchor circle)
			)
			(primitives
				(gr_poly
					(pts
						(arc
							(start -0.1778 -0.2794)
							(mid -0.249642 -0.249642)
							(end -0.2794 -0.1778)
						)
						(arc
							(start -0.2794 0.1778)
							(mid -0.249642 0.249642)
							(end -0.1778 0.2794)
						)
						(arc
							(start 0.1778 0.2794)
							(mid 0.249642 0.249642)
							(end 0.2794 0.1778)
						)
						(arc
							(start 0.2794 -0.1778)
							(mid 0.249642 -0.249642)
							(end 0.1778 -0.2794)
						)
					)
					(width 0)
					(fill yes)
				)
			)
		)
	)
	(footprint ""
		(layer "F.Cu")
		(at 466.451696 -212.390228 -90)
		(property "Reference" "R325"
			(at 0 0 270)
			(layer "F.SilkS")
			(hide yes)
			(effects
				(font
					(size 1.27 1.27)
				)
			)
		)
		(property "Value" "4K7R2F-GP"
			(at 0.064008 -3.993896 270)
			(unlocked yes)
			(layer "F.Fab")
			(hide yes)
			(effects
				(font
					(size 1.016 1.016)
					(thickness 0.1524)
				)
			)
		)
		(property "Device Type" "R402H16"
			(at 0.064008 -5.517896 270)
			(unlocked yes)
			(layer "F.Fab")
			(hide yes)
			(effects
				(font
					(size 1.016 1.016)
					(thickness 0.1524)
				)
			)
		)
		(duplicate_pad_numbers_are_jumpers no)
		(fp_line
			(start -0.508 -0.9398)
			(end -0.508 0.9398)
			(stroke
				(width 0.1524)
				(type default)
			)
			(layer "F.SilkS")
		)
		(fp_line
			(start 0.508 -0.9398)
			(end -0.508 -0.9398)
			(stroke
				(width 0.1524)
				(type default)
			)
			(layer "F.SilkS")
		)
		(fp_rect
			(start -0.508 0.9398)
			(end 0.508 -0.9398)
			(stroke
				(width 0)
				(type default)
			)
			(fill no)
			(layer "F.CrtYd")
		)
		(fp_rect
			(start -0.508 0.9398)
			(end 0.508 -0.9398)
			(stroke
				(width 0)
				(type default)
			)
			(fill no)
			(layer "F.Fab")
		)
		(pad "1" smd custom
			(at 0 -0.4445 270)
			(size 0.1397 0.1397)
			(layers "F.Cu" "F.Mask" "F.Paste")
			(net "DRIVE_B_11_ACT")
			(options
				(clearance outline)
				(anchor circle)
			)
			(primitives
				(gr_poly
					(pts
						(arc
							(start -0.1778 -0.2794)
							(mid -0.249642 -0.249642)
							(end -0.2794 -0.1778)
						)
						(arc
							(start -0.2794 0.1778)
							(mid -0.249642 0.249642)
							(end -0.1778 0.2794)
						)
						(arc
							(start 0.1778 0.2794)
							(mid 0.249642 0.249642)
							(end 0.2794 0.1778)
						)
						(arc
							(start 0.2794 -0.1778)
							(mid 0.249642 -0.249642)
							(end 0.1778 -0.2794)
						)
					)
					(width 0)
					(fill yes)
				)
			)
		)
		(pad "2" smd custom
			(at 0 0.4445 270)
			(size 0.1397 0.1397)
			(layers "F.Cu" "F.Mask" "F.Paste")
			(net "GND")
			(options
				(clearance outline)
				(anchor circle)
			)
			(primitives
				(gr_poly
					(pts
						(arc
							(start -0.1778 -0.2794)
							(mid -0.249642 -0.249642)
							(end -0.2794 -0.1778)
						)
						(arc
							(start -0.2794 0.1778)
							(mid -0.249642 0.249642)
							(end -0.1778 0.2794)
						)
						(arc
							(start 0.1778 0.2794)
							(mid 0.249642 0.249642)
							(end 0.2794 0.1778)
						)
						(arc
							(start 0.2794 -0.1778)
							(mid 0.249642 -0.249642)
							(end 0.1778 -0.2794)
						)
					)
					(width 0)
					(fill yes)
				)
			)
		)
	)
	(footprint ""
		(layer "F.Cu")
		(at 77.978 -140.462 90)
		(property "Reference" "C221"
			(at 0 0 90)
			(layer "F.SilkS")
			(hide yes)
			(effects
				(font
					(size 1.27 1.27)
				)
			)
		)
		(property "Value" "SCD033U25V2KX-GP"
			(at 1.1811 -2.7051 90)
			(unlocked yes)
			(layer "F.Fab")
			(hide yes)
			(effects
				(font
					(size 1.016 1.016)
					(thickness 0.1524)
				)
			)
		)
		(property "Device Type" "C402H22"
			(at 1.1811 -4.2291 90)
			(unlocked yes)
			(layer "F.Fab")
			(hide yes)
			(effects
				(font
					(size 1.016 1.016)
					(thickness 0.1524)
				)
			)
		)
		(duplicate_pad_numbers_are_jumpers no)
		(fp_rect
			(start -0.4318 0.9525)
			(end 0.4318 -0.9525)
			(stroke
				(width 0)
				(type default)
			)
			(fill no)
			(layer "F.CrtYd")
		)
		(fp_rect
			(start -0.4318 0.9525)
			(end 0.4318 -0.9525)
			(stroke
				(width 0)
				(type default)
			)
			(fill no)
			(layer "F.Fab")
		)
		(pad "1" smd custom
			(at 0 -0.4445 90)
			(size 0.1524 0.1524)
			(layers "F.Cu" "F.Mask" "F.Paste")
			(net "P12V_B")
			(options
				(clearance outline)
				(anchor circle)
			)
			(primitives
				(gr_poly
					(pts
						(arc
							(start 0.3048 -0.2032)
							(mid 0.275042 -0.275042)
							(end 0.2032 -0.3048)
						)
						(arc
							(start -0.2032 -0.3048)
							(mid -0.275042 -0.275042)
							(end -0.3048 -0.2032)
						)
						(arc
							(start -0.3048 0.2032)
							(mid -0.275042 0.275042)
							(end -0.2032 0.3048)
						)
						(arc
							(start 0.2032 0.3048)
							(mid 0.275042 0.275042)
							(end 0.3048 0.2032)
						)
					)
					(width 0)
					(fill yes)
				)
			)
		)
		(pad "2" smd custom
			(at 0 0.4445 90)
			(size 0.1524 0.1524)
			(layers "F.Cu" "F.Mask" "F.Paste")
			(net "SW_HDD_N14")
			(options
				(clearance outline)
				(anchor circle)
			)
			(primitives
				(gr_poly
					(pts
						(arc
							(start 0.3048 -0.2032)
							(mid 0.275042 -0.275042)
							(end 0.2032 -0.3048)
						)
						(arc
							(start -0.2032 -0.3048)
							(mid -0.275042 -0.275042)
							(end -0.3048 -0.2032)
						)
						(arc
							(start -0.3048 0.2032)
							(mid -0.275042 0.275042)
							(end -0.2032 0.3048)
						)
						(arc
							(start 0.2032 0.3048)
							(mid 0.275042 0.275042)
							(end 0.3048 0.2032)
						)
					)
					(width 0)
					(fill yes)
				)
			)
		)
	)
	(footprint ""
		(layer "F.Cu")
		(at 18.923 -150.622 90)
		(property "Reference" "R352"
			(at 0 0 90)
			(layer "F.SilkS")
			(hide yes)
			(effects
				(font
					(size 1.27 1.27)
				)
			)
		)
		(property "Value" "2R6F-GP"
			(at -0.0508 -4.8514 90)
			(unlocked yes)
			(layer "F.Fab")
			(hide yes)
			(effects
				(font
					(size 1.016 1.016)
					(thickness 0.1524)
				)
			)
		)
		(property "Device Type" "R1206H26"
			(at 0 -6.3754 90)
			(unlocked yes)
			(layer "F.Fab")
			(hide yes)
			(effects
				(font
					(size 1.016 1.016)
					(thickness 0.1524)
				)
			)
		)
		(duplicate_pad_numbers_are_jumpers no)
		(fp_line
			(start 1.016 -2.2352)
			(end 1.016 2.2352)
			(stroke
				(width 0.1524)
				(type default)
			)
			(layer "F.SilkS")
		)
		(fp_line
			(start -1.016 -2.2352)
			(end 1.016 -2.2352)
			(stroke
				(width 0.1524)
				(type default)
			)
			(layer "F.SilkS")
		)
		(fp_line
			(start 1.016 2.2352)
			(end -1.016 2.2352)
			(stroke
				(width 0.1524)
				(type default)
			)
			(layer "F.SilkS")
		)
		(fp_line
			(start -1.016 2.2352)
			(end -1.016 -2.2352)
			(stroke
				(width 0.1524)
				(type default)
			)
			(layer "F.SilkS")
		)
		(fp_rect
			(start -1.0922 2.3114)
			(end 1.0922 -2.3114)
			(stroke
				(width 0)
				(type default)
			)
			(fill no)
			(layer "F.CrtYd")
		)
		(fp_poly
			(pts
				(xy -1.0922 -2.3114) (xy 1.0922 -2.3114) (xy 1.0922 2.3114) (xy -1.0922 2.3114)
			)
			(stroke
				(width 0)
				(type default)
			)
			(fill no)
			(layer "F.Fab")
		)
		(pad "1" smd rect
			(at 0 -1.397 90)
			(size 1.651 1.27)
			(layers "F.Cu" "F.Mask" "F.Paste")
			(net "P12V_HDD12")
		)
		(pad "2" smd rect
			(at 0 1.397 90)
			(size 1.651 1.27)
			(layers "F.Cu" "F.Mask" "F.Paste")
			(net "12V_PRE_12")
		)
	)
	(footprint ""
		(layer "F.Cu")
		(at 473.8878 -10.6934 90)
		(property "Reference" "C494"
			(at 0 0 90)
			(layer "F.SilkS")
			(hide yes)
			(effects
				(font
					(size 1.27 1.27)
				)
			)
		)
		(property "Value" "SCD033U25V2KX-GP"
			(at 1.1811 -2.7051 90)
			(unlocked yes)
			(layer "F.Fab")
			(hide yes)
			(effects
				(font
					(size 1.016 1.016)
					(thickness 0.1524)
				)
			)
		)
		(property "Device Type" "C402H22"
			(at 1.1811 -4.2291 90)
			(unlocked yes)
			(layer "F.Fab")
			(hide yes)
			(effects
				(font
					(size 1.016 1.016)
					(thickness 0.1524)
				)
			)
		)
		(duplicate_pad_numbers_are_jumpers no)
		(fp_rect
			(start -0.4318 0.9525)
			(end 0.4318 -0.9525)
			(stroke
				(width 0)
				(type default)
			)
			(fill no)
			(layer "F.CrtYd")
		)
		(fp_rect
			(start -0.4318 0.9525)
			(end 0.4318 -0.9525)
			(stroke
				(width 0)
				(type default)
			)
			(fill no)
			(layer "F.Fab")
		)
		(pad "1" smd custom
			(at 0 -0.4445 90)
			(size 0.1524 0.1524)
			(layers "F.Cu" "F.Mask" "F.Paste")
			(net "P12V_B")
			(options
				(clearance outline)
				(anchor circle)
			)
			(primitives
				(gr_poly
					(pts
						(arc
							(start 0.3048 -0.2032)
							(mid 0.275042 -0.275042)
							(end 0.2032 -0.3048)
						)
						(arc
							(start -0.2032 -0.3048)
							(mid -0.275042 -0.275042)
							(end -0.3048 -0.2032)
						)
						(arc
							(start -0.3048 0.2032)
							(mid -0.275042 0.275042)
							(end -0.2032 0.3048)
						)
						(arc
							(start 0.2032 0.3048)
							(mid 0.275042 0.275042)
							(end 0.3048 0.2032)
						)
					)
					(width 0)
					(fill yes)
				)
			)
		)
		(pad "2" smd custom
			(at 0 0.4445 90)
			(size 0.1524 0.1524)
			(layers "F.Cu" "F.Mask" "F.Paste")
			(net "SW_HDD_N35")
			(options
				(clearance outline)
				(anchor circle)
			)
			(primitives
				(gr_poly
					(pts
						(arc
							(start 0.3048 -0.2032)
							(mid 0.275042 -0.275042)
							(end 0.2032 -0.3048)
						)
						(arc
							(start -0.2032 -0.3048)
							(mid -0.275042 -0.275042)
							(end -0.3048 -0.2032)
						)
						(arc
							(start -0.3048 0.2032)
							(mid -0.275042 0.275042)
							(end -0.2032 0.3048)
						)
						(arc
							(start 0.2032 0.3048)
							(mid 0.275042 0.275042)
							(end 0.3048 0.2032)
						)
					)
					(width 0)
					(fill yes)
				)
			)
		)
	)
	(footprint ""
		(layer "F.Cu")
		(at 87.376 -275.463 180)
		(property "Reference" "C62"
			(at 0 0 180)
			(layer "F.SilkS")
			(hide yes)
			(effects
				(font
					(size 1.27 1.27)
				)
			)
		)
		(property "Value" "SC1U25V3KX-GP"
			(at 0 -2.8194 180)
			(unlocked yes)
			(layer "F.Fab")
			(hide yes)
			(effects
				(font
					(size 1.016 1.016)
					(thickness 0.1524)
				)
			)
		)
		(property "Device Type" "C603H36"
			(at 0 -4.3434 180)
			(unlocked yes)
			(layer "F.Fab")
			(hide yes)
			(effects
				(font
					(size 1.016 1.016)
					(thickness 0.1524)
				)
			)
		)
		(duplicate_pad_numbers_are_jumpers no)
		(fp_line
			(start 0.508 0)
			(end -0.508 0)
			(stroke
				(width 0.2032)
				(type default)
			)
			(layer "F.SilkS")
		)
		(fp_rect
			(start -0.5842 1.3335)
			(end 0.5842 -1.3335)
			(stroke
				(width 0)
				(type default)
			)
			(fill no)
			(layer "F.CrtYd")
		)
		(fp_rect
			(start -0.5842 1.3335)
			(end 0.5842 -1.3335)
			(stroke
				(width 0)
				(type default)
			)
			(fill no)
			(layer "F.Fab")
		)
		(pad "1" smd custom
			(at 0 -0.762 180)
			(size 0.2159 0.2159)
			(layers "F.Cu" "F.Mask" "F.Paste")
			(net "P12V_HDD2")
			(options
				(clearance outline)
				(anchor circle)
			)
			(primitives
				(gr_poly
					(pts
						(arc
							(start -0.3302 -0.4318)
							(mid -0.402042 -0.402042)
							(end -0.4318 -0.3302)
						)
						(arc
							(start -0.4318 0.3302)
							(mid -0.402042 0.402042)
							(end -0.3302 0.4318)
						)
						(arc
							(start 0.3302 0.4318)
							(mid 0.402042 0.402042)
							(end 0.4318 0.3302)
						)
						(arc
							(start 0.4318 -0.3302)
							(mid 0.402042 -0.402042)
							(end 0.3302 -0.4318)
						)
					)
					(width 0)
					(fill yes)
				)
			)
		)
		(pad "2" smd custom
			(at 0 0.762 180)
			(size 0.2159 0.2159)
			(layers "F.Cu" "F.Mask" "F.Paste")
			(net "GND")
			(options
				(clearance outline)
				(anchor circle)
			)
			(primitives
				(gr_poly
					(pts
						(arc
							(start -0.3302 -0.4318)
							(mid -0.402042 -0.402042)
							(end -0.4318 -0.3302)
						)
						(arc
							(start -0.4318 0.3302)
							(mid -0.402042 0.402042)
							(end -0.3302 0.4318)
						)
						(arc
							(start 0.3302 0.4318)
							(mid 0.402042 0.402042)
							(end 0.4318 0.3302)
						)
						(arc
							(start 0.4318 -0.3302)
							(mid 0.402042 -0.402042)
							(end 0.3302 -0.4318)
						)
					)
					(width 0)
					(fill yes)
				)
			)
		)
	)
	(footprint ""
		(layer "F.Cu")
		(at 259.089906 -228.84511 -90)
		(property "Reference" "R168"
			(at 0 0 270)
			(layer "F.SilkS")
			(hide yes)
			(effects
				(font
					(size 1.27 1.27)
				)
			)
		)
		(property "Value" "16K2R2F-GP"
			(at 0.064008 -3.993896 270)
			(unlocked yes)
			(layer "F.Fab")
			(hide yes)
			(effects
				(font
					(size 1.016 1.016)
					(thickness 0.1524)
				)
			)
		)
		(property "Device Type" "R402H16"
			(at 0.064008 -5.517896 270)
			(unlocked yes)
			(layer "F.Fab")
			(hide yes)
			(effects
				(font
					(size 1.016 1.016)
					(thickness 0.1524)
				)
			)
		)
		(duplicate_pad_numbers_are_jumpers no)
		(fp_line
			(start -0.508 -0.9398)
			(end -0.508 0.9398)
			(stroke
				(width 0.1524)
				(type default)
			)
			(layer "F.SilkS")
		)
		(fp_line
			(start 0.508 -0.9398)
			(end -0.508 -0.9398)
			(stroke
				(width 0.1524)
				(type default)
			)
			(layer "F.SilkS")
		)
		(fp_rect
			(start -0.508 0.9398)
			(end 0.508 -0.9398)
			(stroke
				(width 0)
				(type default)
			)
			(fill no)
			(layer "F.CrtYd")
		)
		(fp_rect
			(start -0.508 0.9398)
			(end 0.508 -0.9398)
			(stroke
				(width 0)
				(type default)
			)
			(fill no)
			(layer "F.Fab")
		)
		(pad "1" smd custom
			(at 0 -0.4445 270)
			(size 0.1397 0.1397)
			(layers "F.Cu" "F.Mask" "F.Paste")
			(net "P5V_B_3")
			(options
				(clearance outline)
				(anchor circle)
			)
			(primitives
				(gr_poly
					(pts
						(arc
							(start -0.1778 -0.2794)
							(mid -0.249642 -0.249642)
							(end -0.2794 -0.1778)
						)
						(arc
							(start -0.2794 0.1778)
							(mid -0.249642 0.249642)
							(end -0.1778 0.2794)
						)
						(arc
							(start 0.1778 0.2794)
							(mid 0.249642 0.249642)
							(end 0.2794 0.1778)
						)
						(arc
							(start 0.2794 -0.1778)
							(mid 0.249642 -0.249642)
							(end 0.1778 -0.2794)
						)
					)
					(width 0)
					(fill yes)
				)
			)
		)
		(pad "2" smd custom
			(at 0 0.4445 270)
			(size 0.1397 0.1397)
			(layers "F.Cu" "F.Mask" "F.Paste")
			(net "P5V_B_3_SENSE")
			(options
				(clearance outline)
				(anchor circle)
			)
			(primitives
				(gr_poly
					(pts
						(arc
							(start -0.1778 -0.2794)
							(mid -0.249642 -0.249642)
							(end -0.2794 -0.1778)
						)
						(arc
							(start -0.2794 0.1778)
							(mid -0.249642 0.249642)
							(end -0.1778 0.2794)
						)
						(arc
							(start 0.1778 0.2794)
							(mid 0.249642 0.249642)
							(end 0.2794 0.1778)
						)
						(arc
							(start 0.2794 -0.1778)
							(mid 0.249642 -0.249642)
							(end 0.1778 -0.2794)
						)
					)
					(width 0)
					(fill yes)
				)
			)
		)
	)
	(footprint ""
		(layer "F.Cu")
		(at 459.613 -160.02 180)
		(property "Reference" "C322"
			(at 0 0 180)
			(layer "F.SilkS")
			(hide yes)
			(effects
				(font
					(size 1.27 1.27)
				)
			)
		)
		(property "Value" "SC4D7U25V5KX-1-GP"
			(at -0.0762 -6.1214 180)
			(unlocked yes)
			(layer "F.Fab")
			(hide yes)
			(effects
				(font
					(size 1.016 1.016)
					(thickness 0.1524)
				)
			)
		)
		(property "Device Type" "C805H58"
			(at -0.0762 -8.1534 180)
			(unlocked yes)
			(layer "F.Fab")
			(hide yes)
			(effects
				(font
					(size 1.016 1.016)
					(thickness 0.1524)
				)
			)
		)
		(duplicate_pad_numbers_are_jumpers no)
		(fp_line
			(start 0.635 0)
			(end -0.635 0)
			(stroke
				(width 0.508)
				(type default)
			)
			(layer "F.SilkS")
		)
		(fp_rect
			(start -0.9652 1.778)
			(end 0.9652 -1.778)
			(stroke
				(width 0)
				(type default)
			)
			(fill no)
			(layer "F.CrtYd")
		)
		(fp_poly
			(pts
				(xy -0.9652 -1.778) (xy 0.9652 -1.778) (xy 0.9652 1.778) (xy -0.9652 1.778)
			)
			(stroke
				(width 0)
				(type default)
			)
			(fill no)
			(layer "F.Fab")
		)
		(pad "1" smd rect
			(at 0 -0.9652 180)
			(size 1.397 1.143)
			(layers "F.Cu" "F.Mask" "F.Paste")
			(net "P12V_HDD22")
		)
		(pad "2" smd rect
			(at 0 0.9652 180)
			(size 1.397 1.143)
			(layers "F.Cu" "F.Mask" "F.Paste")
			(net "GND")
		)
	)
	(footprint ""
		(layer "F.Cu")
		(at 351.336102 -128.627124 180)
		(property "Reference" "VIA39"
			(at 0 0 180)
			(layer "F.SilkS")
			(hide yes)
			(effects
				(font
					(size 1.27 1.27)
				)
			)
		)
		(property "Value" "100OHM-8L-2D36MM-L18-GP"
			(at 3.8989 0.5715 180)
			(unlocked yes)
			(layer "F.Fab")
			(hide yes)
			(effects
				(font
					(size 1.016 1.016)
					(thickness 0.1524)
				)
			)
		)
		(property "Device Type" "VIA-PCIE-4P-414097"
			(at 3.8989 -0.9525 180)
			(unlocked yes)
			(layer "F.Fab")
			(hide yes)
			(effects
				(font
					(size 1.016 1.016)
					(thickness 0.1524)
				)
			)
		)
		(duplicate_pad_numbers_are_jumpers no)
		(fp_rect
			(start -2.0701 0.4826)
			(end 2.0701 -0.4826)
			(stroke
				(width 0)
				(type default)
			)
			(fill no)
			(layer "F.CrtYd")
		)
		(fp_rect
			(start -2.0701 0.4826)
			(end 2.0701 -0.4826)
			(stroke
				(width 0)
				(type default)
			)
			(fill no)
			(layer "F.Fab")
		)
		(pad "1" thru_hole circle
			(at -1.5875 0 180)
			(size 0.508 0.508)
			(drill 0.254)
			(layers "*.Cu" "*.Mask")
			(remove_unused_layers no)
			(net "GND")
			(clearance 0.2286)
			(thermal_gap 0.2286)
		)
		(pad "2" thru_hole circle
			(at -0.5715 0 180)
			(size 0.508 0.508)
			(drill 0.254)
			(layers "*.Cu" "*.Mask")
			(remove_unused_layers no)
			(net "PHY_SCC_B_TO_DRV_B_19_DP")
			(clearance 0.2286)
			(thermal_gap 0.2286)
		)
		(pad "3" thru_hole circle
			(at 0.5715 0 180)
			(size 0.508 0.508)
			(drill 0.254)
			(layers "*.Cu" "*.Mask")
			(remove_unused_layers no)
			(net "PHY_SCC_B_TO_DRV_B_19_DN")
			(clearance 0.2286)
			(thermal_gap 0.2286)
		)
		(pad "4" thru_hole circle
			(at 1.5875 0 180)
			(size 0.508 0.508)
			(drill 0.254)
			(layers "*.Cu" "*.Mask")
			(remove_unused_layers no)
			(net "GND")
			(clearance 0.2286)
			(thermal_gap 0.2286)
		)
	)
	(footprint ""
		(layer "F.Cu")
		(at 158.496 -31.623)
		(property "Reference" "C400"
			(at 0 0 0)
			(layer "F.SilkS")
			(hide yes)
			(effects
				(font
					(size 1.27 1.27)
				)
			)
		)
		(property "Value" "SCD01U50V2KX-1GP"
			(at 1.1811 -2.7051 0)
			(unlocked yes)
			(layer "F.Fab")
			(hide yes)
			(effects
				(font
					(size 1.016 1.016)
					(thickness 0.1524)
				)
			)
		)
		(property "Device Type" "C402H22"
			(at 1.1811 -4.2291 0)
			(unlocked yes)
			(layer "F.Fab")
			(hide yes)
			(effects
				(font
					(size 1.016 1.016)
					(thickness 0.1524)
				)
			)
		)
		(duplicate_pad_numbers_are_jumpers no)
		(fp_rect
			(start -0.4318 0.9525)
			(end 0.4318 -0.9525)
			(stroke
				(width 0)
				(type default)
			)
			(fill no)
			(layer "F.CrtYd")
		)
		(fp_rect
			(start -0.4318 0.9525)
			(end 0.4318 -0.9525)
			(stroke
				(width 0)
				(type default)
			)
			(fill no)
			(layer "F.Fab")
		)
		(pad "1" smd custom
			(at 0 -0.4445)
			(size 0.1524 0.1524)
			(layers "F.Cu" "F.Mask" "F.Paste")
			(net "HDD_PRSNT_28")
			(options
				(clearance outline)
				(anchor circle)
			)
			(primitives
				(gr_poly
					(pts
						(arc
							(start 0.3048 -0.2032)
							(mid 0.275042 -0.275042)
							(end 0.2032 -0.3048)
						)
						(arc
							(start -0.2032 -0.3048)
							(mid -0.275042 -0.275042)
							(end -0.3048 -0.2032)
						)
						(arc
							(start -0.3048 0.2032)
							(mid -0.275042 0.275042)
							(end -0.2032 0.3048)
						)
						(arc
							(start 0.2032 0.3048)
							(mid 0.275042 0.275042)
							(end 0.3048 0.2032)
						)
					)
					(width 0)
					(fill yes)
				)
			)
		)
		(pad "2" smd custom
			(at 0 0.4445)
			(size 0.1524 0.1524)
			(layers "F.Cu" "F.Mask" "F.Paste")
			(net "GND")
			(options
				(clearance outline)
				(anchor circle)
			)
			(primitives
				(gr_poly
					(pts
						(arc
							(start 0.3048 -0.2032)
							(mid 0.275042 -0.275042)
							(end 0.2032 -0.3048)
						)
						(arc
							(start -0.2032 -0.3048)
							(mid -0.275042 -0.275042)
							(end -0.3048 -0.2032)
						)
						(arc
							(start -0.3048 0.2032)
							(mid -0.275042 0.275042)
							(end -0.2032 0.3048)
						)
						(arc
							(start 0.2032 0.3048)
							(mid 0.275042 0.275042)
							(end 0.3048 0.2032)
						)
					)
					(width 0)
					(fill yes)
				)
			)
		)
	)
	(footprint ""
		(layer "F.Cu")
		(at 305.662076 -340.812882 180)
		(property "Reference" "R101"
			(at 0 0 180)
			(layer "F.SilkS")
			(hide yes)
			(effects
				(font
					(size 1.27 1.27)
				)
			)
		)
		(property "Value" "4K7R2F-GP"
			(at 0.064008 -3.993896 180)
			(unlocked yes)
			(layer "F.Fab")
			(hide yes)
			(effects
				(font
					(size 1.016 1.016)
					(thickness 0.1524)
				)
			)
		)
		(property "Device Type" "R402H16"
			(at 0.064008 -5.517896 180)
			(unlocked yes)
			(layer "F.Fab")
			(hide yes)
			(effects
				(font
					(size 1.016 1.016)
					(thickness 0.1524)
				)
			)
		)
		(duplicate_pad_numbers_are_jumpers no)
		(fp_line
			(start 0.508 -0.9398)
			(end -0.508 -0.9398)
			(stroke
				(width 0.1524)
				(type default)
			)
			(layer "F.SilkS")
		)
		(fp_line
			(start -0.508 -0.9398)
			(end -0.508 0.9398)
			(stroke
				(width 0.1524)
				(type default)
			)
			(layer "F.SilkS")
		)
		(fp_rect
			(start -0.508 0.9398)
			(end 0.508 -0.9398)
			(stroke
				(width 0)
				(type default)
			)
			(fill no)
			(layer "F.CrtYd")
		)
		(fp_rect
			(start -0.508 0.9398)
			(end 0.508 -0.9398)
			(stroke
				(width 0)
				(type default)
			)
			(fill no)
			(layer "F.Fab")
		)
		(pad "1" smd custom
			(at 0 -0.4445 180)
			(size 0.1397 0.1397)
			(layers "F.Cu" "F.Mask" "F.Paste")
			(net "PWM_CAMP_SEL1")
			(options
				(clearance outline)
				(anchor circle)
			)
			(primitives
				(gr_poly
					(pts
						(arc
							(start -0.1778 -0.2794)
							(mid -0.249642 -0.249642)
							(end -0.2794 -0.1778)
						)
						(arc
							(start -0.2794 0.1778)
							(mid -0.249642 0.249642)
							(end -0.1778 0.2794)
						)
						(arc
							(start 0.1778 0.2794)
							(mid 0.249642 0.249642)
							(end 0.2794 0.1778)
						)
						(arc
							(start 0.2794 -0.1778)
							(mid 0.249642 -0.249642)
							(end 0.1778 -0.2794)
						)
					)
					(width 0)
					(fill yes)
				)
			)
		)
		(pad "2" smd custom
			(at 0 0.4445 180)
			(size 0.1397 0.1397)
			(layers "F.Cu" "F.Mask" "F.Paste")
			(net "GND")
			(options
				(clearance outline)
				(anchor circle)
			)
			(primitives
				(gr_poly
					(pts
						(arc
							(start -0.1778 -0.2794)
							(mid -0.249642 -0.249642)
							(end -0.2794 -0.1778)
						)
						(arc
							(start -0.2794 0.1778)
							(mid -0.249642 0.249642)
							(end -0.1778 0.2794)
						)
						(arc
							(start 0.1778 0.2794)
							(mid 0.249642 0.249642)
							(end 0.2794 0.1778)
						)
						(arc
							(start 0.2794 -0.1778)
							(mid 0.249642 -0.249642)
							(end 0.1778 -0.2794)
						)
					)
					(width 0)
					(fill yes)
				)
			)
		)
	)
	(footprint ""
		(layer "F.Cu")
		(at 280.4414 -348.2848 90)
		(property "Reference" "R1073"
			(at 0 0 90)
			(layer "F.SilkS")
			(hide yes)
			(effects
				(font
					(size 1.27 1.27)
				)
			)
		)
		(property "Value" "4K7R2F-GP"
			(at 0.064008 -3.993896 90)
			(unlocked yes)
			(layer "F.Fab")
			(hide yes)
			(effects
				(font
					(size 1.016 1.016)
					(thickness 0.1524)
				)
			)
		)
		(property "Device Type" "R402H16"
			(at 0.064008 -5.517896 90)
			(unlocked yes)
			(layer "F.Fab")
			(hide yes)
			(effects
				(font
					(size 1.016 1.016)
					(thickness 0.1524)
				)
			)
		)
		(duplicate_pad_numbers_are_jumpers no)
		(fp_line
			(start 0.508 -0.9398)
			(end -0.508 -0.9398)
			(stroke
				(width 0.1524)
				(type default)
			)
			(layer "F.SilkS")
		)
		(fp_line
			(start -0.508 -0.9398)
			(end -0.508 0.9398)
			(stroke
				(width 0.1524)
				(type default)
			)
			(layer "F.SilkS")
		)
		(fp_rect
			(start -0.508 0.9398)
			(end 0.508 -0.9398)
			(stroke
				(width 0)
				(type default)
			)
			(fill no)
			(layer "F.CrtYd")
		)
		(fp_rect
			(start -0.508 0.9398)
			(end 0.508 -0.9398)
			(stroke
				(width 0)
				(type default)
			)
			(fill no)
			(layer "F.Fab")
		)
		(pad "1" smd custom
			(at 0 -0.4445 90)
			(size 0.1397 0.1397)
			(layers "F.Cu" "F.Mask" "F.Paste")
			(net "P3V3_STBY_B")
			(options
				(clearance outline)
				(anchor circle)
			)
			(primitives
				(gr_poly
					(pts
						(arc
							(start -0.1778 -0.2794)
							(mid -0.249642 -0.249642)
							(end -0.2794 -0.1778)
						)
						(arc
							(start -0.2794 0.1778)
							(mid -0.249642 0.249642)
							(end -0.1778 0.2794)
						)
						(arc
							(start 0.1778 0.2794)
							(mid 0.249642 0.249642)
							(end 0.2794 0.1778)
						)
						(arc
							(start 0.2794 -0.1778)
							(mid 0.249642 -0.249642)
							(end 0.1778 -0.2794)
						)
					)
					(width 0)
					(fill yes)
				)
			)
		)
		(pad "2" smd custom
			(at 0 0.4445 90)
			(size 0.1397 0.1397)
			(layers "F.Cu" "F.Mask" "F.Paste")
			(net "MAX31790_B_FULL_SPEED")
			(options
				(clearance outline)
				(anchor circle)
			)
			(primitives
				(gr_poly
					(pts
						(arc
							(start -0.1778 -0.2794)
							(mid -0.249642 -0.249642)
							(end -0.2794 -0.1778)
						)
						(arc
							(start -0.2794 0.1778)
							(mid -0.249642 0.249642)
							(end -0.1778 0.2794)
						)
						(arc
							(start 0.1778 0.2794)
							(mid 0.249642 0.249642)
							(end 0.2794 0.1778)
						)
						(arc
							(start 0.2794 -0.1778)
							(mid 0.249642 -0.249642)
							(end 0.1778 -0.2794)
						)
					)
					(width 0)
					(fill yes)
				)
			)
		)
	)
	(footprint ""
		(layer "F.Cu")
		(at 479.044 -42.164)
		(property "Reference" "C490"
			(at 0 0 0)
			(layer "F.SilkS")
			(hide yes)
			(effects
				(font
					(size 1.27 1.27)
				)
			)
		)
		(property "Value" "SC4D7U25V5KX-1-GP"
			(at -0.0762 -6.1214 0)
			(unlocked yes)
			(layer "F.Fab")
			(hide yes)
			(effects
				(font
					(size 1.016 1.016)
					(thickness 0.1524)
				)
			)
		)
		(property "Device Type" "C805H58"
			(at -0.0762 -8.1534 0)
			(unlocked yes)
			(layer "F.Fab")
			(hide yes)
			(effects
				(font
					(size 1.016 1.016)
					(thickness 0.1524)
				)
			)
		)
		(duplicate_pad_numbers_are_jumpers no)
		(fp_line
			(start 0.635 0)
			(end -0.635 0)
			(stroke
				(width 0.508)
				(type default)
			)
			(layer "F.SilkS")
		)
		(fp_rect
			(start -0.9652 1.778)
			(end 0.9652 -1.778)
			(stroke
				(width 0)
				(type default)
			)
			(fill no)
			(layer "F.CrtYd")
		)
		(fp_poly
			(pts
				(xy -0.9652 -1.778) (xy 0.9652 -1.778) (xy 0.9652 1.778) (xy -0.9652 1.778)
			)
			(stroke
				(width 0)
				(type default)
			)
			(fill no)
			(layer "F.Fab")
		)
		(pad "1" smd rect
			(at 0 -0.9652)
			(size 1.397 1.143)
			(layers "F.Cu" "F.Mask" "F.Paste")
			(net "P12V_HDD35")
		)
		(pad "2" smd rect
			(at 0 0.9652)
			(size 1.397 1.143)
			(layers "F.Cu" "F.Mask" "F.Paste")
			(net "GND")
		)
	)
	(footprint ""
		(layer "F.Cu")
		(at 354.866702 -17.4371)
		(property "Reference" "VIA64"
			(at 0 0 0)
			(layer "F.SilkS")
			(hide yes)
			(effects
				(font
					(size 1.27 1.27)
				)
			)
		)
		(property "Value" "100OHM-8L-2D36MM-L16-GP"
			(at -3.4036 -0.4572 0)
			(unlocked yes)
			(layer "F.Fab")
			(hide yes)
			(effects
				(font
					(size 1.016 1.016)
					(thickness 0.1524)
				)
			)
		)
		(property "Device Type" "VIA-PCIE-4P-427097"
			(at -3.4036 -1.9812 0)
			(unlocked yes)
			(layer "F.Fab")
			(hide yes)
			(effects
				(font
					(size 1.016 1.016)
					(thickness 0.1524)
				)
			)
		)
		(duplicate_pad_numbers_are_jumpers no)
		(fp_rect
			(start -2.1336 0.4826)
			(end 2.1336 -0.4826)
			(stroke
				(width 0)
				(type default)
			)
			(fill no)
			(layer "F.CrtYd")
		)
		(fp_rect
			(start -2.1336 0.4826)
			(end 2.1336 -0.4826)
			(stroke
				(width 0)
				(type default)
			)
			(fill no)
			(layer "F.Fab")
		)
		(pad "1" thru_hole circle
			(at -1.651 0)
			(size 0.508 0.508)
			(drill 0.254)
			(layers "*.Cu" "*.Mask")
			(remove_unused_layers no)
			(net "GND")
			(clearance 0.2286)
			(thermal_gap 0.2286)
		)
		(pad "2" thru_hole circle
			(at -0.635 0)
			(size 0.508 0.508)
			(drill 0.254)
			(layers "*.Cu" "*.Mask")
			(remove_unused_layers no)
			(net "PHY_DRV_B_TO_SCC_B_31_DP")
			(clearance 0.2286)
			(thermal_gap 0.2286)
		)
		(pad "3" thru_hole circle
			(at 0.635 0)
			(size 0.508 0.508)
			(drill 0.254)
			(layers "*.Cu" "*.Mask")
			(remove_unused_layers no)
			(net "PHY_DRV_B_TO_SCC_B_31_DN")
			(clearance 0.2286)
			(thermal_gap 0.2286)
		)
		(pad "4" thru_hole circle
			(at 1.651 0)
			(size 0.508 0.508)
			(drill 0.254)
			(layers "*.Cu" "*.Mask")
			(remove_unused_layers no)
			(net "GND")
			(clearance 0.2286)
			(thermal_gap 0.2286)
		)
	)
	(footprint ""
		(layer "F.Cu")
		(at 95.563436 -130.21945 90)
		(property "Reference" "C210"
			(at 0 0 90)
			(layer "F.SilkS")
			(hide yes)
			(effects
				(font
					(size 1.27 1.27)
				)
			)
		)
		(property "Value" "SCD01U16V1KX-GP"
			(at -2.8321 -1.7399 90)
			(unlocked yes)
			(layer "F.Fab")
			(hide yes)
			(effects
				(font
					(size 1.016 1.016)
					(thickness 0.1524)
				)
			)
		)
		(property "Device Type" "C0201H13"
			(at -2.8321 -3.2639 90)
			(unlocked yes)
			(layer "F.Fab")
			(hide yes)
			(effects
				(font
					(size 1.016 1.016)
					(thickness 0.1524)
				)
			)
		)
		(duplicate_pad_numbers_are_jumpers no)
		(fp_rect
			(start -0.2794 0.6477)
			(end 0.2794 -0.6477)
			(stroke
				(width 0)
				(type default)
			)
			(fill no)
			(layer "F.CrtYd")
		)
		(fp_rect
			(start -0.2794 0.6477)
			(end 0.2794 -0.6477)
			(stroke
				(width 0)
				(type default)
			)
			(fill no)
			(layer "F.Fab")
		)
		(pad "1" smd custom
			(at 0 -0.2794 90)
			(size 0.0762 0.0762)
			(layers "F.Cu" "F.Mask" "F.Paste")
			(net "SAS_HDD_RX_N14")
			(options
				(clearance outline)
				(anchor circle)
			)
			(primitives
				(gr_poly
					(pts
						(arc
							(start 0.1524 -0.127)
							(mid 0.137521 -0.162921)
							(end 0.1016 -0.1778)
						)
						(arc
							(start -0.1016 -0.1778)
							(mid -0.137521 -0.162921)
							(end -0.1524 -0.127)
						)
						(arc
							(start -0.1524 0.127)
							(mid -0.137521 0.162921)
							(end -0.1016 0.1778)
						)
						(arc
							(start 0.1016 0.1778)
							(mid 0.137521 0.162921)
							(end 0.1524 0.127)
						)
					)
					(width 0)
					(fill yes)
				)
			)
		)
		(pad "2" smd custom
			(at 0 0.2794 90)
			(size 0.0762 0.0762)
			(layers "F.Cu" "F.Mask" "F.Paste")
			(net "PHY_SCC_B_TO_DRV_B_14_DN")
			(options
				(clearance outline)
				(anchor circle)
			)
			(primitives
				(gr_poly
					(pts
						(arc
							(start 0.1524 -0.127)
							(mid 0.137521 -0.162921)
							(end 0.1016 -0.1778)
						)
						(arc
							(start -0.1016 -0.1778)
							(mid -0.137521 -0.162921)
							(end -0.1524 -0.127)
						)
						(arc
							(start -0.1524 0.127)
							(mid -0.137521 0.162921)
							(end -0.1016 0.1778)
						)
						(arc
							(start 0.1016 0.1778)
							(mid 0.137521 0.162921)
							(end 0.1524 0.127)
						)
					)
					(width 0)
					(fill yes)
				)
			)
		)
	)
	(footprint ""
		(layer "F.Cu")
		(at 237.49 -215.265)
		(property "Reference" "R87"
			(at 0 0 0)
			(layer "F.SilkS")
			(hide yes)
			(effects
				(font
					(size 1.27 1.27)
				)
			)
		)
		(property "Value" "0R2J-2-GP"
			(at 0.064008 -3.993896 0)
			(unlocked yes)
			(layer "F.Fab")
			(hide yes)
			(effects
				(font
					(size 1.016 1.016)
					(thickness 0.1524)
				)
			)
		)
		(property "Device Type" "R402H16"
			(at 0.064008 -5.517896 0)
			(unlocked yes)
			(layer "F.Fab")
			(hide yes)
			(effects
				(font
					(size 1.016 1.016)
					(thickness 0.1524)
				)
			)
		)
		(duplicate_pad_numbers_are_jumpers no)
		(fp_line
			(start -0.508 -0.9398)
			(end -0.508 0.9398)
			(stroke
				(width 0.1524)
				(type default)
			)
			(layer "F.SilkS")
		)
		(fp_line
			(start 0.508 -0.9398)
			(end -0.508 -0.9398)
			(stroke
				(width 0.1524)
				(type default)
			)
			(layer "F.SilkS")
		)
		(fp_rect
			(start -0.508 0.9398)
			(end 0.508 -0.9398)
			(stroke
				(width 0)
				(type default)
			)
			(fill no)
			(layer "F.CrtYd")
		)
		(fp_rect
			(start -0.508 0.9398)
			(end 0.508 -0.9398)
			(stroke
				(width 0)
				(type default)
			)
			(fill no)
			(layer "F.Fab")
		)
		(pad "1" smd custom
			(at 0 -0.4445)
			(size 0.1397 0.1397)
			(layers "F.Cu" "F.Mask" "F.Paste")
			(net "IO_EXP3_SCL")
			(options
				(clearance outline)
				(anchor circle)
			)
			(primitives
				(gr_poly
					(pts
						(arc
							(start -0.1778 -0.2794)
							(mid -0.249642 -0.249642)
							(end -0.2794 -0.1778)
						)
						(arc
							(start -0.2794 0.1778)
							(mid -0.249642 0.249642)
							(end -0.1778 0.2794)
						)
						(arc
							(start 0.1778 0.2794)
							(mid 0.249642 0.249642)
							(end 0.2794 0.1778)
						)
						(arc
							(start 0.2794 -0.1778)
							(mid 0.249642 -0.249642)
							(end 0.1778 -0.2794)
						)
					)
					(width 0)
					(fill yes)
				)
			)
		)
		(pad "2" smd custom
			(at 0 0.4445)
			(size 0.1397 0.1397)
			(layers "F.Cu" "F.Mask" "F.Paste")
			(net "I2C_DRIVE_B_PWR_SCL")
			(options
				(clearance outline)
				(anchor circle)
			)
			(primitives
				(gr_poly
					(pts
						(arc
							(start -0.1778 -0.2794)
							(mid -0.249642 -0.249642)
							(end -0.2794 -0.1778)
						)
						(arc
							(start -0.2794 0.1778)
							(mid -0.249642 0.249642)
							(end -0.1778 0.2794)
						)
						(arc
							(start 0.1778 0.2794)
							(mid 0.249642 0.249642)
							(end 0.2794 0.1778)
						)
						(arc
							(start 0.2794 -0.1778)
							(mid 0.249642 -0.249642)
							(end 0.1778 -0.2794)
						)
					)
					(width 0)
					(fill yes)
				)
			)
		)
	)
	(footprint ""
		(layer "F.Cu")
		(at 23.876 -272.288)
		(property "Reference" "C503"
			(at 0 0 0)
			(layer "F.SilkS")
			(hide yes)
			(effects
				(font
					(size 1.27 1.27)
				)
			)
		)
		(property "Value" "SC4D7U25V5KX-1-GP"
			(at -0.0762 -6.1214 0)
			(unlocked yes)
			(layer "F.Fab")
			(hide yes)
			(effects
				(font
					(size 1.016 1.016)
					(thickness 0.1524)
				)
			)
		)
		(property "Device Type" "C805H58"
			(at -0.0762 -8.1534 0)
			(unlocked yes)
			(layer "F.Fab")
			(hide yes)
			(effects
				(font
					(size 1.016 1.016)
					(thickness 0.1524)
				)
			)
		)
		(duplicate_pad_numbers_are_jumpers no)
		(fp_line
			(start 0.635 0)
			(end -0.635 0)
			(stroke
				(width 0.508)
				(type default)
			)
			(layer "F.SilkS")
		)
		(fp_rect
			(start -0.9652 1.778)
			(end 0.9652 -1.778)
			(stroke
				(width 0)
				(type default)
			)
			(fill no)
			(layer "F.CrtYd")
		)
		(fp_poly
			(pts
				(xy -0.9652 -1.778) (xy 0.9652 -1.778) (xy 0.9652 1.778) (xy -0.9652 1.778)
			)
			(stroke
				(width 0)
				(type default)
			)
			(fill no)
			(layer "F.Fab")
		)
		(pad "1" smd rect
			(at 0 -0.9652)
			(size 1.397 1.143)
			(layers "F.Cu" "F.Mask" "F.Paste")
			(net "P12V_HDD0")
		)
		(pad "2" smd rect
			(at 0 0.9652)
			(size 1.397 1.143)
			(layers "F.Cu" "F.Mask" "F.Paste")
			(net "GND")
		)
	)
	(footprint ""
		(layer "F.Cu")
		(at 16.764 -138.049 90)
		(property "Reference" "R355"
			(at 0 0 90)
			(layer "F.SilkS")
			(hide yes)
			(effects
				(font
					(size 1.27 1.27)
				)
			)
		)
		(property "Value" "4K7R2J-2-GP"
			(at 0.064008 -3.993896 90)
			(unlocked yes)
			(layer "F.Fab")
			(hide yes)
			(effects
				(font
					(size 1.016 1.016)
					(thickness 0.1524)
				)
			)
		)
		(property "Device Type" "R402H16"
			(at 0.064008 -5.517896 90)
			(unlocked yes)
			(layer "F.Fab")
			(hide yes)
			(effects
				(font
					(size 1.016 1.016)
					(thickness 0.1524)
				)
			)
		)
		(duplicate_pad_numbers_are_jumpers no)
		(fp_line
			(start 0.508 -0.9398)
			(end -0.508 -0.9398)
			(stroke
				(width 0.1524)
				(type default)
			)
			(layer "F.SilkS")
		)
		(fp_line
			(start -0.508 -0.9398)
			(end -0.508 0.9398)
			(stroke
				(width 0.1524)
				(type default)
			)
			(layer "F.SilkS")
		)
		(fp_rect
			(start -0.508 0.9398)
			(end 0.508 -0.9398)
			(stroke
				(width 0)
				(type default)
			)
			(fill no)
			(layer "F.CrtYd")
		)
		(fp_rect
			(start -0.508 0.9398)
			(end 0.508 -0.9398)
			(stroke
				(width 0)
				(type default)
			)
			(fill no)
			(layer "F.Fab")
		)
		(pad "1" smd custom
			(at 0 -0.4445 90)
			(size 0.1397 0.1397)
			(layers "F.Cu" "F.Mask" "F.Paste")
			(net "P12V_B")
			(options
				(clearance outline)
				(anchor circle)
			)
			(primitives
				(gr_poly
					(pts
						(arc
							(start -0.1778 -0.2794)
							(mid -0.249642 -0.249642)
							(end -0.2794 -0.1778)
						)
						(arc
							(start -0.2794 0.1778)
							(mid -0.249642 0.249642)
							(end -0.1778 0.2794)
						)
						(arc
							(start 0.1778 0.2794)
							(mid 0.249642 0.249642)
							(end 0.2794 0.1778)
						)
						(arc
							(start 0.2794 -0.1778)
							(mid 0.249642 -0.249642)
							(end 0.1778 -0.2794)
						)
					)
					(width 0)
					(fill yes)
				)
			)
		)
		(pad "2" smd custom
			(at 0 0.4445 90)
			(size 0.1397 0.1397)
			(layers "F.Cu" "F.Mask" "F.Paste")
			(net "SW_HDD_P12")
			(options
				(clearance outline)
				(anchor circle)
			)
			(primitives
				(gr_poly
					(pts
						(arc
							(start -0.1778 -0.2794)
							(mid -0.249642 -0.249642)
							(end -0.2794 -0.1778)
						)
						(arc
							(start -0.2794 0.1778)
							(mid -0.249642 0.249642)
							(end -0.1778 0.2794)
						)
						(arc
							(start 0.1778 0.2794)
							(mid 0.249642 0.249642)
							(end 0.2794 0.1778)
						)
						(arc
							(start 0.2794 -0.1778)
							(mid 0.249642 -0.249642)
							(end 0.1778 -0.2794)
						)
					)
					(width 0)
					(fill yes)
				)
			)
		)
	)
	(footprint ""
		(layer "F.Cu")
		(at 52.197 -141.224 180)
		(property "Reference" "Q51"
			(at 0 0 180)
			(layer "F.SilkS")
			(hide yes)
			(effects
				(font
					(size 1.27 1.27)
				)
			)
		)
		(property "Value" "AO4406AL-GP"
			(at -3.707384 -1.5367 180)
			(unlocked yes)
			(layer "F.Fab")
			(hide yes)
			(effects
				(font
					(size 1.016 1.016)
					(thickness 0.1524)
				)
			)
		)
		(property "Device Type" "SOIC8H69"
			(at -3.707384 -3.0607 180)
			(unlocked yes)
			(layer "F.Fab")
			(hide yes)
			(effects
				(font
					(size 1.016 1.016)
					(thickness 0.1524)
				)
			)
		)
		(duplicate_pad_numbers_are_jumpers no)
		(fp_line
			(start 2.1336 1.4224)
			(end 2.1336 -1.4224)
			(stroke
				(width 0.1524)
				(type default)
			)
			(layer "F.SilkS")
		)
		(fp_line
			(start 2.1336 -1.4224)
			(end -2.7432 -1.4224)
			(stroke
				(width 0.1524)
				(type default)
			)
			(layer "F.SilkS")
		)
		(fp_line
			(start -2.1844 -0.0508)
			(end -2.7178 0.508)
			(stroke
				(width 0.1524)
				(type default)
			)
			(layer "F.SilkS")
		)
		(fp_line
			(start -2.6289 3.4417)
			(end -2.6289 1.4732)
			(stroke
				(width 0.381)
				(type default)
			)
			(layer "F.SilkS")
		)
		(fp_line
			(start -2.7178 -0.508)
			(end -2.1844 -0.0508)
			(stroke
				(width 0.1524)
				(type default)
			)
			(layer "F.SilkS")
		)
		(fp_line
			(start -2.7432 1.4224)
			(end 2.1336 1.4224)
			(stroke
				(width 0.1524)
				(type default)
			)
			(layer "F.SilkS")
		)
		(fp_line
			(start -2.7432 1.4224)
			(end -2.6416 1.4224)
			(stroke
				(width 0.1524)
				(type default)
			)
			(layer "F.SilkS")
		)
		(fp_line
			(start -2.7432 -1.4224)
			(end -2.7432 1.4224)
			(stroke
				(width 0.1524)
				(type default)
			)
			(layer "F.SilkS")
		)
		(fp_poly
			(pts
				(xy -2.2098 -1.4224) (xy -2.2098 1.4224) (xy 2.2098 1.4224) (xy 2.2098 -1.4224)
			)
			(stroke
				(width 0)
				(type default)
			)
			(fill yes)
			(layer "F.SilkS")
		)
		(fp_rect
			(start -2.450084 2.999994)
			(end 2.450084 -2.999994)
			(stroke
				(width 0)
				(type default)
			)
			(fill no)
			(layer "F.CrtYd")
		)
		(fp_poly
			(pts
				(xy -2.8194 3.6322) (xy -2.8194 -3.6322) (xy 2.8194 -3.6322) (xy 2.8194 1.18364) (xy 2.450084 1.18364)
				(xy 2.450084 -2.999994) (xy -2.450084 -2.999994) (xy -2.450084 2.999994) (xy 2.450084 2.999994)
				(xy 2.450084 1.18618) (xy 2.8194 1.18618) (xy 2.8194 3.6322)
			)
			(stroke
				(width 0)
				(type default)
			)
			(fill no)
			(layer "F.CrtYd")
		)
		(fp_rect
			(start -2.8194 3.6322)
			(end 2.8194 -3.6322)
			(stroke
				(width 0)
				(type default)
			)
			(fill no)
			(layer "F.Fab")
		)
		(pad "1" smd rect
			(at -1.905 2.54 180)
			(size 0.635 1.651)
			(layers "F.Cu" "F.Mask" "F.Paste")
			(net "P5V_HDD13")
		)
		(pad "2" smd rect
			(at -0.635 2.54 180)
			(size 0.635 1.651)
			(layers "F.Cu" "F.Mask" "F.Paste")
			(net "P5V_HDD13")
		)
		(pad "3" smd rect
			(at 0.635 2.54 180)
			(size 0.635 1.651)
			(layers "F.Cu" "F.Mask" "F.Paste")
			(net "P5V_HDD13")
		)
		(pad "4" smd rect
			(at 1.905 2.54 180)
			(size 0.635 1.651)
			(layers "F.Cu" "F.Mask" "F.Paste")
			(net "SW_HDD_P13")
		)
		(pad "5" smd rect
			(at 1.905 -2.54 180)
			(size 0.635 1.651)
			(layers "F.Cu" "F.Mask" "F.Paste")
			(net "P5V_B_1")
		)
		(pad "6" smd rect
			(at 0.635 -2.54 180)
			(size 0.635 1.651)
			(layers "F.Cu" "F.Mask" "F.Paste")
			(net "P5V_B_1")
		)
		(pad "7" smd rect
			(at -0.635 -2.54 180)
			(size 0.635 1.651)
			(layers "F.Cu" "F.Mask" "F.Paste")
			(net "P5V_B_1")
		)
		(pad "8" smd rect
			(at -1.905 -2.54 180)
			(size 0.635 1.651)
			(layers "F.Cu" "F.Mask" "F.Paste")
			(net "P5V_B_1")
		)
	)
	(footprint ""
		(layer "F.Cu")
		(at 55.499 -272.288)
		(property "Reference" "C49"
			(at 0 0 0)
			(layer "F.SilkS")
			(hide yes)
			(effects
				(font
					(size 1.27 1.27)
				)
			)
		)
		(property "Value" "SC4D7U25V5KX-1-GP"
			(at -0.0762 -6.1214 0)
			(unlocked yes)
			(layer "F.Fab")
			(hide yes)
			(effects
				(font
					(size 1.016 1.016)
					(thickness 0.1524)
				)
			)
		)
		(property "Device Type" "C805H58"
			(at -0.0762 -8.1534 0)
			(unlocked yes)
			(layer "F.Fab")
			(hide yes)
			(effects
				(font
					(size 1.016 1.016)
					(thickness 0.1524)
				)
			)
		)
		(duplicate_pad_numbers_are_jumpers no)
		(fp_line
			(start 0.635 0)
			(end -0.635 0)
			(stroke
				(width 0.508)
				(type default)
			)
			(layer "F.SilkS")
		)
		(fp_rect
			(start -0.9652 1.778)
			(end 0.9652 -1.778)
			(stroke
				(width 0)
				(type default)
			)
			(fill no)
			(layer "F.CrtYd")
		)
		(fp_poly
			(pts
				(xy -0.9652 -1.778) (xy 0.9652 -1.778) (xy 0.9652 1.778) (xy -0.9652 1.778)
			)
			(stroke
				(width 0)
				(type default)
			)
			(fill no)
			(layer "F.Fab")
		)
		(pad "1" smd rect
			(at 0 -0.9652)
			(size 1.397 1.143)
			(layers "F.Cu" "F.Mask" "F.Paste")
			(net "P12V_HDD1")
		)
		(pad "2" smd rect
			(at 0 0.9652)
			(size 1.397 1.143)
			(layers "F.Cu" "F.Mask" "F.Paste")
			(net "GND")
		)
	)
	(footprint ""
		(layer "F.Cu")
		(at 170.199812 -13.999972)
		(property "Reference" ""
			(at 0 0 0)
			(layer "F.SilkS")
			(hide yes)
			(effects
				(font
					(size 1.27 1.27)
				)
			)
		)
		(property "Value" "*"
			(at -6.3373 -0.4572 0)
			(unlocked yes)
			(layer "F.Fab")
			(hide yes)
			(effects
				(font
					(size 1.016 1.016)
					(thickness 0.1524)
				)
			)
		)
		(duplicate_pad_numbers_are_jumpers no)
		(fp_poly
			(pts
				(arc
					(start 5.0673 0)
					(mid -5.0673 0)
					(end 5.0673 0)
				)
			)
			(stroke
				(width 0)
				(type default)
			)
			(fill no)
			(layer "B.CrtYd")
		)
		(fp_poly
			(pts
				(arc
					(start 5.0673 0)
					(mid -5.0673 0)
					(end 5.0673 0)
				)
			)
			(stroke
				(width 0)
				(type default)
			)
			(fill no)
			(layer "F.CrtYd")
		)
		(fp_poly
			(pts
				(arc
					(start 5.0673 0)
					(mid -5.0673 0)
					(end 5.0673 0)
				)
			)
			(stroke
				(width 0)
				(type default)
			)
			(fill no)
			(layer "B.Fab")
		)
		(fp_poly
			(pts
				(arc
					(start 5.0673 0)
					(mid -5.0673 0)
					(end 5.0673 0)
				)
			)
			(stroke
				(width 0)
				(type default)
			)
			(fill no)
			(layer "F.Fab")
		)
		(pad "1" thru_hole circle
			(at 0 0)
			(size 9.525 9.525)
			(drill 3.556)
			(layers "*.Cu" "*.Mask")
			(remove_unused_layers no)
			(net "Net_35")
			(clearance -2.4765)
			(thermal_gap 0.3048)
			(padstack
				(mode front_inner_back)
				(layer "Inner"
					(shape circle)
					(size 3.9624 3.9624)
					(clearance 0.3048)
				)
				(layer "B.Cu"
					(shape circle)
					(size 9.525 9.525)
					(clearance -2.4765)
				)
			)
		)
		(zone
			(layers "F.Cu" "B.Cu" "In1.Cu" "In2.Cu" "In3.Cu" "In4.Cu" "In5.Cu" "In6.Cu")
			(hatch none 0.5)
			(connect_pads
				(clearance 0)
			)
			(min_thickness 0.25)
			(keepout
				(tracks not_allowed)
				(vias allowed)
				(pads allowed)
				(copperpour not_allowed)
				(footprints allowed)
			)
			(placement
				(enabled no)
				(sheetname "")
			)
			(fill
				(thermal_gap 0.5)
				(thermal_bridge_width 0.5)
				(island_removal_mode 0)
			)
			(polygon
				(pts
					(arc
						(start 174.962312 -13.999972)
						(mid 165.437312 -13.999972)
						(end 174.962312 -13.999972)
					)
				)
			)
		)
	)
	(footprint ""
		(layer "F.Cu")
		(at 255.3843 -214.31504)
		(property "Reference" "R117"
			(at 0 0 0)
			(layer "F.SilkS")
			(hide yes)
			(effects
				(font
					(size 1.27 1.27)
				)
			)
		)
		(property "Value" "0R2J-2-GP"
			(at 0.064008 -3.993896 0)
			(unlocked yes)
			(layer "F.Fab")
			(hide yes)
			(effects
				(font
					(size 1.016 1.016)
					(thickness 0.1524)
				)
			)
		)
		(property "Device Type" "R402H16"
			(at 0.064008 -5.517896 0)
			(unlocked yes)
			(layer "F.Fab")
			(hide yes)
			(effects
				(font
					(size 1.016 1.016)
					(thickness 0.1524)
				)
			)
		)
		(duplicate_pad_numbers_are_jumpers no)
		(fp_line
			(start -0.508 -0.9398)
			(end -0.508 0.9398)
			(stroke
				(width 0.1524)
				(type default)
			)
			(layer "F.SilkS")
		)
		(fp_line
			(start 0.508 -0.9398)
			(end -0.508 -0.9398)
			(stroke
				(width 0.1524)
				(type default)
			)
			(layer "F.SilkS")
		)
		(fp_rect
			(start -0.508 0.9398)
			(end 0.508 -0.9398)
			(stroke
				(width 0)
				(type default)
			)
			(fill no)
			(layer "F.CrtYd")
		)
		(fp_rect
			(start -0.508 0.9398)
			(end 0.508 -0.9398)
			(stroke
				(width 0)
				(type default)
			)
			(fill no)
			(layer "F.Fab")
		)
		(pad "1" smd custom
			(at 0 -0.4445)
			(size 0.1397 0.1397)
			(layers "F.Cu" "F.Mask" "F.Paste")
			(net "VOL_SEN_SCL")
			(options
				(clearance outline)
				(anchor circle)
			)
			(primitives
				(gr_poly
					(pts
						(arc
							(start -0.1778 -0.2794)
							(mid -0.249642 -0.249642)
							(end -0.2794 -0.1778)
						)
						(arc
							(start -0.2794 0.1778)
							(mid -0.249642 0.249642)
							(end -0.1778 0.2794)
						)
						(arc
							(start 0.1778 0.2794)
							(mid 0.249642 0.249642)
							(end 0.2794 0.1778)
						)
						(arc
							(start 0.2794 -0.1778)
							(mid 0.249642 -0.249642)
							(end 0.1778 -0.2794)
						)
					)
					(width 0)
					(fill yes)
				)
			)
		)
		(pad "2" smd custom
			(at 0 0.4445)
			(size 0.1397 0.1397)
			(layers "F.Cu" "F.Mask" "F.Paste")
			(net "I2C_DPB_B_SCL_BUF")
			(options
				(clearance outline)
				(anchor circle)
			)
			(primitives
				(gr_poly
					(pts
						(arc
							(start -0.1778 -0.2794)
							(mid -0.249642 -0.249642)
							(end -0.2794 -0.1778)
						)
						(arc
							(start -0.2794 0.1778)
							(mid -0.249642 0.249642)
							(end -0.1778 0.2794)
						)
						(arc
							(start 0.1778 0.2794)
							(mid 0.249642 0.249642)
							(end 0.2794 0.1778)
						)
						(arc
							(start 0.2794 -0.1778)
							(mid 0.249642 -0.249642)
							(end 0.1778 -0.2794)
						)
					)
					(width 0)
					(fill yes)
				)
			)
		)
	)
	(footprint ""
		(layer "F.Cu")
		(at 64.0588 -133.75005 -90)
		(property "Reference" "VIA28"
			(at 0 0 270)
			(layer "F.SilkS")
			(hide yes)
			(effects
				(font
					(size 1.27 1.27)
				)
			)
		)
		(property "Value" "100OHM-8L-2D36MM-L16-GP"
			(at -3.4036 -0.4572 270)
			(unlocked yes)
			(layer "F.Fab")
			(hide yes)
			(effects
				(font
					(size 1.016 1.016)
					(thickness 0.1524)
				)
			)
		)
		(property "Device Type" "VIA-PCIE-4P-427097"
			(at -3.4036 -1.9812 270)
			(unlocked yes)
			(layer "F.Fab")
			(hide yes)
			(effects
				(font
					(size 1.016 1.016)
					(thickness 0.1524)
				)
			)
		)
		(duplicate_pad_numbers_are_jumpers no)
		(fp_rect
			(start -2.1336 0.4826)
			(end 2.1336 -0.4826)
			(stroke
				(width 0)
				(type default)
			)
			(fill no)
			(layer "F.CrtYd")
		)
		(fp_rect
			(start -2.1336 0.4826)
			(end 2.1336 -0.4826)
			(stroke
				(width 0)
				(type default)
			)
			(fill no)
			(layer "F.Fab")
		)
		(pad "1" thru_hole circle
			(at -1.651 0 270)
			(size 0.508 0.508)
			(drill 0.254)
			(layers "*.Cu" "*.Mask")
			(remove_unused_layers no)
			(net "GND")
			(clearance 0.2286)
			(thermal_gap 0.2286)
		)
		(pad "2" thru_hole circle
			(at -0.635 0 270)
			(size 0.508 0.508)
			(drill 0.254)
			(layers "*.Cu" "*.Mask")
			(remove_unused_layers no)
			(net "PHY_DRV_B_TO_SCC_B_13_DP")
			(clearance 0.2286)
			(thermal_gap 0.2286)
		)
		(pad "3" thru_hole circle
			(at 0.635 0 270)
			(size 0.508 0.508)
			(drill 0.254)
			(layers "*.Cu" "*.Mask")
			(remove_unused_layers no)
			(net "PHY_DRV_B_TO_SCC_B_13_DN")
			(clearance 0.2286)
			(thermal_gap 0.2286)
		)
		(pad "4" thru_hole circle
			(at 1.651 0 270)
			(size 0.508 0.508)
			(drill 0.254)
			(layers "*.Cu" "*.Mask")
			(remove_unused_layers no)
			(net "GND")
			(clearance 0.2286)
			(thermal_gap 0.2286)
		)
	)
	(footprint ""
		(layer "F.Cu")
		(at 45.814996 -358.3559)
		(property "Reference" "R147"
			(at 0 0 0)
			(layer "F.SilkS")
			(hide yes)
			(effects
				(font
					(size 1.27 1.27)
				)
			)
		)
		(property "Value" "200KR2F-L-GP"
			(at 0.064008 -3.993896 0)
			(unlocked yes)
			(layer "F.Fab")
			(hide yes)
			(effects
				(font
					(size 1.016 1.016)
					(thickness 0.1524)
				)
			)
		)
		(property "Device Type" "R402H16"
			(at 0.064008 -5.517896 0)
			(unlocked yes)
			(layer "F.Fab")
			(hide yes)
			(effects
				(font
					(size 1.016 1.016)
					(thickness 0.1524)
				)
			)
		)
		(duplicate_pad_numbers_are_jumpers no)
		(fp_line
			(start -0.508 -0.9398)
			(end -0.508 0.9398)
			(stroke
				(width 0.1524)
				(type default)
			)
			(layer "F.SilkS")
		)
		(fp_line
			(start 0.508 -0.9398)
			(end -0.508 -0.9398)
			(stroke
				(width 0.1524)
				(type default)
			)
			(layer "F.SilkS")
		)
		(fp_rect
			(start -0.508 0.9398)
			(end 0.508 -0.9398)
			(stroke
				(width 0)
				(type default)
			)
			(fill no)
			(layer "F.CrtYd")
		)
		(fp_rect
			(start -0.508 0.9398)
			(end 0.508 -0.9398)
			(stroke
				(width 0)
				(type default)
			)
			(fill no)
			(layer "F.Fab")
		)
		(pad "1" smd custom
			(at 0 -0.4445)
			(size 0.1397 0.1397)
			(layers "F.Cu" "F.Mask" "F.Paste")
			(net "GATE_FAN0")
			(options
				(clearance outline)
				(anchor circle)
			)
			(primitives
				(gr_poly
					(pts
						(arc
							(start -0.1778 -0.2794)
							(mid -0.249642 -0.249642)
							(end -0.2794 -0.1778)
						)
						(arc
							(start -0.2794 0.1778)
							(mid -0.249642 0.249642)
							(end -0.1778 0.2794)
						)
						(arc
							(start 0.1778 0.2794)
							(mid 0.249642 0.249642)
							(end 0.2794 0.1778)
						)
						(arc
							(start 0.2794 -0.1778)
							(mid 0.249642 -0.249642)
							(end 0.1778 -0.2794)
						)
					)
					(width 0)
					(fill yes)
				)
			)
		)
		(pad "2" smd custom
			(at 0 0.4445)
			(size 0.1397 0.1397)
			(layers "F.Cu" "F.Mask" "F.Paste")
			(net "GATE_FAN0_R")
			(options
				(clearance outline)
				(anchor circle)
			)
			(primitives
				(gr_poly
					(pts
						(arc
							(start -0.1778 -0.2794)
							(mid -0.249642 -0.249642)
							(end -0.2794 -0.1778)
						)
						(arc
							(start -0.2794 0.1778)
							(mid -0.249642 0.249642)
							(end -0.1778 0.2794)
						)
						(arc
							(start 0.1778 0.2794)
							(mid 0.249642 0.249642)
							(end 0.2794 0.1778)
						)
						(arc
							(start 0.2794 -0.1778)
							(mid 0.249642 -0.249642)
							(end 0.1778 -0.2794)
						)
					)
					(width 0)
					(fill yes)
				)
			)
		)
	)
	(footprint ""
		(layer "F.Cu")
		(at 383.8956 -261.6454 180)
		(property "Reference" "R287"
			(at 0 0 180)
			(layer "F.SilkS")
			(hide yes)
			(effects
				(font
					(size 1.27 1.27)
				)
			)
		)
		(property "Value" "10KR2F-2-GP"
			(at 0.064008 -3.993896 180)
			(unlocked yes)
			(layer "F.Fab")
			(hide yes)
			(effects
				(font
					(size 1.016 1.016)
					(thickness 0.1524)
				)
			)
		)
		(property "Device Type" "R402H16"
			(at 0.064008 -5.517896 180)
			(unlocked yes)
			(layer "F.Fab")
			(hide yes)
			(effects
				(font
					(size 1.016 1.016)
					(thickness 0.1524)
				)
			)
		)
		(duplicate_pad_numbers_are_jumpers no)
		(fp_line
			(start 0.508 -0.9398)
			(end -0.508 -0.9398)
			(stroke
				(width 0.1524)
				(type default)
			)
			(layer "F.SilkS")
		)
		(fp_line
			(start -0.508 -0.9398)
			(end -0.508 0.9398)
			(stroke
				(width 0.1524)
				(type default)
			)
			(layer "F.SilkS")
		)
		(fp_rect
			(start -0.508 0.9398)
			(end 0.508 -0.9398)
			(stroke
				(width 0)
				(type default)
			)
			(fill no)
			(layer "F.CrtYd")
		)
		(fp_rect
			(start -0.508 0.9398)
			(end 0.508 -0.9398)
			(stroke
				(width 0)
				(type default)
			)
			(fill no)
			(layer "F.Fab")
		)
		(pad "1" smd custom
			(at 0 -0.4445 180)
			(size 0.1397 0.1397)
			(layers "F.Cu" "F.Mask" "F.Paste")
			(net "P3V3_STBY_B")
			(options
				(clearance outline)
				(anchor circle)
			)
			(primitives
				(gr_poly
					(pts
						(arc
							(start -0.1778 -0.2794)
							(mid -0.249642 -0.249642)
							(end -0.2794 -0.1778)
						)
						(arc
							(start -0.2794 0.1778)
							(mid -0.249642 0.249642)
							(end -0.1778 0.2794)
						)
						(arc
							(start 0.1778 0.2794)
							(mid 0.249642 0.249642)
							(end 0.2794 0.1778)
						)
						(arc
							(start 0.2794 -0.1778)
							(mid 0.249642 -0.249642)
							(end 0.1778 -0.2794)
						)
					)
					(width 0)
					(fill yes)
				)
			)
		)
		(pad "2" smd custom
			(at 0 0.4445 180)
			(size 0.1397 0.1397)
			(layers "F.Cu" "F.Mask" "F.Paste")
			(net "HDD_PRSNT_8")
			(options
				(clearance outline)
				(anchor circle)
			)
			(primitives
				(gr_poly
					(pts
						(arc
							(start -0.1778 -0.2794)
							(mid -0.249642 -0.249642)
							(end -0.2794 -0.1778)
						)
						(arc
							(start -0.2794 0.1778)
							(mid -0.249642 0.249642)
							(end -0.1778 0.2794)
						)
						(arc
							(start 0.1778 0.2794)
							(mid 0.249642 0.249642)
							(end 0.2794 0.1778)
						)
						(arc
							(start 0.2794 -0.1778)
							(mid 0.249642 -0.249642)
							(end 0.1778 -0.2794)
						)
					)
					(width 0)
					(fill yes)
				)
			)
		)
	)
	(footprint ""
		(layer "F.Cu")
		(at 213.23046 -162.98926 90)
		(property "Reference" "C11"
			(at 0 0 90)
			(layer "F.SilkS")
			(hide yes)
			(effects
				(font
					(size 1.27 1.27)
				)
			)
		)
		(property "Value" "SC1U16V3KX-5GP"
			(at 0 -2.8194 90)
			(unlocked yes)
			(layer "F.Fab")
			(hide yes)
			(effects
				(font
					(size 1.016 1.016)
					(thickness 0.1524)
				)
			)
		)
		(property "Device Type" "C603H36"
			(at 0 -4.3434 90)
			(unlocked yes)
			(layer "F.Fab")
			(hide yes)
			(effects
				(font
					(size 1.016 1.016)
					(thickness 0.1524)
				)
			)
		)
		(duplicate_pad_numbers_are_jumpers no)
		(fp_line
			(start 0.508 0)
			(end -0.508 0)
			(stroke
				(width 0.2032)
				(type default)
			)
			(layer "F.SilkS")
		)
		(fp_rect
			(start -0.5842 1.3335)
			(end 0.5842 -1.3335)
			(stroke
				(width 0)
				(type default)
			)
			(fill no)
			(layer "F.CrtYd")
		)
		(fp_rect
			(start -0.5842 1.3335)
			(end 0.5842 -1.3335)
			(stroke
				(width 0)
				(type default)
			)
			(fill no)
			(layer "F.Fab")
		)
		(pad "1" smd custom
			(at 0 -0.762 90)
			(size 0.2159 0.2159)
			(layers "F.Cu" "F.Mask" "F.Paste")
			(net "P3V3_STBY_B")
			(options
				(clearance outline)
				(anchor circle)
			)
			(primitives
				(gr_poly
					(pts
						(arc
							(start -0.3302 -0.4318)
							(mid -0.402042 -0.402042)
							(end -0.4318 -0.3302)
						)
						(arc
							(start -0.4318 0.3302)
							(mid -0.402042 0.402042)
							(end -0.3302 0.4318)
						)
						(arc
							(start 0.3302 0.4318)
							(mid 0.402042 0.402042)
							(end 0.4318 0.3302)
						)
						(arc
							(start 0.4318 -0.3302)
							(mid 0.402042 -0.402042)
							(end 0.3302 -0.4318)
						)
					)
					(width 0)
					(fill yes)
				)
			)
		)
		(pad "2" smd custom
			(at 0 0.762 90)
			(size 0.2159 0.2159)
			(layers "F.Cu" "F.Mask" "F.Paste")
			(net "GND")
			(options
				(clearance outline)
				(anchor circle)
			)
			(primitives
				(gr_poly
					(pts
						(arc
							(start -0.3302 -0.4318)
							(mid -0.402042 -0.402042)
							(end -0.4318 -0.3302)
						)
						(arc
							(start -0.4318 0.3302)
							(mid -0.402042 0.402042)
							(end -0.3302 0.4318)
						)
						(arc
							(start 0.3302 0.4318)
							(mid 0.402042 0.402042)
							(end 0.4318 0.3302)
						)
						(arc
							(start 0.4318 -0.3302)
							(mid 0.402042 -0.402042)
							(end 0.3302 -0.4318)
						)
					)
					(width 0)
					(fill yes)
				)
			)
		)
	)
	(footprint ""
		(layer "F.Cu")
		(at 323.360796 -378.1044 90)
		(property "Reference" "R1299"
			(at 0 0 90)
			(layer "F.SilkS")
			(hide yes)
			(effects
				(font
					(size 1.27 1.27)
				)
			)
		)
		(property "Value" "4K7R2F-GP"
			(at 0.064008 -3.993896 90)
			(unlocked yes)
			(layer "F.Fab")
			(hide yes)
			(effects
				(font
					(size 1.016 1.016)
					(thickness 0.1524)
				)
			)
		)
		(property "Device Type" "R402H16"
			(at 0.064008 -5.517896 90)
			(unlocked yes)
			(layer "F.Fab")
			(hide yes)
			(effects
				(font
					(size 1.016 1.016)
					(thickness 0.1524)
				)
			)
		)
		(duplicate_pad_numbers_are_jumpers no)
		(fp_line
			(start 0.508 -0.9398)
			(end -0.508 -0.9398)
			(stroke
				(width 0.1524)
				(type default)
			)
			(layer "F.SilkS")
		)
		(fp_line
			(start -0.508 -0.9398)
			(end -0.508 0.9398)
			(stroke
				(width 0.1524)
				(type default)
			)
			(layer "F.SilkS")
		)
		(fp_rect
			(start -0.508 0.9398)
			(end 0.508 -0.9398)
			(stroke
				(width 0)
				(type default)
			)
			(fill no)
			(layer "F.CrtYd")
		)
		(fp_rect
			(start -0.508 0.9398)
			(end 0.508 -0.9398)
			(stroke
				(width 0)
				(type default)
			)
			(fill no)
			(layer "F.Fab")
		)
		(pad "1" smd custom
			(at 0 -0.4445 90)
			(size 0.1397 0.1397)
			(layers "F.Cu" "F.Mask" "F.Paste")
			(net "FAN_YELLOW_LED2")
			(options
				(clearance outline)
				(anchor circle)
			)
			(primitives
				(gr_poly
					(pts
						(arc
							(start -0.1778 -0.2794)
							(mid -0.249642 -0.249642)
							(end -0.2794 -0.1778)
						)
						(arc
							(start -0.2794 0.1778)
							(mid -0.249642 0.249642)
							(end -0.1778 0.2794)
						)
						(arc
							(start 0.1778 0.2794)
							(mid 0.249642 0.249642)
							(end 0.2794 0.1778)
						)
						(arc
							(start 0.2794 -0.1778)
							(mid 0.249642 -0.249642)
							(end 0.1778 -0.2794)
						)
					)
					(width 0)
					(fill yes)
				)
			)
		)
		(pad "2" smd custom
			(at 0 0.4445 90)
			(size 0.1397 0.1397)
			(layers "F.Cu" "F.Mask" "F.Paste")
			(net "P12V_IN")
			(options
				(clearance outline)
				(anchor circle)
			)
			(primitives
				(gr_poly
					(pts
						(arc
							(start -0.1778 -0.2794)
							(mid -0.249642 -0.249642)
							(end -0.2794 -0.1778)
						)
						(arc
							(start -0.2794 0.1778)
							(mid -0.249642 0.249642)
							(end -0.1778 0.2794)
						)
						(arc
							(start 0.1778 0.2794)
							(mid 0.249642 0.249642)
							(end 0.2794 0.1778)
						)
						(arc
							(start 0.2794 -0.1778)
							(mid 0.249642 -0.249642)
							(end 0.1778 -0.2794)
						)
					)
					(width 0)
					(fill yes)
				)
			)
		)
	)
	(footprint ""
		(layer "F.Cu")
		(at 461.584802 -232.16235)
		(property "Reference" "R1135"
			(at 0 0 0)
			(layer "F.SilkS")
			(hide yes)
			(effects
				(font
					(size 1.27 1.27)
				)
			)
		)
		(property "Value" "49K9R2F-L-GP"
			(at 0.064008 -3.993896 0)
			(unlocked yes)
			(layer "F.Fab")
			(hide yes)
			(effects
				(font
					(size 1.016 1.016)
					(thickness 0.1524)
				)
			)
		)
		(property "Device Type" "R402H16"
			(at 0.064008 -5.517896 0)
			(unlocked yes)
			(layer "F.Fab")
			(hide yes)
			(effects
				(font
					(size 1.016 1.016)
					(thickness 0.1524)
				)
			)
		)
		(duplicate_pad_numbers_are_jumpers no)
		(fp_line
			(start -0.508 -0.9398)
			(end -0.508 0.9398)
			(stroke
				(width 0.1524)
				(type default)
			)
			(layer "F.SilkS")
		)
		(fp_line
			(start 0.508 -0.9398)
			(end -0.508 -0.9398)
			(stroke
				(width 0.1524)
				(type default)
			)
			(layer "F.SilkS")
		)
		(fp_rect
			(start -0.508 0.9398)
			(end 0.508 -0.9398)
			(stroke
				(width 0)
				(type default)
			)
			(fill no)
			(layer "F.CrtYd")
		)
		(fp_rect
			(start -0.508 0.9398)
			(end 0.508 -0.9398)
			(stroke
				(width 0)
				(type default)
			)
			(fill no)
			(layer "F.Fab")
		)
		(pad "1" smd custom
			(at 0 -0.4445)
			(size 0.1397 0.1397)
			(layers "F.Cu" "F.Mask" "F.Paste")
			(net "P12V_B")
			(options
				(clearance outline)
				(anchor circle)
			)
			(primitives
				(gr_poly
					(pts
						(arc
							(start -0.1778 -0.2794)
							(mid -0.249642 -0.249642)
							(end -0.2794 -0.1778)
						)
						(arc
							(start -0.2794 0.1778)
							(mid -0.249642 0.249642)
							(end -0.1778 0.2794)
						)
						(arc
							(start 0.1778 0.2794)
							(mid 0.249642 0.249642)
							(end 0.2794 0.1778)
						)
						(arc
							(start 0.2794 -0.1778)
							(mid 0.249642 -0.249642)
							(end 0.1778 -0.2794)
						)
					)
					(width 0)
					(fill yes)
				)
			)
		)
		(pad "2" smd custom
			(at 0 0.4445)
			(size 0.1397 0.1397)
			(layers "F.Cu" "F.Mask" "F.Paste")
			(net "P5V_B_3_EN_R")
			(options
				(clearance outline)
				(anchor circle)
			)
			(primitives
				(gr_poly
					(pts
						(arc
							(start -0.1778 -0.2794)
							(mid -0.249642 -0.249642)
							(end -0.2794 -0.1778)
						)
						(arc
							(start -0.2794 0.1778)
							(mid -0.249642 0.249642)
							(end -0.1778 0.2794)
						)
						(arc
							(start 0.1778 0.2794)
							(mid 0.249642 0.249642)
							(end 0.2794 0.1778)
						)
						(arc
							(start 0.2794 -0.1778)
							(mid 0.249642 -0.249642)
							(end 0.1778 -0.2794)
						)
					)
					(width 0)
					(fill yes)
				)
			)
		)
	)
	(footprint ""
		(layer "F.Cu")
		(at 177.9778 -263.779 -90)
		(property "Reference" "C95"
			(at 0 0 270)
			(layer "F.SilkS")
			(hide yes)
			(effects
				(font
					(size 1.27 1.27)
				)
			)
		)
		(property "Value" "SC1U16V3KX-5GP"
			(at 0 -2.8194 270)
			(unlocked yes)
			(layer "F.Fab")
			(hide yes)
			(effects
				(font
					(size 1.016 1.016)
					(thickness 0.1524)
				)
			)
		)
		(property "Device Type" "C603H36"
			(at 0 -4.3434 270)
			(unlocked yes)
			(layer "F.Fab")
			(hide yes)
			(effects
				(font
					(size 1.016 1.016)
					(thickness 0.1524)
				)
			)
		)
		(duplicate_pad_numbers_are_jumpers no)
		(fp_line
			(start 0.508 0)
			(end -0.508 0)
			(stroke
				(width 0.2032)
				(type default)
			)
			(layer "F.SilkS")
		)
		(fp_rect
			(start -0.5842 1.3335)
			(end 0.5842 -1.3335)
			(stroke
				(width 0)
				(type default)
			)
			(fill no)
			(layer "F.CrtYd")
		)
		(fp_rect
			(start -0.5842 1.3335)
			(end 0.5842 -1.3335)
			(stroke
				(width 0)
				(type default)
			)
			(fill no)
			(layer "F.Fab")
		)
		(pad "1" smd custom
			(at 0 -0.762 270)
			(size 0.2159 0.2159)
			(layers "F.Cu" "F.Mask" "F.Paste")
			(net "P5V_HDD5")
			(options
				(clearance outline)
				(anchor circle)
			)
			(primitives
				(gr_poly
					(pts
						(arc
							(start -0.3302 -0.4318)
							(mid -0.402042 -0.402042)
							(end -0.4318 -0.3302)
						)
						(arc
							(start -0.4318 0.3302)
							(mid -0.402042 0.402042)
							(end -0.3302 0.4318)
						)
						(arc
							(start 0.3302 0.4318)
							(mid 0.402042 0.402042)
							(end 0.4318 0.3302)
						)
						(arc
							(start 0.4318 -0.3302)
							(mid 0.402042 -0.402042)
							(end 0.3302 -0.4318)
						)
					)
					(width 0)
					(fill yes)
				)
			)
		)
		(pad "2" smd custom
			(at 0 0.762 270)
			(size 0.2159 0.2159)
			(layers "F.Cu" "F.Mask" "F.Paste")
			(net "GND")
			(options
				(clearance outline)
				(anchor circle)
			)
			(primitives
				(gr_poly
					(pts
						(arc
							(start -0.3302 -0.4318)
							(mid -0.402042 -0.402042)
							(end -0.4318 -0.3302)
						)
						(arc
							(start -0.4318 0.3302)
							(mid -0.402042 0.402042)
							(end -0.3302 0.4318)
						)
						(arc
							(start 0.3302 0.4318)
							(mid 0.402042 0.402042)
							(end 0.4318 0.3302)
						)
						(arc
							(start 0.4318 -0.3302)
							(mid 0.402042 -0.402042)
							(end 0.3302 -0.4318)
						)
					)
					(width 0)
					(fill yes)
				)
			)
		)
	)
	(footprint ""
		(layer "F.Cu")
		(at 367.284 -13.589 180)
		(property "Reference" "R793"
			(at 0 0 180)
			(layer "F.SilkS")
			(hide yes)
			(effects
				(font
					(size 1.27 1.27)
				)
			)
		)
		(property "Value" "0R2J-2-GP"
			(at 0.064008 -3.993896 180)
			(unlocked yes)
			(layer "F.Fab")
			(hide yes)
			(effects
				(font
					(size 1.016 1.016)
					(thickness 0.1524)
				)
			)
		)
		(property "Device Type" "R402H16"
			(at 0.064008 -5.517896 180)
			(unlocked yes)
			(layer "F.Fab")
			(hide yes)
			(effects
				(font
					(size 1.016 1.016)
					(thickness 0.1524)
				)
			)
		)
		(duplicate_pad_numbers_are_jumpers no)
		(fp_line
			(start 0.508 -0.9398)
			(end -0.508 -0.9398)
			(stroke
				(width 0.1524)
				(type default)
			)
			(layer "F.SilkS")
		)
		(fp_line
			(start -0.508 -0.9398)
			(end -0.508 0.9398)
			(stroke
				(width 0.1524)
				(type default)
			)
			(layer "F.SilkS")
		)
		(fp_rect
			(start -0.508 0.9398)
			(end 0.508 -0.9398)
			(stroke
				(width 0)
				(type default)
			)
			(fill no)
			(layer "F.CrtYd")
		)
		(fp_rect
			(start -0.508 0.9398)
			(end 0.508 -0.9398)
			(stroke
				(width 0)
				(type default)
			)
			(fill no)
			(layer "F.Fab")
		)
		(pad "1" smd custom
			(at 0 -0.4445 180)
			(size 0.1397 0.1397)
			(layers "F.Cu" "F.Mask" "F.Paste")
			(net "DRIVE_B_31_PWR")
			(options
				(clearance outline)
				(anchor circle)
			)
			(primitives
				(gr_poly
					(pts
						(arc
							(start -0.1778 -0.2794)
							(mid -0.249642 -0.249642)
							(end -0.2794 -0.1778)
						)
						(arc
							(start -0.2794 0.1778)
							(mid -0.249642 0.249642)
							(end -0.1778 0.2794)
						)
						(arc
							(start 0.1778 0.2794)
							(mid 0.249642 0.249642)
							(end 0.2794 0.1778)
						)
						(arc
							(start 0.2794 -0.1778)
							(mid 0.249642 -0.249642)
							(end 0.1778 -0.2794)
						)
					)
					(width 0)
					(fill yes)
				)
			)
		)
		(pad "2" smd custom
			(at 0 0.4445 180)
			(size 0.1397 0.1397)
			(layers "F.Cu" "F.Mask" "F.Paste")
			(net "SW_PWR_R_HDD31")
			(options
				(clearance outline)
				(anchor circle)
			)
			(primitives
				(gr_poly
					(pts
						(arc
							(start -0.1778 -0.2794)
							(mid -0.249642 -0.249642)
							(end -0.2794 -0.1778)
						)
						(arc
							(start -0.2794 0.1778)
							(mid -0.249642 0.249642)
							(end -0.1778 0.2794)
						)
						(arc
							(start 0.1778 0.2794)
							(mid 0.249642 0.249642)
							(end 0.2794 0.1778)
						)
						(arc
							(start 0.2794 -0.1778)
							(mid 0.249642 -0.249642)
							(end 0.1778 -0.2794)
						)
					)
					(width 0)
					(fill yes)
				)
			)
		)
	)
	(footprint ""
		(layer "F.Cu")
		(at 265.586972 -353.463606 -90)
		(property "Reference" "R153"
			(at 0 0 270)
			(layer "F.SilkS")
			(hide yes)
			(effects
				(font
					(size 1.27 1.27)
				)
			)
		)
		(property "Value" "0R5J-5-GP"
			(at 0 -8.9535 270)
			(unlocked yes)
			(layer "F.Fab")
			(hide yes)
			(effects
				(font
					(size 1.27 1.016)
					(thickness 0.1524)
				)
			)
		)
		(property "Device Type" "R805H24"
			(at 0 -10.6299 270)
			(unlocked yes)
			(layer "F.Fab")
			(hide yes)
			(effects
				(font
					(size 1.27 1.016)
					(thickness 0.1524)
				)
			)
		)
		(duplicate_pad_numbers_are_jumpers no)
		(fp_line
			(start -0.889 1.7018)
			(end 0.889 1.7018)
			(stroke
				(width 0.1524)
				(type default)
			)
			(layer "F.SilkS")
		)
		(fp_line
			(start 0.889 1.7018)
			(end 0.889 -0.508)
			(stroke
				(width 0.1524)
				(type default)
			)
			(layer "F.SilkS")
		)
		(fp_line
			(start -0.889 0.0762)
			(end -0.889 1.7018)
			(stroke
				(width 0.1524)
				(type default)
			)
			(layer "F.SilkS")
		)
		(fp_line
			(start -0.889 -1.7018)
			(end -0.889 0.2794)
			(stroke
				(width 0.1524)
				(type default)
			)
			(layer "F.SilkS")
		)
		(fp_line
			(start 0.889 -1.7018)
			(end 0.889 -0.381)
			(stroke
				(width 0.1524)
				(type default)
			)
			(layer "F.SilkS")
		)
		(fp_line
			(start 0.889 -1.7018)
			(end -0.889 -1.7018)
			(stroke
				(width 0.1524)
				(type default)
			)
			(layer "F.SilkS")
		)
		(fp_poly
			(pts
				(xy 0.9652 -1.778) (xy 0.9652 1.778) (xy -0.9652 1.778) (xy -0.9652 -1.778)
			)
			(stroke
				(width 0)
				(type default)
			)
			(fill no)
			(layer "F.CrtYd")
		)
		(fp_rect
			(start -0.9652 1.778)
			(end 0.9652 -1.778)
			(stroke
				(width 0)
				(type default)
			)
			(fill no)
			(layer "F.Fab")
		)
		(pad "1" smd rect
			(at 0 -0.9652 270)
			(size 1.397 1.143)
			(layers "F.Cu" "F.Mask" "F.Paste")
			(net "MB3_CM_GATE_R")
		)
		(pad "2" smd rect
			(at 0 0.9652 270)
			(size 1.397 1.143)
			(layers "F.Cu" "F.Mask" "F.Paste")
			(net "MB3_CM_GATE_C")
		)
	)
	(footprint ""
		(layer "F.Cu")
		(at 55.499 -42.291)
		(property "Reference" "C360"
			(at 0 0 0)
			(layer "F.SilkS")
			(hide yes)
			(effects
				(font
					(size 1.27 1.27)
				)
			)
		)
		(property "Value" "SC4D7U25V5KX-1-GP"
			(at -0.0762 -6.1214 0)
			(unlocked yes)
			(layer "F.Fab")
			(hide yes)
			(effects
				(font
					(size 1.016 1.016)
					(thickness 0.1524)
				)
			)
		)
		(property "Device Type" "C805H58"
			(at -0.0762 -8.1534 0)
			(unlocked yes)
			(layer "F.Fab")
			(hide yes)
			(effects
				(font
					(size 1.016 1.016)
					(thickness 0.1524)
				)
			)
		)
		(duplicate_pad_numbers_are_jumpers no)
		(fp_line
			(start 0.635 0)
			(end -0.635 0)
			(stroke
				(width 0.508)
				(type default)
			)
			(layer "F.SilkS")
		)
		(fp_rect
			(start -0.9652 1.778)
			(end 0.9652 -1.778)
			(stroke
				(width 0)
				(type default)
			)
			(fill no)
			(layer "F.CrtYd")
		)
		(fp_poly
			(pts
				(xy -0.9652 -1.778) (xy 0.9652 -1.778) (xy 0.9652 1.778) (xy -0.9652 1.778)
			)
			(stroke
				(width 0)
				(type default)
			)
			(fill no)
			(layer "F.Fab")
		)
		(pad "1" smd rect
			(at 0 -0.9652)
			(size 1.397 1.143)
			(layers "F.Cu" "F.Mask" "F.Paste")
			(net "P12V_HDD25")
		)
		(pad "2" smd rect
			(at 0 0.9652)
			(size 1.397 1.143)
			(layers "F.Cu" "F.Mask" "F.Paste")
			(net "GND")
		)
	)
	(footprint ""
		(layer "F.Cu")
		(at 117.0686 -246.1768 -90)
		(property "Reference" "R214"
			(at 0 0 270)
			(layer "F.SilkS")
			(hide yes)
			(effects
				(font
					(size 1.27 1.27)
				)
			)
		)
		(property "Value" "0R2J-2-GP"
			(at 0.064008 -3.993896 270)
			(unlocked yes)
			(layer "F.Fab")
			(hide yes)
			(effects
				(font
					(size 1.016 1.016)
					(thickness 0.1524)
				)
			)
		)
		(property "Device Type" "R402H16"
			(at 0.064008 -5.517896 270)
			(unlocked yes)
			(layer "F.Fab")
			(hide yes)
			(effects
				(font
					(size 1.016 1.016)
					(thickness 0.1524)
				)
			)
		)
		(duplicate_pad_numbers_are_jumpers no)
		(fp_line
			(start -0.508 -0.9398)
			(end -0.508 0.9398)
			(stroke
				(width 0.1524)
				(type default)
			)
			(layer "F.SilkS")
		)
		(fp_line
			(start 0.508 -0.9398)
			(end -0.508 -0.9398)
			(stroke
				(width 0.1524)
				(type default)
			)
			(layer "F.SilkS")
		)
		(fp_rect
			(start -0.508 0.9398)
			(end 0.508 -0.9398)
			(stroke
				(width 0)
				(type default)
			)
			(fill no)
			(layer "F.CrtYd")
		)
		(fp_rect
			(start -0.508 0.9398)
			(end 0.508 -0.9398)
			(stroke
				(width 0)
				(type default)
			)
			(fill no)
			(layer "F.Fab")
		)
		(pad "1" smd custom
			(at 0 -0.4445 270)
			(size 0.1397 0.1397)
			(layers "F.Cu" "F.Mask" "F.Paste")
			(net "DRIVE_B_3_PWR")
			(options
				(clearance outline)
				(anchor circle)
			)
			(primitives
				(gr_poly
					(pts
						(arc
							(start -0.1778 -0.2794)
							(mid -0.249642 -0.249642)
							(end -0.2794 -0.1778)
						)
						(arc
							(start -0.2794 0.1778)
							(mid -0.249642 0.249642)
							(end -0.1778 0.2794)
						)
						(arc
							(start 0.1778 0.2794)
							(mid 0.249642 0.249642)
							(end 0.2794 0.1778)
						)
						(arc
							(start 0.2794 -0.1778)
							(mid 0.249642 -0.249642)
							(end 0.1778 -0.2794)
						)
					)
					(width 0)
					(fill yes)
				)
			)
		)
		(pad "2" smd custom
			(at 0 0.4445 270)
			(size 0.1397 0.1397)
			(layers "F.Cu" "F.Mask" "F.Paste")
			(net "SW_PWR_R_HDD3")
			(options
				(clearance outline)
				(anchor circle)
			)
			(primitives
				(gr_poly
					(pts
						(arc
							(start -0.1778 -0.2794)
							(mid -0.249642 -0.249642)
							(end -0.2794 -0.1778)
						)
						(arc
							(start -0.2794 0.1778)
							(mid -0.249642 0.249642)
							(end -0.1778 0.2794)
						)
						(arc
							(start 0.1778 0.2794)
							(mid 0.249642 0.249642)
							(end 0.2794 0.1778)
						)
						(arc
							(start 0.2794 -0.1778)
							(mid 0.249642 -0.249642)
							(end 0.1778 -0.2794)
						)
					)
					(width 0)
					(fill yes)
				)
			)
		)
	)
	(footprint ""
		(layer "F.Cu")
		(at 352.3488 -31.6484 180)
		(property "Reference" "R783"
			(at 0 0 180)
			(layer "F.SilkS")
			(hide yes)
			(effects
				(font
					(size 1.27 1.27)
				)
			)
		)
		(property "Value" "10KR2F-2-GP"
			(at 0.064008 -3.993896 180)
			(unlocked yes)
			(layer "F.Fab")
			(hide yes)
			(effects
				(font
					(size 1.016 1.016)
					(thickness 0.1524)
				)
			)
		)
		(property "Device Type" "R402H16"
			(at 0.064008 -5.517896 180)
			(unlocked yes)
			(layer "F.Fab")
			(hide yes)
			(effects
				(font
					(size 1.016 1.016)
					(thickness 0.1524)
				)
			)
		)
		(duplicate_pad_numbers_are_jumpers no)
		(fp_line
			(start 0.508 -0.9398)
			(end -0.508 -0.9398)
			(stroke
				(width 0.1524)
				(type default)
			)
			(layer "F.SilkS")
		)
		(fp_line
			(start -0.508 -0.9398)
			(end -0.508 0.9398)
			(stroke
				(width 0.1524)
				(type default)
			)
			(layer "F.SilkS")
		)
		(fp_rect
			(start -0.508 0.9398)
			(end 0.508 -0.9398)
			(stroke
				(width 0)
				(type default)
			)
			(fill no)
			(layer "F.CrtYd")
		)
		(fp_rect
			(start -0.508 0.9398)
			(end 0.508 -0.9398)
			(stroke
				(width 0)
				(type default)
			)
			(fill no)
			(layer "F.Fab")
		)
		(pad "1" smd custom
			(at 0 -0.4445 180)
			(size 0.1397 0.1397)
			(layers "F.Cu" "F.Mask" "F.Paste")
			(net "P3V3_STBY_B")
			(options
				(clearance outline)
				(anchor circle)
			)
			(primitives
				(gr_poly
					(pts
						(arc
							(start -0.1778 -0.2794)
							(mid -0.249642 -0.249642)
							(end -0.2794 -0.1778)
						)
						(arc
							(start -0.2794 0.1778)
							(mid -0.249642 0.249642)
							(end -0.1778 0.2794)
						)
						(arc
							(start 0.1778 0.2794)
							(mid 0.249642 0.249642)
							(end 0.2794 0.1778)
						)
						(arc
							(start 0.2794 -0.1778)
							(mid 0.249642 -0.249642)
							(end 0.1778 -0.2794)
						)
					)
					(width 0)
					(fill yes)
				)
			)
		)
		(pad "2" smd custom
			(at 0 0.4445 180)
			(size 0.1397 0.1397)
			(layers "F.Cu" "F.Mask" "F.Paste")
			(net "HDD_PRSNT_31")
			(options
				(clearance outline)
				(anchor circle)
			)
			(primitives
				(gr_poly
					(pts
						(arc
							(start -0.1778 -0.2794)
							(mid -0.249642 -0.249642)
							(end -0.2794 -0.1778)
						)
						(arc
							(start -0.2794 0.1778)
							(mid -0.249642 0.249642)
							(end -0.1778 0.2794)
						)
						(arc
							(start 0.1778 0.2794)
							(mid 0.249642 0.249642)
							(end 0.2794 0.1778)
						)
						(arc
							(start 0.2794 -0.1778)
							(mid 0.249642 -0.249642)
							(end 0.1778 -0.2794)
						)
					)
					(width 0)
					(fill yes)
				)
			)
		)
	)
	(footprint ""
		(layer "F.Cu")
		(at 190.258954 -18.750026 -90)
		(property "Reference" "VIA60"
			(at 0 0 270)
			(layer "F.SilkS")
			(hide yes)
			(effects
				(font
					(size 1.27 1.27)
				)
			)
		)
		(property "Value" "100OHM-8L-2D36MM-L16-GP"
			(at -3.4036 -0.4572 270)
			(unlocked yes)
			(layer "F.Fab")
			(hide yes)
			(effects
				(font
					(size 1.016 1.016)
					(thickness 0.1524)
				)
			)
		)
		(property "Device Type" "VIA-PCIE-4P-427097"
			(at -3.4036 -1.9812 270)
			(unlocked yes)
			(layer "F.Fab")
			(hide yes)
			(effects
				(font
					(size 1.016 1.016)
					(thickness 0.1524)
				)
			)
		)
		(duplicate_pad_numbers_are_jumpers no)
		(fp_rect
			(start -2.1336 0.4826)
			(end 2.1336 -0.4826)
			(stroke
				(width 0)
				(type default)
			)
			(fill no)
			(layer "F.CrtYd")
		)
		(fp_rect
			(start -2.1336 0.4826)
			(end 2.1336 -0.4826)
			(stroke
				(width 0)
				(type default)
			)
			(fill no)
			(layer "F.Fab")
		)
		(pad "1" thru_hole circle
			(at -1.651 0 270)
			(size 0.508 0.508)
			(drill 0.254)
			(layers "*.Cu" "*.Mask")
			(remove_unused_layers no)
			(net "GND")
			(clearance 0.2286)
			(thermal_gap 0.2286)
		)
		(pad "2" thru_hole circle
			(at -0.635 0 270)
			(size 0.508 0.508)
			(drill 0.254)
			(layers "*.Cu" "*.Mask")
			(remove_unused_layers no)
			(net "PHY_DRV_B_TO_SCC_B_29_DP")
			(clearance 0.2286)
			(thermal_gap 0.2286)
		)
		(pad "3" thru_hole circle
			(at 0.635 0 270)
			(size 0.508 0.508)
			(drill 0.254)
			(layers "*.Cu" "*.Mask")
			(remove_unused_layers no)
			(net "PHY_DRV_B_TO_SCC_B_29_DN")
			(clearance 0.2286)
			(thermal_gap 0.2286)
		)
		(pad "4" thru_hole circle
			(at 1.651 0 270)
			(size 0.508 0.508)
			(drill 0.254)
			(layers "*.Cu" "*.Mask")
			(remove_unused_layers no)
			(net "GND")
			(clearance 0.2286)
			(thermal_gap 0.2286)
		)
	)
	(footprint ""
		(layer "F.Cu")
		(at 14.859 -145.796)
		(property "Reference" "Q48"
			(at 0 0 0)
			(layer "F.SilkS")
			(hide yes)
			(effects
				(font
					(size 1.27 1.27)
				)
			)
		)
		(property "Value" "AO4407AL-GP"
			(at -3.707384 -1.5367 0)
			(unlocked yes)
			(layer "F.Fab")
			(hide yes)
			(effects
				(font
					(size 1.016 1.016)
					(thickness 0.1524)
				)
			)
		)
		(property "Device Type" "SOIC8H69"
			(at -3.707384 -3.0607 0)
			(unlocked yes)
			(layer "F.Fab")
			(hide yes)
			(effects
				(font
					(size 1.016 1.016)
					(thickness 0.1524)
				)
			)
		)
		(duplicate_pad_numbers_are_jumpers no)
		(fp_line
			(start -2.7432 -1.4224)
			(end -2.7432 1.4224)
			(stroke
				(width 0.1524)
				(type default)
			)
			(layer "F.SilkS")
		)
		(fp_line
			(start -2.7432 1.4224)
			(end -2.6416 1.4224)
			(stroke
				(width 0.1524)
				(type default)
			)
			(layer "F.SilkS")
		)
		(fp_line
			(start -2.7432 1.4224)
			(end 2.1336 1.4224)
			(stroke
				(width 0.1524)
				(type default)
			)
			(layer "F.SilkS")
		)
		(fp_line
			(start -2.7178 -0.508)
			(end -2.1844 -0.0508)
			(stroke
				(width 0.1524)
				(type default)
			)
			(layer "F.SilkS")
		)
		(fp_line
			(start -2.6289 3.4417)
			(end -2.6289 1.4732)
			(stroke
				(width 0.381)
				(type default)
			)
			(layer "F.SilkS")
		)
		(fp_line
			(start -2.1844 -0.0508)
			(end -2.7178 0.508)
			(stroke
				(width 0.1524)
				(type default)
			)
			(layer "F.SilkS")
		)
		(fp_line
			(start 2.1336 -1.4224)
			(end -2.7432 -1.4224)
			(stroke
				(width 0.1524)
				(type default)
			)
			(layer "F.SilkS")
		)
		(fp_line
			(start 2.1336 1.4224)
			(end 2.1336 -1.4224)
			(stroke
				(width 0.1524)
				(type default)
			)
			(layer "F.SilkS")
		)
		(fp_poly
			(pts
				(xy -2.2098 -1.4224) (xy -2.2098 1.4224) (xy 2.2098 1.4224) (xy 2.2098 -1.4224)
			)
			(stroke
				(width 0)
				(type default)
			)
			(fill yes)
			(layer "F.SilkS")
		)
		(fp_rect
			(start -2.450084 2.999994)
			(end 2.450084 -2.999994)
			(stroke
				(width 0)
				(type default)
			)
			(fill no)
			(layer "F.CrtYd")
		)
		(fp_poly
			(pts
				(xy -2.8194 3.6322) (xy -2.8194 -3.6322) (xy 2.8194 -3.6322) (xy 2.8194 1.18364) (xy 2.450084 1.18364)
				(xy 2.450084 -2.999994) (xy -2.450084 -2.999994) (xy -2.450084 2.999994) (xy 2.450084 2.999994)
				(xy 2.450084 1.18618) (xy 2.8194 1.18618) (xy 2.8194 3.6322)
			)
			(stroke
				(width 0)
				(type default)
			)
			(fill no)
			(layer "F.CrtYd")
		)
		(fp_rect
			(start -2.8194 3.6322)
			(end 2.8194 -3.6322)
			(stroke
				(width 0)
				(type default)
			)
			(fill no)
			(layer "F.Fab")
		)
		(pad "1" smd rect
			(at -1.905 2.54)
			(size 0.635 1.651)
			(layers "F.Cu" "F.Mask" "F.Paste")
			(net "P12V_B")
		)
		(pad "2" smd rect
			(at -0.635 2.54)
			(size 0.635 1.651)
			(layers "F.Cu" "F.Mask" "F.Paste")
			(net "P12V_B")
		)
		(pad "3" smd rect
			(at 0.635 2.54)
			(size 0.635 1.651)
			(layers "F.Cu" "F.Mask" "F.Paste")
			(net "P12V_B")
		)
		(pad "4" smd rect
			(at 1.905 2.54)
			(size 0.635 1.651)
			(layers "F.Cu" "F.Mask" "F.Paste")
			(net "SW_HDD_N12")
		)
		(pad "5" smd rect
			(at 1.905 -2.54)
			(size 0.635 1.651)
			(layers "F.Cu" "F.Mask" "F.Paste")
			(net "P12V_HDD12")
		)
		(pad "6" smd rect
			(at 0.635 -2.54)
			(size 0.635 1.651)
			(layers "F.Cu" "F.Mask" "F.Paste")
			(net "P12V_HDD12")
		)
		(pad "7" smd rect
			(at -0.635 -2.54)
			(size 0.635 1.651)
			(layers "F.Cu" "F.Mask" "F.Paste")
			(net "P12V_HDD12")
		)
		(pad "8" smd rect
			(at -1.905 -2.54)
			(size 0.635 1.651)
			(layers "F.Cu" "F.Mask" "F.Paste")
			(net "P12V_HDD12")
		)
	)
	(footprint ""
		(layer "F.Cu")
		(at 477.0628 -153.1366)
		(property "Reference" "TP136"
			(at 0 0 0)
			(layer "F.SilkS")
			(hide yes)
			(effects
				(font
					(size 1.27 1.27)
				)
			)
		)
		(property "Value" "*"
			(at -0.0508 -1.6764 0)
			(unlocked yes)
			(layer "F.Fab")
			(hide yes)
			(effects
				(font
					(size 1.016 1.016)
					(thickness 0.1524)
				)
			)
		)
		(property "Device Type" "TPAD32"
			(at -0.0508 -3.2004 0)
			(unlocked yes)
			(layer "F.Fab")
			(hide yes)
			(effects
				(font
					(size 1.016 1.016)
					(thickness 0.1524)
				)
			)
		)
		(duplicate_pad_numbers_are_jumpers no)
		(fp_poly
			(pts
				(arc
					(start 0.4064 0)
					(mid -0.4064 0)
					(end 0.4064 0)
				)
			)
			(stroke
				(width 0)
				(type default)
			)
			(fill no)
			(layer "F.CrtYd")
		)
		(fp_poly
			(pts
				(arc
					(start 0.7112 0)
					(mid -0.7112 0)
					(end 0.7112 0)
				)
			)
			(stroke
				(width 0)
				(type default)
			)
			(fill no)
			(layer "F.Fab")
		)
		(pad "1" smd circle
			(at 0 0)
			(size 0.8128 0.8128)
			(layers "F.Cu" "F.Mask" "F.Paste")
			(net "ACT_HDD_23")
		)
	)
	(footprint ""
		(layer "F.Cu")
		(at 118.364 -148.209)
		(property "Reference" "R414"
			(at 0 0 0)
			(layer "F.SilkS")
			(hide yes)
			(effects
				(font
					(size 1.27 1.27)
				)
			)
		)
		(property "Value" "2R6F-GP"
			(at -0.0508 -4.8514 0)
			(unlocked yes)
			(layer "F.Fab")
			(hide yes)
			(effects
				(font
					(size 1.016 1.016)
					(thickness 0.1524)
				)
			)
		)
		(property "Device Type" "R1206H26"
			(at 0 -6.3754 0)
			(unlocked yes)
			(layer "F.Fab")
			(hide yes)
			(effects
				(font
					(size 1.016 1.016)
					(thickness 0.1524)
				)
			)
		)
		(duplicate_pad_numbers_are_jumpers no)
		(fp_line
			(start -1.016 -2.2352)
			(end 1.016 -2.2352)
			(stroke
				(width 0.1524)
				(type default)
			)
			(layer "F.SilkS")
		)
		(fp_line
			(start -1.016 2.2352)
			(end -1.016 -2.2352)
			(stroke
				(width 0.1524)
				(type default)
			)
			(layer "F.SilkS")
		)
		(fp_line
			(start 1.016 -2.2352)
			(end 1.016 2.2352)
			(stroke
				(width 0.1524)
				(type default)
			)
			(layer "F.SilkS")
		)
		(fp_line
			(start 1.016 2.2352)
			(end -1.016 2.2352)
			(stroke
				(width 0.1524)
				(type default)
			)
			(layer "F.SilkS")
		)
		(fp_rect
			(start -1.0922 2.3114)
			(end 1.0922 -2.3114)
			(stroke
				(width 0)
				(type default)
			)
			(fill no)
			(layer "F.CrtYd")
		)
		(fp_poly
			(pts
				(xy -1.0922 -2.3114) (xy 1.0922 -2.3114) (xy 1.0922 2.3114) (xy -1.0922 2.3114)
			)
			(stroke
				(width 0)
				(type default)
			)
			(fill no)
			(layer "F.Fab")
		)
		(pad "1" smd rect
			(at 0 -1.397)
			(size 1.651 1.27)
			(layers "F.Cu" "F.Mask" "F.Paste")
			(net "P5V_HDD15")
		)
		(pad "2" smd rect
			(at 0 1.397)
			(size 1.651 1.27)
			(layers "F.Cu" "F.Mask" "F.Paste")
			(net "5V_PRE_15")
		)
	)
	(footprint ""
		(layer "F.Cu")
		(at 64.013334 -14.660626 90)
		(property "Reference" "C354"
			(at 0 0 90)
			(layer "F.SilkS")
			(hide yes)
			(effects
				(font
					(size 1.27 1.27)
				)
			)
		)
		(property "Value" "SCD01U16V1KX-GP"
			(at -2.8321 -1.7399 90)
			(unlocked yes)
			(layer "F.Fab")
			(hide yes)
			(effects
				(font
					(size 1.016 1.016)
					(thickness 0.1524)
				)
			)
		)
		(property "Device Type" "C0201H13"
			(at -2.8321 -3.2639 90)
			(unlocked yes)
			(layer "F.Fab")
			(hide yes)
			(effects
				(font
					(size 1.016 1.016)
					(thickness 0.1524)
				)
			)
		)
		(duplicate_pad_numbers_are_jumpers no)
		(fp_rect
			(start -0.2794 0.6477)
			(end 0.2794 -0.6477)
			(stroke
				(width 0)
				(type default)
			)
			(fill no)
			(layer "F.CrtYd")
		)
		(fp_rect
			(start -0.2794 0.6477)
			(end 0.2794 -0.6477)
			(stroke
				(width 0)
				(type default)
			)
			(fill no)
			(layer "F.Fab")
		)
		(pad "1" smd custom
			(at 0 -0.2794 90)
			(size 0.0762 0.0762)
			(layers "F.Cu" "F.Mask" "F.Paste")
			(net "SAS_HDD_RX_P25")
			(options
				(clearance outline)
				(anchor circle)
			)
			(primitives
				(gr_poly
					(pts
						(arc
							(start 0.1524 -0.127)
							(mid 0.137521 -0.162921)
							(end 0.1016 -0.1778)
						)
						(arc
							(start -0.1016 -0.1778)
							(mid -0.137521 -0.162921)
							(end -0.1524 -0.127)
						)
						(arc
							(start -0.1524 0.127)
							(mid -0.137521 0.162921)
							(end -0.1016 0.1778)
						)
						(arc
							(start 0.1016 0.1778)
							(mid 0.137521 0.162921)
							(end 0.1524 0.127)
						)
					)
					(width 0)
					(fill yes)
				)
			)
		)
		(pad "2" smd custom
			(at 0 0.2794 90)
			(size 0.0762 0.0762)
			(layers "F.Cu" "F.Mask" "F.Paste")
			(net "PHY_SCC_B_TO_DRV_B_25_DP")
			(options
				(clearance outline)
				(anchor circle)
			)
			(primitives
				(gr_poly
					(pts
						(arc
							(start 0.1524 -0.127)
							(mid 0.137521 -0.162921)
							(end 0.1016 -0.1778)
						)
						(arc
							(start -0.1016 -0.1778)
							(mid -0.137521 -0.162921)
							(end -0.1524 -0.127)
						)
						(arc
							(start -0.1524 0.127)
							(mid -0.137521 0.162921)
							(end -0.1016 0.1778)
						)
						(arc
							(start 0.1016 0.1778)
							(mid 0.137521 0.162921)
							(end 0.1524 0.127)
						)
					)
					(width 0)
					(fill yes)
				)
			)
		)
	)
	(footprint ""
		(layer "F.Cu")
		(at 433.324 -28.829 90)
		(property "Reference" "C468"
			(at 0 0 90)
			(layer "F.SilkS")
			(hide yes)
			(effects
				(font
					(size 1.27 1.27)
				)
			)
		)
		(property "Value" "SCD033U25V2KX-GP"
			(at 1.1811 -2.7051 90)
			(unlocked yes)
			(layer "F.Fab")
			(hide yes)
			(effects
				(font
					(size 1.016 1.016)
					(thickness 0.1524)
				)
			)
		)
		(property "Device Type" "C402H22"
			(at 1.1811 -4.2291 90)
			(unlocked yes)
			(layer "F.Fab")
			(hide yes)
			(effects
				(font
					(size 1.016 1.016)
					(thickness 0.1524)
				)
			)
		)
		(duplicate_pad_numbers_are_jumpers no)
		(fp_rect
			(start -0.4318 0.9525)
			(end 0.4318 -0.9525)
			(stroke
				(width 0)
				(type default)
			)
			(fill no)
			(layer "F.CrtYd")
		)
		(fp_rect
			(start -0.4318 0.9525)
			(end 0.4318 -0.9525)
			(stroke
				(width 0)
				(type default)
			)
			(fill no)
			(layer "F.Fab")
		)
		(pad "1" smd custom
			(at 0 -0.4445 90)
			(size 0.1524 0.1524)
			(layers "F.Cu" "F.Mask" "F.Paste")
			(net "P12V_B")
			(options
				(clearance outline)
				(anchor circle)
			)
			(primitives
				(gr_poly
					(pts
						(arc
							(start 0.3048 -0.2032)
							(mid 0.275042 -0.275042)
							(end 0.2032 -0.3048)
						)
						(arc
							(start -0.2032 -0.3048)
							(mid -0.275042 -0.275042)
							(end -0.3048 -0.2032)
						)
						(arc
							(start -0.3048 0.2032)
							(mid -0.275042 0.275042)
							(end -0.2032 0.3048)
						)
						(arc
							(start 0.2032 0.3048)
							(mid 0.275042 0.275042)
							(end 0.3048 0.2032)
						)
					)
					(width 0)
					(fill yes)
				)
			)
		)
		(pad "2" smd custom
			(at 0 0.4445 90)
			(size 0.1524 0.1524)
			(layers "F.Cu" "F.Mask" "F.Paste")
			(net "SW_HDD_N33")
			(options
				(clearance outline)
				(anchor circle)
			)
			(primitives
				(gr_poly
					(pts
						(arc
							(start 0.3048 -0.2032)
							(mid 0.275042 -0.275042)
							(end 0.2032 -0.3048)
						)
						(arc
							(start -0.2032 -0.3048)
							(mid -0.275042 -0.275042)
							(end -0.3048 -0.2032)
						)
						(arc
							(start -0.3048 0.2032)
							(mid -0.275042 0.275042)
							(end -0.2032 0.3048)
						)
						(arc
							(start 0.2032 0.3048)
							(mid 0.275042 0.275042)
							(end 0.3048 0.2032)
						)
					)
					(width 0)
					(fill yes)
				)
			)
		)
	)
	(footprint ""
		(layer "F.Cu")
		(at 158.663386 -244.660674 90)
		(property "Reference" "C80"
			(at 0 0 90)
			(layer "F.SilkS")
			(hide yes)
			(effects
				(font
					(size 1.27 1.27)
				)
			)
		)
		(property "Value" "SCD01U16V1KX-GP"
			(at -2.8321 -1.7399 90)
			(unlocked yes)
			(layer "F.Fab")
			(hide yes)
			(effects
				(font
					(size 1.016 1.016)
					(thickness 0.1524)
				)
			)
		)
		(property "Device Type" "C0201H13"
			(at -2.8321 -3.2639 90)
			(unlocked yes)
			(layer "F.Fab")
			(hide yes)
			(effects
				(font
					(size 1.016 1.016)
					(thickness 0.1524)
				)
			)
		)
		(duplicate_pad_numbers_are_jumpers no)
		(fp_rect
			(start -0.2794 0.6477)
			(end 0.2794 -0.6477)
			(stroke
				(width 0)
				(type default)
			)
			(fill no)
			(layer "F.CrtYd")
		)
		(fp_rect
			(start -0.2794 0.6477)
			(end 0.2794 -0.6477)
			(stroke
				(width 0)
				(type default)
			)
			(fill no)
			(layer "F.Fab")
		)
		(pad "1" smd custom
			(at 0 -0.2794 90)
			(size 0.0762 0.0762)
			(layers "F.Cu" "F.Mask" "F.Paste")
			(net "SAS_HDD_RX_P4")
			(options
				(clearance outline)
				(anchor circle)
			)
			(primitives
				(gr_poly
					(pts
						(arc
							(start 0.1524 -0.127)
							(mid 0.137521 -0.162921)
							(end 0.1016 -0.1778)
						)
						(arc
							(start -0.1016 -0.1778)
							(mid -0.137521 -0.162921)
							(end -0.1524 -0.127)
						)
						(arc
							(start -0.1524 0.127)
							(mid -0.137521 0.162921)
							(end -0.1016 0.1778)
						)
						(arc
							(start 0.1016 0.1778)
							(mid 0.137521 0.162921)
							(end 0.1524 0.127)
						)
					)
					(width 0)
					(fill yes)
				)
			)
		)
		(pad "2" smd custom
			(at 0 0.2794 90)
			(size 0.0762 0.0762)
			(layers "F.Cu" "F.Mask" "F.Paste")
			(net "PHY_SCC_B_TO_DRV_B_4_DP")
			(options
				(clearance outline)
				(anchor circle)
			)
			(primitives
				(gr_poly
					(pts
						(arc
							(start 0.1524 -0.127)
							(mid 0.137521 -0.162921)
							(end 0.1016 -0.1778)
						)
						(arc
							(start -0.1016 -0.1778)
							(mid -0.137521 -0.162921)
							(end -0.1524 -0.127)
						)
						(arc
							(start -0.1524 0.127)
							(mid -0.137521 0.162921)
							(end -0.1016 0.1778)
						)
						(arc
							(start 0.1016 0.1778)
							(mid 0.137521 0.162921)
							(end 0.1524 0.127)
						)
					)
					(width 0)
					(fill yes)
				)
			)
		)
	)
	(footprint ""
		(layer "F.Cu")
		(at 363.601 -243.586)
		(property "Reference" "R279"
			(at 0 0 0)
			(layer "F.SilkS")
			(hide yes)
			(effects
				(font
					(size 1.27 1.27)
				)
			)
		)
		(property "Value" "4K7R2F-GP"
			(at 0.064008 -3.993896 0)
			(unlocked yes)
			(layer "F.Fab")
			(hide yes)
			(effects
				(font
					(size 1.016 1.016)
					(thickness 0.1524)
				)
			)
		)
		(property "Device Type" "R402H16"
			(at 0.064008 -5.517896 0)
			(unlocked yes)
			(layer "F.Fab")
			(hide yes)
			(effects
				(font
					(size 1.016 1.016)
					(thickness 0.1524)
				)
			)
		)
		(duplicate_pad_numbers_are_jumpers no)
		(fp_line
			(start -0.508 -0.9398)
			(end -0.508 0.9398)
			(stroke
				(width 0.1524)
				(type default)
			)
			(layer "F.SilkS")
		)
		(fp_line
			(start 0.508 -0.9398)
			(end -0.508 -0.9398)
			(stroke
				(width 0.1524)
				(type default)
			)
			(layer "F.SilkS")
		)
		(fp_rect
			(start -0.508 0.9398)
			(end 0.508 -0.9398)
			(stroke
				(width 0)
				(type default)
			)
			(fill no)
			(layer "F.CrtYd")
		)
		(fp_rect
			(start -0.508 0.9398)
			(end 0.508 -0.9398)
			(stroke
				(width 0)
				(type default)
			)
			(fill no)
			(layer "F.Fab")
		)
		(pad "1" smd custom
			(at 0 -0.4445)
			(size 0.1397 0.1397)
			(layers "F.Cu" "F.Mask" "F.Paste")
			(net "SW_PWR_R_HDD7")
			(options
				(clearance outline)
				(anchor circle)
			)
			(primitives
				(gr_poly
					(pts
						(arc
							(start -0.1778 -0.2794)
							(mid -0.249642 -0.249642)
							(end -0.2794 -0.1778)
						)
						(arc
							(start -0.2794 0.1778)
							(mid -0.249642 0.249642)
							(end -0.1778 0.2794)
						)
						(arc
							(start 0.1778 0.2794)
							(mid 0.249642 0.249642)
							(end 0.2794 0.1778)
						)
						(arc
							(start 0.2794 -0.1778)
							(mid 0.249642 -0.249642)
							(end 0.1778 -0.2794)
						)
					)
					(width 0)
					(fill yes)
				)
			)
		)
		(pad "2" smd custom
			(at 0 0.4445)
			(size 0.1397 0.1397)
			(layers "F.Cu" "F.Mask" "F.Paste")
			(net "GND")
			(options
				(clearance outline)
				(anchor circle)
			)
			(primitives
				(gr_poly
					(pts
						(arc
							(start -0.1778 -0.2794)
							(mid -0.249642 -0.249642)
							(end -0.2794 -0.1778)
						)
						(arc
							(start -0.2794 0.1778)
							(mid -0.249642 0.249642)
							(end -0.1778 0.2794)
						)
						(arc
							(start 0.1778 0.2794)
							(mid 0.249642 0.249642)
							(end 0.2794 0.1778)
						)
						(arc
							(start 0.2794 -0.1778)
							(mid 0.249642 -0.249642)
							(end 0.1778 -0.2794)
						)
					)
					(width 0)
					(fill yes)
				)
			)
		)
	)
	(footprint ""
		(layer "F.Cu")
		(at 261.552436 -353.474528 -90)
		(property "Reference" "C566"
			(at 0 0 270)
			(layer "F.SilkS")
			(hide yes)
			(effects
				(font
					(size 1.27 1.27)
				)
			)
		)
		(property "Value" "SCD033U50V3KX-1GP"
			(at 0 -2.8194 270)
			(unlocked yes)
			(layer "F.Fab")
			(hide yes)
			(effects
				(font
					(size 1.016 1.016)
					(thickness 0.1524)
				)
			)
		)
		(property "Device Type" "C603H36"
			(at 0 -4.3434 270)
			(unlocked yes)
			(layer "F.Fab")
			(hide yes)
			(effects
				(font
					(size 1.016 1.016)
					(thickness 0.1524)
				)
			)
		)
		(duplicate_pad_numbers_are_jumpers no)
		(fp_line
			(start 0.508 0)
			(end -0.508 0)
			(stroke
				(width 0.2032)
				(type default)
			)
			(layer "F.SilkS")
		)
		(fp_rect
			(start -0.5842 1.3335)
			(end 0.5842 -1.3335)
			(stroke
				(width 0)
				(type default)
			)
			(fill no)
			(layer "F.CrtYd")
		)
		(fp_rect
			(start -0.5842 1.3335)
			(end 0.5842 -1.3335)
			(stroke
				(width 0)
				(type default)
			)
			(fill no)
			(layer "F.Fab")
		)
		(pad "1" smd custom
			(at 0 -0.762 270)
			(size 0.2159 0.2159)
			(layers "F.Cu" "F.Mask" "F.Paste")
			(net "MB3_CM_GATE_C")
			(options
				(clearance outline)
				(anchor circle)
			)
			(primitives
				(gr_poly
					(pts
						(arc
							(start -0.3302 -0.4318)
							(mid -0.402042 -0.402042)
							(end -0.4318 -0.3302)
						)
						(arc
							(start -0.4318 0.3302)
							(mid -0.402042 0.402042)
							(end -0.3302 0.4318)
						)
						(arc
							(start 0.3302 0.4318)
							(mid 0.402042 0.402042)
							(end 0.4318 0.3302)
						)
						(arc
							(start 0.4318 -0.3302)
							(mid 0.402042 -0.402042)
							(end 0.3302 -0.4318)
						)
					)
					(width 0)
					(fill yes)
				)
			)
		)
		(pad "2" smd custom
			(at 0 0.762 270)
			(size 0.2159 0.2159)
			(layers "F.Cu" "F.Mask" "F.Paste")
			(net "GND")
			(options
				(clearance outline)
				(anchor circle)
			)
			(primitives
				(gr_poly
					(pts
						(arc
							(start -0.3302 -0.4318)
							(mid -0.402042 -0.402042)
							(end -0.4318 -0.3302)
						)
						(arc
							(start -0.4318 0.3302)
							(mid -0.402042 0.402042)
							(end -0.3302 0.4318)
						)
						(arc
							(start 0.3302 0.4318)
							(mid 0.402042 0.402042)
							(end 0.4318 0.3302)
						)
						(arc
							(start 0.4318 -0.3302)
							(mid 0.402042 -0.402042)
							(end 0.3302 -0.4318)
						)
					)
					(width 0)
					(fill yes)
				)
			)
		)
	)
	(footprint ""
		(layer "F.Cu")
		(at 444.4238 -32.7406 180)
		(property "Reference" "R856"
			(at 0 0 180)
			(layer "F.SilkS")
			(hide yes)
			(effects
				(font
					(size 1.27 1.27)
				)
			)
		)
		(property "Value" "220R3F-1-GP"
			(at -0.0254 -2.5146 180)
			(unlocked yes)
			(layer "F.Fab")
			(hide yes)
			(effects
				(font
					(size 1.016 1.016)
					(thickness 0.1524)
				)
			)
		)
		(property "Device Type" "R603H22"
			(at -0.0254 -4.0386 180)
			(unlocked yes)
			(layer "F.Fab")
			(hide yes)
			(effects
				(font
					(size 1.016 1.016)
					(thickness 0.1524)
				)
			)
		)
		(duplicate_pad_numbers_are_jumpers no)
		(fp_line
			(start 0.2032 0)
			(end 0.4826 0)
			(stroke
				(width 0.2032)
				(type default)
			)
			(layer "F.SilkS")
		)
		(fp_line
			(start -0.4826 0)
			(end -0.2032 0)
			(stroke
				(width 0.2032)
				(type default)
			)
			(layer "F.SilkS")
		)
		(fp_rect
			(start -0.5842 1.3335)
			(end 0.5842 -1.3335)
			(stroke
				(width 0)
				(type default)
			)
			(fill no)
			(layer "F.CrtYd")
		)
		(fp_rect
			(start -0.5842 1.3335)
			(end 0.5842 -1.3335)
			(stroke
				(width 0)
				(type default)
			)
			(fill no)
			(layer "F.Fab")
		)
		(pad "1" smd custom
			(at 0 -0.762 180)
			(size 0.2159 0.2159)
			(layers "F.Cu" "F.Mask" "F.Paste")
			(net "HDD_PRSNT_34")
			(options
				(clearance outline)
				(anchor circle)
			)
			(primitives
				(gr_poly
					(pts
						(arc
							(start -0.3302 -0.4318)
							(mid -0.402042 -0.402042)
							(end -0.4318 -0.3302)
						)
						(arc
							(start -0.4318 0.3302)
							(mid -0.402042 0.402042)
							(end -0.3302 0.4318)
						)
						(arc
							(start 0.3302 0.4318)
							(mid 0.402042 0.402042)
							(end 0.4318 0.3302)
						)
						(arc
							(start 0.4318 -0.3302)
							(mid 0.402042 -0.402042)
							(end 0.3302 -0.4318)
						)
					)
					(width 0)
					(fill yes)
				)
			)
		)
		(pad "2" smd custom
			(at 0 0.762 180)
			(size 0.2159 0.2159)
			(layers "F.Cu" "F.Mask" "F.Paste")
			(net "DRIVE_B_34_INS")
			(options
				(clearance outline)
				(anchor circle)
			)
			(primitives
				(gr_poly
					(pts
						(arc
							(start -0.3302 -0.4318)
							(mid -0.402042 -0.402042)
							(end -0.4318 -0.3302)
						)
						(arc
							(start -0.4318 0.3302)
							(mid -0.402042 0.402042)
							(end -0.3302 0.4318)
						)
						(arc
							(start 0.3302 0.4318)
							(mid 0.402042 0.402042)
							(end 0.4318 0.3302)
						)
						(arc
							(start 0.4318 -0.3302)
							(mid 0.402042 -0.402042)
							(end 0.3302 -0.4318)
						)
					)
					(width 0)
					(fill yes)
				)
			)
		)
	)
	(footprint ""
		(layer "F.Cu")
		(at 221.73946 -166.41826 90)
		(property "Reference" "R59"
			(at 0 0 90)
			(layer "F.SilkS")
			(hide yes)
			(effects
				(font
					(size 1.27 1.27)
				)
			)
		)
		(property "Value" "4K7R2F-GP"
			(at 0.064008 -3.993896 90)
			(unlocked yes)
			(layer "F.Fab")
			(hide yes)
			(effects
				(font
					(size 1.016 1.016)
					(thickness 0.1524)
				)
			)
		)
		(property "Device Type" "R402H16"
			(at 0.064008 -5.517896 90)
			(unlocked yes)
			(layer "F.Fab")
			(hide yes)
			(effects
				(font
					(size 1.016 1.016)
					(thickness 0.1524)
				)
			)
		)
		(duplicate_pad_numbers_are_jumpers no)
		(fp_line
			(start 0.508 -0.9398)
			(end -0.508 -0.9398)
			(stroke
				(width 0.1524)
				(type default)
			)
			(layer "F.SilkS")
		)
		(fp_line
			(start -0.508 -0.9398)
			(end -0.508 0.9398)
			(stroke
				(width 0.1524)
				(type default)
			)
			(layer "F.SilkS")
		)
		(fp_rect
			(start -0.508 0.9398)
			(end 0.508 -0.9398)
			(stroke
				(width 0)
				(type default)
			)
			(fill no)
			(layer "F.CrtYd")
		)
		(fp_rect
			(start -0.508 0.9398)
			(end 0.508 -0.9398)
			(stroke
				(width 0)
				(type default)
			)
			(fill no)
			(layer "F.Fab")
		)
		(pad "1" smd custom
			(at 0 -0.4445 90)
			(size 0.1397 0.1397)
			(layers "F.Cu" "F.Mask" "F.Paste")
			(net "IO_EXP6_A2")
			(options
				(clearance outline)
				(anchor circle)
			)
			(primitives
				(gr_poly
					(pts
						(arc
							(start -0.1778 -0.2794)
							(mid -0.249642 -0.249642)
							(end -0.2794 -0.1778)
						)
						(arc
							(start -0.2794 0.1778)
							(mid -0.249642 0.249642)
							(end -0.1778 0.2794)
						)
						(arc
							(start 0.1778 0.2794)
							(mid 0.249642 0.249642)
							(end 0.2794 0.1778)
						)
						(arc
							(start 0.2794 -0.1778)
							(mid 0.249642 -0.249642)
							(end 0.1778 -0.2794)
						)
					)
					(width 0)
					(fill yes)
				)
			)
		)
		(pad "2" smd custom
			(at 0 0.4445 90)
			(size 0.1397 0.1397)
			(layers "F.Cu" "F.Mask" "F.Paste")
			(net "GND")
			(options
				(clearance outline)
				(anchor circle)
			)
			(primitives
				(gr_poly
					(pts
						(arc
							(start -0.1778 -0.2794)
							(mid -0.249642 -0.249642)
							(end -0.2794 -0.1778)
						)
						(arc
							(start -0.2794 0.1778)
							(mid -0.249642 0.249642)
							(end -0.1778 0.2794)
						)
						(arc
							(start 0.1778 0.2794)
							(mid 0.249642 0.249642)
							(end 0.2794 0.1778)
						)
						(arc
							(start 0.2794 -0.1778)
							(mid 0.249642 -0.249642)
							(end 0.1778 -0.2794)
						)
					)
					(width 0)
					(fill yes)
				)
			)
		)
	)
	(footprint ""
		(layer "F.Cu")
		(at 181.991 -275.463 180)
		(property "Reference" "C101"
			(at 0 0 180)
			(layer "F.SilkS")
			(hide yes)
			(effects
				(font
					(size 1.27 1.27)
				)
			)
		)
		(property "Value" "SC1U25V3KX-GP"
			(at 0 -2.8194 180)
			(unlocked yes)
			(layer "F.Fab")
			(hide yes)
			(effects
				(font
					(size 1.016 1.016)
					(thickness 0.1524)
				)
			)
		)
		(property "Device Type" "C603H36"
			(at 0 -4.3434 180)
			(unlocked yes)
			(layer "F.Fab")
			(hide yes)
			(effects
				(font
					(size 1.016 1.016)
					(thickness 0.1524)
				)
			)
		)
		(duplicate_pad_numbers_are_jumpers no)
		(fp_line
			(start 0.508 0)
			(end -0.508 0)
			(stroke
				(width 0.2032)
				(type default)
			)
			(layer "F.SilkS")
		)
		(fp_rect
			(start -0.5842 1.3335)
			(end 0.5842 -1.3335)
			(stroke
				(width 0)
				(type default)
			)
			(fill no)
			(layer "F.CrtYd")
		)
		(fp_rect
			(start -0.5842 1.3335)
			(end 0.5842 -1.3335)
			(stroke
				(width 0)
				(type default)
			)
			(fill no)
			(layer "F.Fab")
		)
		(pad "1" smd custom
			(at 0 -0.762 180)
			(size 0.2159 0.2159)
			(layers "F.Cu" "F.Mask" "F.Paste")
			(net "P12V_HDD5")
			(options
				(clearance outline)
				(anchor circle)
			)
			(primitives
				(gr_poly
					(pts
						(arc
							(start -0.3302 -0.4318)
							(mid -0.402042 -0.402042)
							(end -0.4318 -0.3302)
						)
						(arc
							(start -0.4318 0.3302)
							(mid -0.402042 0.402042)
							(end -0.3302 0.4318)
						)
						(arc
							(start 0.3302 0.4318)
							(mid 0.402042 0.402042)
							(end 0.4318 0.3302)
						)
						(arc
							(start 0.4318 -0.3302)
							(mid 0.402042 -0.402042)
							(end 0.3302 -0.4318)
						)
					)
					(width 0)
					(fill yes)
				)
			)
		)
		(pad "2" smd custom
			(at 0 0.762 180)
			(size 0.2159 0.2159)
			(layers "F.Cu" "F.Mask" "F.Paste")
			(net "GND")
			(options
				(clearance outline)
				(anchor circle)
			)
			(primitives
				(gr_poly
					(pts
						(arc
							(start -0.3302 -0.4318)
							(mid -0.402042 -0.402042)
							(end -0.4318 -0.3302)
						)
						(arc
							(start -0.4318 0.3302)
							(mid -0.402042 0.402042)
							(end -0.3302 0.4318)
						)
						(arc
							(start 0.3302 0.4318)
							(mid 0.402042 0.402042)
							(end 0.4318 0.3302)
						)
						(arc
							(start 0.4318 -0.3302)
							(mid 0.402042 -0.402042)
							(end 0.3302 -0.4318)
						)
					)
					(width 0)
					(fill yes)
				)
			)
		)
	)
	(footprint ""
		(layer "F.Cu")
		(at 464.566 -28.829 90)
		(property "Reference" "C481"
			(at 0 0 90)
			(layer "F.SilkS")
			(hide yes)
			(effects
				(font
					(size 1.27 1.27)
				)
			)
		)
		(property "Value" "SCD033U25V2KX-GP"
			(at 1.1811 -2.7051 90)
			(unlocked yes)
			(layer "F.Fab")
			(hide yes)
			(effects
				(font
					(size 1.016 1.016)
					(thickness 0.1524)
				)
			)
		)
		(property "Device Type" "C402H22"
			(at 1.1811 -4.2291 90)
			(unlocked yes)
			(layer "F.Fab")
			(hide yes)
			(effects
				(font
					(size 1.016 1.016)
					(thickness 0.1524)
				)
			)
		)
		(duplicate_pad_numbers_are_jumpers no)
		(fp_rect
			(start -0.4318 0.9525)
			(end 0.4318 -0.9525)
			(stroke
				(width 0)
				(type default)
			)
			(fill no)
			(layer "F.CrtYd")
		)
		(fp_rect
			(start -0.4318 0.9525)
			(end 0.4318 -0.9525)
			(stroke
				(width 0)
				(type default)
			)
			(fill no)
			(layer "F.Fab")
		)
		(pad "1" smd custom
			(at 0 -0.4445 90)
			(size 0.1524 0.1524)
			(layers "F.Cu" "F.Mask" "F.Paste")
			(net "P12V_B")
			(options
				(clearance outline)
				(anchor circle)
			)
			(primitives
				(gr_poly
					(pts
						(arc
							(start 0.3048 -0.2032)
							(mid 0.275042 -0.275042)
							(end 0.2032 -0.3048)
						)
						(arc
							(start -0.2032 -0.3048)
							(mid -0.275042 -0.275042)
							(end -0.3048 -0.2032)
						)
						(arc
							(start -0.3048 0.2032)
							(mid -0.275042 0.275042)
							(end -0.2032 0.3048)
						)
						(arc
							(start 0.2032 0.3048)
							(mid 0.275042 0.275042)
							(end 0.3048 0.2032)
						)
					)
					(width 0)
					(fill yes)
				)
			)
		)
		(pad "2" smd custom
			(at 0 0.4445 90)
			(size 0.1524 0.1524)
			(layers "F.Cu" "F.Mask" "F.Paste")
			(net "SW_HDD_N34")
			(options
				(clearance outline)
				(anchor circle)
			)
			(primitives
				(gr_poly
					(pts
						(arc
							(start 0.3048 -0.2032)
							(mid 0.275042 -0.275042)
							(end 0.2032 -0.3048)
						)
						(arc
							(start -0.2032 -0.3048)
							(mid -0.275042 -0.275042)
							(end -0.3048 -0.2032)
						)
						(arc
							(start -0.3048 0.2032)
							(mid -0.275042 0.275042)
							(end -0.2032 0.3048)
						)
						(arc
							(start 0.2032 0.3048)
							(mid 0.275042 0.275042)
							(end 0.3048 0.2032)
						)
					)
					(width 0)
					(fill yes)
				)
			)
		)
	)
	(footprint ""
		(layer "F.Cu")
		(at 457.708 -250.4948 -90)
		(property "Reference" "C168"
			(at 0 0 270)
			(layer "F.SilkS")
			(hide yes)
			(effects
				(font
					(size 1.27 1.27)
				)
			)
		)
		(property "Value" "SCD033U25V2KX-GP"
			(at 1.1811 -2.7051 270)
			(unlocked yes)
			(layer "F.Fab")
			(hide yes)
			(effects
				(font
					(size 1.016 1.016)
					(thickness 0.1524)
				)
			)
		)
		(property "Device Type" "C402H22"
			(at 1.1811 -4.2291 270)
			(unlocked yes)
			(layer "F.Fab")
			(hide yes)
			(effects
				(font
					(size 1.016 1.016)
					(thickness 0.1524)
				)
			)
		)
		(duplicate_pad_numbers_are_jumpers no)
		(fp_rect
			(start -0.4318 0.9525)
			(end 0.4318 -0.9525)
			(stroke
				(width 0)
				(type default)
			)
			(fill no)
			(layer "F.CrtYd")
		)
		(fp_rect
			(start -0.4318 0.9525)
			(end 0.4318 -0.9525)
			(stroke
				(width 0)
				(type default)
			)
			(fill no)
			(layer "F.Fab")
		)
		(pad "1" smd custom
			(at 0 -0.4445 270)
			(size 0.1524 0.1524)
			(layers "F.Cu" "F.Mask" "F.Paste")
			(net "SW_HDD_P10")
			(options
				(clearance outline)
				(anchor circle)
			)
			(primitives
				(gr_poly
					(pts
						(arc
							(start 0.3048 -0.2032)
							(mid 0.275042 -0.275042)
							(end 0.2032 -0.3048)
						)
						(arc
							(start -0.2032 -0.3048)
							(mid -0.275042 -0.275042)
							(end -0.3048 -0.2032)
						)
						(arc
							(start -0.3048 0.2032)
							(mid -0.275042 0.275042)
							(end -0.2032 0.3048)
						)
						(arc
							(start 0.2032 0.3048)
							(mid 0.275042 0.275042)
							(end 0.3048 0.2032)
						)
					)
					(width 0)
					(fill yes)
				)
			)
		)
		(pad "2" smd custom
			(at 0 0.4445 270)
			(size 0.1524 0.1524)
			(layers "F.Cu" "F.Mask" "F.Paste")
			(net "GND")
			(options
				(clearance outline)
				(anchor circle)
			)
			(primitives
				(gr_poly
					(pts
						(arc
							(start 0.3048 -0.2032)
							(mid 0.275042 -0.275042)
							(end 0.2032 -0.3048)
						)
						(arc
							(start -0.2032 -0.3048)
							(mid -0.275042 -0.275042)
							(end -0.3048 -0.2032)
						)
						(arc
							(start -0.3048 0.2032)
							(mid -0.275042 0.275042)
							(end -0.2032 0.3048)
						)
						(arc
							(start 0.2032 0.3048)
							(mid 0.275042 0.275042)
							(end 0.3048 0.2032)
						)
					)
					(width 0)
					(fill yes)
				)
			)
		)
	)
	(footprint ""
		(layer "F.Cu")
		(at 469.49995 -377.219972 180)
		(property "Reference" "FLED4"
			(at 0 0 180)
			(layer "F.SilkS")
			(hide yes)
			(effects
				(font
					(size 1.27 1.27)
				)
			)
		)
		(property "Value" "LED-BY-14-GP"
			(at -4.7752 -2.1844 180)
			(unlocked yes)
			(layer "F.Fab")
			(hide yes)
			(effects
				(font
					(size 1.016 1.016)
					(thickness 0.1524)
				)
			)
		)
		(property "Device Type" "LED-100-3PH206"
			(at -4.7752 -3.7084 180)
			(unlocked yes)
			(layer "F.Fab")
			(hide yes)
			(effects
				(font
					(size 1.016 1.016)
					(thickness 0.1524)
				)
			)
		)
		(duplicate_pad_numbers_are_jumpers no)
		(fp_line
			(start 3.7592 8.0264)
			(end -3.7592 8.0264)
			(stroke
				(width 0.1524)
				(type default)
			)
			(layer "F.SilkS")
		)
		(fp_line
			(start 3.7592 -1.524)
			(end 3.7592 8.0264)
			(stroke
				(width 0.1524)
				(type default)
			)
			(layer "F.SilkS")
		)
		(fp_line
			(start 1.87833 3.63474)
			(end 0.58293 2.33934)
			(stroke
				(width 0.1524)
				(type default)
			)
			(layer "F.SilkS")
		)
		(fp_line
			(start 1.87833 2.33934)
			(end 2.81813 2.33934)
			(stroke
				(width 0.1524)
				(type default)
			)
			(layer "F.SilkS")
		)
		(fp_line
			(start 1.87833 1.04394)
			(end 1.87833 3.63474)
			(stroke
				(width 0.1524)
				(type default)
			)
			(layer "F.SilkS")
		)
		(fp_line
			(start 0.58293 3.05054)
			(end 0.58293 1.42494)
			(stroke
				(width 0.1524)
				(type default)
			)
			(layer "F.SilkS")
		)
		(fp_line
			(start 0.58293 2.33934)
			(end 1.87833 1.04394)
			(stroke
				(width 0.1524)
				(type default)
			)
			(layer "F.SilkS")
		)
		(fp_line
			(start -0.45847 3.05054)
			(end -0.45847 1.42494)
			(stroke
				(width 0.1524)
				(type default)
			)
			(layer "F.SilkS")
		)
		(fp_line
			(start -0.45847 2.33934)
			(end 0.58293 2.33934)
			(stroke
				(width 0.1524)
				(type default)
			)
			(layer "F.SilkS")
		)
		(fp_line
			(start -0.45847 2.33934)
			(end -1.75387 1.04394)
			(stroke
				(width 0.1524)
				(type default)
			)
			(layer "F.SilkS")
		)
		(fp_line
			(start -1.75387 3.63474)
			(end -0.45847 2.33934)
			(stroke
				(width 0.1524)
				(type default)
			)
			(layer "F.SilkS")
		)
		(fp_line
			(start -1.75387 2.33934)
			(end -3.45567 2.33934)
			(stroke
				(width 0.1524)
				(type default)
			)
			(layer "F.SilkS")
		)
		(fp_line
			(start -1.75387 1.04394)
			(end -1.75387 3.63474)
			(stroke
				(width 0.1524)
				(type default)
			)
			(layer "F.SilkS")
		)
		(fp_line
			(start -3.7592 8.0264)
			(end -3.7592 -1.524)
			(stroke
				(width 0.1524)
				(type default)
			)
			(layer "F.SilkS")
		)
		(fp_line
			(start -3.7592 -1.524)
			(end 3.7592 -1.524)
			(stroke
				(width 0.1524)
				(type default)
			)
			(layer "F.SilkS")
		)
		(fp_circle
			(center 2.54 0)
			(end 1.5494 0)
			(stroke
				(width 0.3048)
				(type default)
			)
			(fill no)
			(layer "F.SilkS")
		)
		(fp_circle
			(center 0 0)
			(end -0.9906 0)
			(stroke
				(width 0.3048)
				(type default)
			)
			(fill no)
			(layer "F.SilkS")
		)
		(fp_circle
			(center -2.54 0)
			(end -3.5306 0)
			(stroke
				(width 0.3048)
				(type default)
			)
			(fill no)
			(layer "F.SilkS")
		)
		(fp_rect
			(start -3.5052 7.7724)
			(end 3.5052 -1.27)
			(stroke
				(width 0)
				(type default)
			)
			(fill no)
			(layer "F.CrtYd")
		)
		(fp_poly
			(pts
				(xy -4.0132 8.2804) (xy -4.0132 -1.778) (xy -3.5052 -1.778) (xy -3.5052 7.7724) (xy 3.5052 7.7724)
				(xy 3.5052 -1.27) (xy -3.50012 -1.27) (xy -3.50012 -1.778) (xy 4.0132 -1.778) (xy 4.0132 8.2804)
			)
			(stroke
				(width 0)
				(type default)
			)
			(fill no)
			(layer "F.CrtYd")
		)
		(fp_rect
			(start -4.0132 8.2804)
			(end 4.0132 -1.778)
			(stroke
				(width 0)
				(type default)
			)
			(fill no)
			(layer "F.Fab")
		)
		(pad "1" thru_hole circle
			(at -2.54 0 180)
			(size 1.27 1.27)
			(drill 0.889)
			(layers "*.Cu" "*.Mask")
			(remove_unused_layers no)
			(net "FAN_LED_BLUE3")
			(clearance 0.1651)
			(thermal_gap 0.1651)
		)
		(pad "2" thru_hole circle
			(at 0 0 180)
			(size 1.27 1.27)
			(drill 0.889)
			(layers "*.Cu" "*.Mask")
			(remove_unused_layers no)
			(net "GND")
			(clearance 0.1651)
			(thermal_gap 0.1651)
		)
		(pad "3" thru_hole circle
			(at 2.54 0 180)
			(size 1.27 1.27)
			(drill 0.889)
			(layers "*.Cu" "*.Mask")
			(remove_unused_layers no)
			(net "FAN_LED_YELLOW_3")
			(clearance 0.1651)
			(thermal_gap 0.1651)
		)
	)
	(footprint ""
		(layer "F.Cu")
		(at 363.601 -131.318 -90)
		(property "Reference" "Q89"
			(at 0 0 270)
			(layer "F.SilkS")
			(hide yes)
			(effects
				(font
					(size 1.27 1.27)
				)
			)
		)
		(property "Value" "2N7002KDW-GP"
			(at -2.3622 -8.2042 270)
			(unlocked yes)
			(layer "F.Fab")
			(hide yes)
			(effects
				(font
					(size 1.016 1.016)
					(thickness 0.1524)
				)
			)
		)
		(property "Device Type" "SOT-363H44"
			(at -2.3622 -10.1092 270)
			(unlocked yes)
			(layer "F.Fab")
			(hide yes)
			(effects
				(font
					(size 1.016 1.016)
					(thickness 0.1524)
				)
			)
		)
		(duplicate_pad_numbers_are_jumpers no)
		(fp_line
			(start -1.4478 1.7018)
			(end 1.4478 1.7018)
			(stroke
				(width 0.1524)
				(type default)
			)
			(layer "F.SilkS")
		)
		(fp_line
			(start 1.4478 1.7018)
			(end 1.4478 -1.7018)
			(stroke
				(width 0.1524)
				(type default)
			)
			(layer "F.SilkS")
		)
		(fp_line
			(start -1.27 1.524)
			(end -1.27 0.6604)
			(stroke
				(width 0.4826)
				(type default)
			)
			(layer "F.SilkS")
		)
		(fp_line
			(start -1.4478 -1.7018)
			(end -1.4478 1.7018)
			(stroke
				(width 0.1524)
				(type default)
			)
			(layer "F.SilkS")
		)
		(fp_line
			(start 1.4478 -1.7018)
			(end -1.4478 -1.7018)
			(stroke
				(width 0.1524)
				(type default)
			)
			(layer "F.SilkS")
		)
		(fp_poly
			(pts
				(xy -1.524 -1.778) (xy 1.524 -1.778) (xy 1.524 1.778) (xy -1.524 1.778)
			)
			(stroke
				(width 0)
				(type default)
			)
			(fill no)
			(layer "F.CrtYd")
		)
		(fp_poly
			(pts
				(xy -1.524 -1.778) (xy 1.524 -1.778) (xy 1.524 1.778) (xy -1.524 1.778)
			)
			(stroke
				(width 0)
				(type default)
			)
			(fill no)
			(layer "F.Fab")
		)
		(pad "1" smd rect
			(at -0.65024 0.9398 270)
			(size 0.4064 1.016)
			(layers "F.Cu" "F.Mask" "F.Paste")
			(net "GND")
		)
		(pad "2" smd rect
			(at 0 0.9398 270)
			(size 0.4064 1.016)
			(layers "F.Cu" "F.Mask" "F.Paste")
			(net "SW_PWR_R_HDD19")
		)
		(pad "3" smd rect
			(at 0.65024 0.9398 270)
			(size 0.4064 1.016)
			(layers "F.Cu" "F.Mask" "F.Paste")
			(net "SW_HDD_P19")
		)
		(pad "4" smd rect
			(at 0.65024 -0.9398 270)
			(size 0.4064 1.016)
			(layers "F.Cu" "F.Mask" "F.Paste")
			(net "GND")
		)
		(pad "5" smd rect
			(at 0 -0.9398 270)
			(size 0.4064 1.016)
			(layers "F.Cu" "F.Mask" "F.Paste")
			(net "SW_HDD_G19")
		)
		(pad "6" smd rect
			(at -0.65024 -0.9398 270)
			(size 0.4064 1.016)
			(layers "F.Cu" "F.Mask" "F.Paste")
			(net "SW_HDD_R19")
		)
	)
	(footprint ""
		(layer "F.Cu")
		(at 329.819 -45.339 180)
		(property "Reference" "C426"
			(at 0 0 180)
			(layer "F.SilkS")
			(hide yes)
			(effects
				(font
					(size 1.27 1.27)
				)
			)
		)
		(property "Value" "SC1U25V3KX-GP"
			(at 0 -2.8194 180)
			(unlocked yes)
			(layer "F.Fab")
			(hide yes)
			(effects
				(font
					(size 1.016 1.016)
					(thickness 0.1524)
				)
			)
		)
		(property "Device Type" "C603H36"
			(at 0 -4.3434 180)
			(unlocked yes)
			(layer "F.Fab")
			(hide yes)
			(effects
				(font
					(size 1.016 1.016)
					(thickness 0.1524)
				)
			)
		)
		(duplicate_pad_numbers_are_jumpers no)
		(fp_line
			(start 0.508 0)
			(end -0.508 0)
			(stroke
				(width 0.2032)
				(type default)
			)
			(layer "F.SilkS")
		)
		(fp_rect
			(start -0.5842 1.3335)
			(end 0.5842 -1.3335)
			(stroke
				(width 0)
				(type default)
			)
			(fill no)
			(layer "F.CrtYd")
		)
		(fp_rect
			(start -0.5842 1.3335)
			(end 0.5842 -1.3335)
			(stroke
				(width 0)
				(type default)
			)
			(fill no)
			(layer "F.Fab")
		)
		(pad "1" smd custom
			(at 0 -0.762 180)
			(size 0.2159 0.2159)
			(layers "F.Cu" "F.Mask" "F.Paste")
			(net "P12V_HDD30")
			(options
				(clearance outline)
				(anchor circle)
			)
			(primitives
				(gr_poly
					(pts
						(arc
							(start -0.3302 -0.4318)
							(mid -0.402042 -0.402042)
							(end -0.4318 -0.3302)
						)
						(arc
							(start -0.4318 0.3302)
							(mid -0.402042 0.402042)
							(end -0.3302 0.4318)
						)
						(arc
							(start 0.3302 0.4318)
							(mid 0.402042 0.402042)
							(end 0.4318 0.3302)
						)
						(arc
							(start 0.4318 -0.3302)
							(mid 0.402042 -0.402042)
							(end 0.3302 -0.4318)
						)
					)
					(width 0)
					(fill yes)
				)
			)
		)
		(pad "2" smd custom
			(at 0 0.762 180)
			(size 0.2159 0.2159)
			(layers "F.Cu" "F.Mask" "F.Paste")
			(net "GND")
			(options
				(clearance outline)
				(anchor circle)
			)
			(primitives
				(gr_poly
					(pts
						(arc
							(start -0.3302 -0.4318)
							(mid -0.402042 -0.402042)
							(end -0.4318 -0.3302)
						)
						(arc
							(start -0.4318 0.3302)
							(mid -0.402042 0.402042)
							(end -0.3302 0.4318)
						)
						(arc
							(start 0.3302 0.4318)
							(mid 0.402042 0.402042)
							(end 0.4318 0.3302)
						)
						(arc
							(start 0.4318 -0.3302)
							(mid 0.402042 -0.402042)
							(end 0.3302 -0.4318)
						)
					)
					(width 0)
					(fill yes)
				)
			)
		)
	)
	(footprint ""
		(layer "F.Cu")
		(at 461.264 -99.8474 180)
		(property "Reference" "Q242"
			(at 0 0 180)
			(layer "F.SilkS")
			(hide yes)
			(effects
				(font
					(size 1.27 1.27)
				)
			)
		)
		(property "Value" "2N7002K-2-GP"
			(at 0.127 -8.9662 180)
			(unlocked yes)
			(layer "F.Fab")
			(hide yes)
			(effects
				(font
					(size 1.016 1.016)
					(thickness 0.1524)
				)
			)
		)
		(property "Device Type" "SOT23DGS2D4H44"
			(at 0.127 -10.4902 180)
			(unlocked yes)
			(layer "F.Fab")
			(hide yes)
			(effects
				(font
					(size 1.016 1.016)
					(thickness 0.1524)
				)
			)
		)
		(duplicate_pad_numbers_are_jumpers no)
		(fp_line
			(start 1.651 1.778)
			(end 1.651 -1.778)
			(stroke
				(width 0.1524)
				(type default)
			)
			(layer "F.SilkS")
		)
		(fp_line
			(start 1.651 -1.778)
			(end -1.651 -1.778)
			(stroke
				(width 0.1524)
				(type default)
			)
			(layer "F.SilkS")
		)
		(fp_line
			(start -1.651 1.778)
			(end 1.651 1.778)
			(stroke
				(width 0.1524)
				(type default)
			)
			(layer "F.SilkS")
		)
		(fp_line
			(start -1.651 -1.778)
			(end -1.651 1.778)
			(stroke
				(width 0.1524)
				(type default)
			)
			(layer "F.SilkS")
		)
		(fp_poly
			(pts
				(xy -1.778 1.8796) (xy -1.778 -1.8796) (xy 1.778 -1.8796) (xy 1.778 1.8796)
			)
			(stroke
				(width 0)
				(type default)
			)
			(fill no)
			(layer "F.CrtYd")
		)
		(fp_poly
			(pts
				(xy -1.778 1.8796) (xy -1.778 -1.8796) (xy 1.778 -1.8796) (xy 1.778 1.8796)
			)
			(stroke
				(width 0)
				(type default)
			)
			(fill no)
			(layer "F.Fab")
		)
		(pad "D" smd custom
			(at 0 -0.9525 180)
			(size 0.1905 0.1905)
			(layers "F.Cu" "F.Mask" "F.Paste")
			(net "FLT_HDD23_N")
			(options
				(clearance outline)
				(anchor circle)
			)
			(primitives
				(gr_poly
					(pts
						(arc
							(start -0.1778 0.5715)
							(mid -0.321484 0.511984)
							(end -0.381 0.3683)
						)
						(arc
							(start -0.381 -0.3683)
							(mid -0.321484 -0.511984)
							(end -0.1778 -0.5715)
						)
						(arc
							(start 0.1778 -0.5715)
							(mid 0.321484 -0.511984)
							(end 0.381 -0.3683)
						)
						(arc
							(start 0.381 0.3683)
							(mid 0.321484 0.511984)
							(end 0.1778 0.5715)
						)
					)
					(width 0)
					(fill yes)
				)
			)
		)
		(pad "G" smd custom
			(at -0.98425 0.9525 180)
			(size 0.1905 0.1905)
			(layers "F.Cu" "F.Mask" "F.Paste")
			(net "DRIVE_B_23_FLT_LED")
			(options
				(clearance outline)
				(anchor circle)
			)
			(primitives
				(gr_poly
					(pts
						(arc
							(start -0.1778 0.5715)
							(mid -0.321484 0.511984)
							(end -0.381 0.3683)
						)
						(arc
							(start -0.381 -0.3683)
							(mid -0.321484 -0.511984)
							(end -0.1778 -0.5715)
						)
						(arc
							(start 0.1778 -0.5715)
							(mid 0.321484 -0.511984)
							(end 0.381 -0.3683)
						)
						(arc
							(start 0.381 0.3683)
							(mid 0.321484 0.511984)
							(end 0.1778 0.5715)
						)
					)
					(width 0)
					(fill yes)
				)
			)
		)
		(pad "S" smd custom
			(at 0.98425 0.9525 180)
			(size 0.1905 0.1905)
			(layers "F.Cu" "F.Mask" "F.Paste")
			(net "GND")
			(options
				(clearance outline)
				(anchor circle)
			)
			(primitives
				(gr_poly
					(pts
						(arc
							(start -0.1778 0.5715)
							(mid -0.321484 0.511984)
							(end -0.381 0.3683)
						)
						(arc
							(start -0.381 -0.3683)
							(mid -0.321484 -0.511984)
							(end -0.1778 -0.5715)
						)
						(arc
							(start 0.1778 -0.5715)
							(mid 0.321484 -0.511984)
							(end 0.381 -0.3683)
						)
						(arc
							(start 0.381 0.3683)
							(mid 0.321484 0.511984)
							(end 0.1778 0.5715)
						)
					)
					(width 0)
					(fill yes)
				)
			)
		)
	)
	(footprint ""
		(layer "F.Cu")
		(at 432.689 -135.509 90)
		(property "Reference" "R569"
			(at 0 0 90)
			(layer "F.SilkS")
			(hide yes)
			(effects
				(font
					(size 1.27 1.27)
				)
			)
		)
		(property "Value" "200KR2F-L-GP"
			(at 0.064008 -3.993896 90)
			(unlocked yes)
			(layer "F.Fab")
			(hide yes)
			(effects
				(font
					(size 1.016 1.016)
					(thickness 0.1524)
				)
			)
		)
		(property "Device Type" "R402H16"
			(at 0.064008 -5.517896 90)
			(unlocked yes)
			(layer "F.Fab")
			(hide yes)
			(effects
				(font
					(size 1.016 1.016)
					(thickness 0.1524)
				)
			)
		)
		(duplicate_pad_numbers_are_jumpers no)
		(fp_line
			(start 0.508 -0.9398)
			(end -0.508 -0.9398)
			(stroke
				(width 0.1524)
				(type default)
			)
			(layer "F.SilkS")
		)
		(fp_line
			(start -0.508 -0.9398)
			(end -0.508 0.9398)
			(stroke
				(width 0.1524)
				(type default)
			)
			(layer "F.SilkS")
		)
		(fp_rect
			(start -0.508 0.9398)
			(end 0.508 -0.9398)
			(stroke
				(width 0)
				(type default)
			)
			(fill no)
			(layer "F.CrtYd")
		)
		(fp_rect
			(start -0.508 0.9398)
			(end 0.508 -0.9398)
			(stroke
				(width 0)
				(type default)
			)
			(fill no)
			(layer "F.Fab")
		)
		(pad "1" smd custom
			(at 0 -0.4445 90)
			(size 0.1397 0.1397)
			(layers "F.Cu" "F.Mask" "F.Paste")
			(net "SW_HDD_R21")
			(options
				(clearance outline)
				(anchor circle)
			)
			(primitives
				(gr_poly
					(pts
						(arc
							(start -0.1778 -0.2794)
							(mid -0.249642 -0.249642)
							(end -0.2794 -0.1778)
						)
						(arc
							(start -0.2794 0.1778)
							(mid -0.249642 0.249642)
							(end -0.1778 0.2794)
						)
						(arc
							(start 0.1778 0.2794)
							(mid 0.249642 0.249642)
							(end 0.2794 0.1778)
						)
						(arc
							(start 0.2794 -0.1778)
							(mid 0.249642 -0.249642)
							(end 0.1778 -0.2794)
						)
					)
					(width 0)
					(fill yes)
				)
			)
		)
		(pad "2" smd custom
			(at 0 0.4445 90)
			(size 0.1397 0.1397)
			(layers "F.Cu" "F.Mask" "F.Paste")
			(net "SW_HDD_N21")
			(options
				(clearance outline)
				(anchor circle)
			)
			(primitives
				(gr_poly
					(pts
						(arc
							(start -0.1778 -0.2794)
							(mid -0.249642 -0.249642)
							(end -0.2794 -0.1778)
						)
						(arc
							(start -0.2794 0.1778)
							(mid -0.249642 0.249642)
							(end -0.1778 0.2794)
						)
						(arc
							(start 0.1778 0.2794)
							(mid 0.249642 0.249642)
							(end 0.2794 0.1778)
						)
						(arc
							(start 0.2794 -0.1778)
							(mid 0.249642 -0.249642)
							(end 0.1778 -0.2794)
						)
					)
					(width 0)
					(fill yes)
				)
			)
		)
	)
	(footprint ""
		(layer "F.Cu")
		(at 352.1456 -146.6342 180)
		(property "Reference" "R507"
			(at 0 0 180)
			(layer "F.SilkS")
			(hide yes)
			(effects
				(font
					(size 1.27 1.27)
				)
			)
		)
		(property "Value" "10KR2F-2-GP"
			(at 0.064008 -3.993896 180)
			(unlocked yes)
			(layer "F.Fab")
			(hide yes)
			(effects
				(font
					(size 1.016 1.016)
					(thickness 0.1524)
				)
			)
		)
		(property "Device Type" "R402H16"
			(at 0.064008 -5.517896 180)
			(unlocked yes)
			(layer "F.Fab")
			(hide yes)
			(effects
				(font
					(size 1.016 1.016)
					(thickness 0.1524)
				)
			)
		)
		(duplicate_pad_numbers_are_jumpers no)
		(fp_line
			(start 0.508 -0.9398)
			(end -0.508 -0.9398)
			(stroke
				(width 0.1524)
				(type default)
			)
			(layer "F.SilkS")
		)
		(fp_line
			(start -0.508 -0.9398)
			(end -0.508 0.9398)
			(stroke
				(width 0.1524)
				(type default)
			)
			(layer "F.SilkS")
		)
		(fp_rect
			(start -0.508 0.9398)
			(end 0.508 -0.9398)
			(stroke
				(width 0)
				(type default)
			)
			(fill no)
			(layer "F.CrtYd")
		)
		(fp_rect
			(start -0.508 0.9398)
			(end 0.508 -0.9398)
			(stroke
				(width 0)
				(type default)
			)
			(fill no)
			(layer "F.Fab")
		)
		(pad "1" smd custom
			(at 0 -0.4445 180)
			(size 0.1397 0.1397)
			(layers "F.Cu" "F.Mask" "F.Paste")
			(net "P3V3_STBY_B")
			(options
				(clearance outline)
				(anchor circle)
			)
			(primitives
				(gr_poly
					(pts
						(arc
							(start -0.1778 -0.2794)
							(mid -0.249642 -0.249642)
							(end -0.2794 -0.1778)
						)
						(arc
							(start -0.2794 0.1778)
							(mid -0.249642 0.249642)
							(end -0.1778 0.2794)
						)
						(arc
							(start 0.1778 0.2794)
							(mid 0.249642 0.249642)
							(end 0.2794 0.1778)
						)
						(arc
							(start 0.2794 -0.1778)
							(mid 0.249642 -0.249642)
							(end 0.1778 -0.2794)
						)
					)
					(width 0)
					(fill yes)
				)
			)
		)
		(pad "2" smd custom
			(at 0 0.4445 180)
			(size 0.1397 0.1397)
			(layers "F.Cu" "F.Mask" "F.Paste")
			(net "HDD_PRSNT_19")
			(options
				(clearance outline)
				(anchor circle)
			)
			(primitives
				(gr_poly
					(pts
						(arc
							(start -0.1778 -0.2794)
							(mid -0.249642 -0.249642)
							(end -0.2794 -0.1778)
						)
						(arc
							(start -0.2794 0.1778)
							(mid -0.249642 0.249642)
							(end -0.1778 0.2794)
						)
						(arc
							(start 0.1778 0.2794)
							(mid 0.249642 0.249642)
							(end 0.2794 0.1778)
						)
						(arc
							(start 0.2794 -0.1778)
							(mid 0.249642 -0.249642)
							(end 0.1778 -0.2794)
						)
					)
					(width 0)
					(fill yes)
				)
			)
		)
	)
	(footprint ""
		(layer "F.Cu")
		(at 349.6818 -32.8676 180)
		(property "Reference" "R787"
			(at 0 0 180)
			(layer "F.SilkS")
			(hide yes)
			(effects
				(font
					(size 1.27 1.27)
				)
			)
		)
		(property "Value" "220R3F-1-GP"
			(at -0.0254 -2.5146 180)
			(unlocked yes)
			(layer "F.Fab")
			(hide yes)
			(effects
				(font
					(size 1.016 1.016)
					(thickness 0.1524)
				)
			)
		)
		(property "Device Type" "R603H22"
			(at -0.0254 -4.0386 180)
			(unlocked yes)
			(layer "F.Fab")
			(hide yes)
			(effects
				(font
					(size 1.016 1.016)
					(thickness 0.1524)
				)
			)
		)
		(duplicate_pad_numbers_are_jumpers no)
		(fp_line
			(start 0.2032 0)
			(end 0.4826 0)
			(stroke
				(width 0.2032)
				(type default)
			)
			(layer "F.SilkS")
		)
		(fp_line
			(start -0.4826 0)
			(end -0.2032 0)
			(stroke
				(width 0.2032)
				(type default)
			)
			(layer "F.SilkS")
		)
		(fp_rect
			(start -0.5842 1.3335)
			(end 0.5842 -1.3335)
			(stroke
				(width 0)
				(type default)
			)
			(fill no)
			(layer "F.CrtYd")
		)
		(fp_rect
			(start -0.5842 1.3335)
			(end 0.5842 -1.3335)
			(stroke
				(width 0)
				(type default)
			)
			(fill no)
			(layer "F.Fab")
		)
		(pad "1" smd custom
			(at 0 -0.762 180)
			(size 0.2159 0.2159)
			(layers "F.Cu" "F.Mask" "F.Paste")
			(net "HDD_PRSNT_31")
			(options
				(clearance outline)
				(anchor circle)
			)
			(primitives
				(gr_poly
					(pts
						(arc
							(start -0.3302 -0.4318)
							(mid -0.402042 -0.402042)
							(end -0.4318 -0.3302)
						)
						(arc
							(start -0.4318 0.3302)
							(mid -0.402042 0.402042)
							(end -0.3302 0.4318)
						)
						(arc
							(start 0.3302 0.4318)
							(mid 0.402042 0.402042)
							(end 0.4318 0.3302)
						)
						(arc
							(start 0.4318 -0.3302)
							(mid 0.402042 -0.402042)
							(end 0.3302 -0.4318)
						)
					)
					(width 0)
					(fill yes)
				)
			)
		)
		(pad "2" smd custom
			(at 0 0.762 180)
			(size 0.2159 0.2159)
			(layers "F.Cu" "F.Mask" "F.Paste")
			(net "DRIVE_B_31_INS")
			(options
				(clearance outline)
				(anchor circle)
			)
			(primitives
				(gr_poly
					(pts
						(arc
							(start -0.3302 -0.4318)
							(mid -0.402042 -0.402042)
							(end -0.4318 -0.3302)
						)
						(arc
							(start -0.4318 0.3302)
							(mid -0.402042 0.402042)
							(end -0.3302 0.4318)
						)
						(arc
							(start 0.3302 0.4318)
							(mid 0.402042 0.402042)
							(end 0.4318 0.3302)
						)
						(arc
							(start 0.4318 -0.3302)
							(mid 0.402042 -0.402042)
							(end 0.3302 -0.4318)
						)
					)
					(width 0)
					(fill yes)
				)
			)
		)
	)
	(footprint ""
		(layer "F.Cu")
		(at 64.0588 -248.750074 -90)
		(property "Reference" "VIA4"
			(at 0 0 270)
			(layer "F.SilkS")
			(hide yes)
			(effects
				(font
					(size 1.27 1.27)
				)
			)
		)
		(property "Value" "100OHM-8L-2D36MM-L16-GP"
			(at -3.4036 -0.4572 270)
			(unlocked yes)
			(layer "F.Fab")
			(hide yes)
			(effects
				(font
					(size 1.016 1.016)
					(thickness 0.1524)
				)
			)
		)
		(property "Device Type" "VIA-PCIE-4P-427097"
			(at -3.4036 -1.9812 270)
			(unlocked yes)
			(layer "F.Fab")
			(hide yes)
			(effects
				(font
					(size 1.016 1.016)
					(thickness 0.1524)
				)
			)
		)
		(duplicate_pad_numbers_are_jumpers no)
		(fp_rect
			(start -2.1336 0.4826)
			(end 2.1336 -0.4826)
			(stroke
				(width 0)
				(type default)
			)
			(fill no)
			(layer "F.CrtYd")
		)
		(fp_rect
			(start -2.1336 0.4826)
			(end 2.1336 -0.4826)
			(stroke
				(width 0)
				(type default)
			)
			(fill no)
			(layer "F.Fab")
		)
		(pad "1" thru_hole circle
			(at -1.651 0 270)
			(size 0.508 0.508)
			(drill 0.254)
			(layers "*.Cu" "*.Mask")
			(remove_unused_layers no)
			(net "GND")
			(clearance 0.2286)
			(thermal_gap 0.2286)
		)
		(pad "2" thru_hole circle
			(at -0.635 0 270)
			(size 0.508 0.508)
			(drill 0.254)
			(layers "*.Cu" "*.Mask")
			(remove_unused_layers no)
			(net "PHY_DRV_B_TO_SCC_B_1_DP")
			(clearance 0.2286)
			(thermal_gap 0.2286)
		)
		(pad "3" thru_hole circle
			(at 0.635 0 270)
			(size 0.508 0.508)
			(drill 0.254)
			(layers "*.Cu" "*.Mask")
			(remove_unused_layers no)
			(net "PHY_DRV_B_TO_SCC_B_1_DN")
			(clearance 0.2286)
			(thermal_gap 0.2286)
		)
		(pad "4" thru_hole circle
			(at 1.651 0 270)
			(size 0.508 0.508)
			(drill 0.254)
			(layers "*.Cu" "*.Mask")
			(remove_unused_layers no)
			(net "GND")
			(clearance 0.2286)
			(thermal_gap 0.2286)
		)
	)
	(footprint ""
		(layer "F.Cu")
		(at 174.625 -247.65 180)
		(property "Reference" "D5"
			(at 0 0 180)
			(layer "F.SilkS")
			(hide yes)
			(effects
				(font
					(size 1.27 1.27)
				)
			)
		)
		(property "Value" "RB551V30-GP"
			(at 0 -6.7818 180)
			(unlocked yes)
			(layer "F.Fab")
			(hide yes)
			(effects
				(font
					(size 1.016 1.016)
					(thickness 0.1524)
				)
			)
		)
		(property "Device Type" "SOD323AKH38"
			(at 0 -8.6868 180)
			(unlocked yes)
			(layer "F.Fab")
			(hide yes)
			(effects
				(font
					(size 1.016 1.016)
					(thickness 0.1524)
				)
			)
		)
		(duplicate_pad_numbers_are_jumpers no)
		(fp_line
			(start 0.889 2.159)
			(end -0.889 2.159)
			(stroke
				(width 0.1524)
				(type default)
			)
			(layer "F.SilkS")
		)
		(fp_line
			(start 0.889 -1.9304)
			(end 0.889 2.159)
			(stroke
				(width 0.1524)
				(type default)
			)
			(layer "F.SilkS")
		)
		(fp_line
			(start 0.762 2.0574)
			(end -0.762 2.0574)
			(stroke
				(width 0.508)
				(type default)
			)
			(layer "F.SilkS")
		)
		(fp_line
			(start -0.889 2.159)
			(end -0.889 -1.9304)
			(stroke
				(width 0.1524)
				(type default)
			)
			(layer "F.SilkS")
		)
		(fp_line
			(start -0.889 -1.9304)
			(end 0.889 -1.9304)
			(stroke
				(width 0.1524)
				(type default)
			)
			(layer "F.SilkS")
		)
		(fp_rect
			(start -1.016 2.3114)
			(end 1.016 -2.0066)
			(stroke
				(width 0)
				(type default)
			)
			(fill no)
			(layer "F.CrtYd")
		)
		(fp_poly
			(pts
				(xy -1.016 -2.0066) (xy 1.016 -2.0066) (xy 1.016 2.3114) (xy -1.016 2.3114)
			)
			(stroke
				(width 0)
				(type default)
			)
			(fill no)
			(layer "F.Fab")
		)
		(pad "A" smd rect
			(at 0 -1.143 180)
			(size 0.5588 1.016)
			(layers "F.Cu" "F.Mask" "F.Paste")
			(net "SW_HDD_R5")
		)
		(pad "K" smd rect
			(at 0 1.143 180)
			(size 0.5588 1.016)
			(layers "F.Cu" "F.Mask" "F.Paste")
			(net "SW_HDD_N5")
		)
	)
	(footprint ""
		(layer "F.Cu")
		(at 118.999 -19.177)
		(property "Reference" "R701"
			(at 0 0 0)
			(layer "F.SilkS")
			(hide yes)
			(effects
				(font
					(size 1.27 1.27)
				)
			)
		)
		(property "Value" "0R2J-2-GP"
			(at 0.064008 -3.993896 0)
			(unlocked yes)
			(layer "F.Fab")
			(hide yes)
			(effects
				(font
					(size 1.016 1.016)
					(thickness 0.1524)
				)
			)
		)
		(property "Device Type" "R402H16"
			(at 0.064008 -5.517896 0)
			(unlocked yes)
			(layer "F.Fab")
			(hide yes)
			(effects
				(font
					(size 1.016 1.016)
					(thickness 0.1524)
				)
			)
		)
		(duplicate_pad_numbers_are_jumpers no)
		(fp_line
			(start -0.508 -0.9398)
			(end -0.508 0.9398)
			(stroke
				(width 0.1524)
				(type default)
			)
			(layer "F.SilkS")
		)
		(fp_line
			(start 0.508 -0.9398)
			(end -0.508 -0.9398)
			(stroke
				(width 0.1524)
				(type default)
			)
			(layer "F.SilkS")
		)
		(fp_rect
			(start -0.508 0.9398)
			(end 0.508 -0.9398)
			(stroke
				(width 0)
				(type default)
			)
			(fill no)
			(layer "F.CrtYd")
		)
		(fp_rect
			(start -0.508 0.9398)
			(end 0.508 -0.9398)
			(stroke
				(width 0)
				(type default)
			)
			(fill no)
			(layer "F.Fab")
		)
		(pad "1" smd custom
			(at 0 -0.4445)
			(size 0.1397 0.1397)
			(layers "F.Cu" "F.Mask" "F.Paste")
			(net "DRIVE_B_27_PWR")
			(options
				(clearance outline)
				(anchor circle)
			)
			(primitives
				(gr_poly
					(pts
						(arc
							(start -0.1778 -0.2794)
							(mid -0.249642 -0.249642)
							(end -0.2794 -0.1778)
						)
						(arc
							(start -0.2794 0.1778)
							(mid -0.249642 0.249642)
							(end -0.1778 0.2794)
						)
						(arc
							(start 0.1778 0.2794)
							(mid 0.249642 0.249642)
							(end 0.2794 0.1778)
						)
						(arc
							(start 0.2794 -0.1778)
							(mid 0.249642 -0.249642)
							(end 0.1778 -0.2794)
						)
					)
					(width 0)
					(fill yes)
				)
			)
		)
		(pad "2" smd custom
			(at 0 0.4445)
			(size 0.1397 0.1397)
			(layers "F.Cu" "F.Mask" "F.Paste")
			(net "SW_PWR_R_HDD27")
			(options
				(clearance outline)
				(anchor circle)
			)
			(primitives
				(gr_poly
					(pts
						(arc
							(start -0.1778 -0.2794)
							(mid -0.249642 -0.249642)
							(end -0.2794 -0.1778)
						)
						(arc
							(start -0.2794 0.1778)
							(mid -0.249642 0.249642)
							(end -0.1778 0.2794)
						)
						(arc
							(start 0.1778 0.2794)
							(mid 0.249642 0.249642)
							(end 0.2794 0.1778)
						)
						(arc
							(start 0.2794 -0.1778)
							(mid 0.249642 -0.249642)
							(end 0.1778 -0.2794)
						)
					)
					(width 0)
					(fill yes)
				)
			)
		)
	)
	(footprint ""
		(layer "F.Cu")
		(at 86.106 -134.493 90)
		(property "Reference" "R404"
			(at 0 0 90)
			(layer "F.SilkS")
			(hide yes)
			(effects
				(font
					(size 1.27 1.27)
				)
			)
		)
		(property "Value" "4K7R2F-GP"
			(at 0.064008 -3.993896 90)
			(unlocked yes)
			(layer "F.Fab")
			(hide yes)
			(effects
				(font
					(size 1.016 1.016)
					(thickness 0.1524)
				)
			)
		)
		(property "Device Type" "R402H16"
			(at 0.064008 -5.517896 90)
			(unlocked yes)
			(layer "F.Fab")
			(hide yes)
			(effects
				(font
					(size 1.016 1.016)
					(thickness 0.1524)
				)
			)
		)
		(duplicate_pad_numbers_are_jumpers no)
		(fp_line
			(start 0.508 -0.9398)
			(end -0.508 -0.9398)
			(stroke
				(width 0.1524)
				(type default)
			)
			(layer "F.SilkS")
		)
		(fp_line
			(start -0.508 -0.9398)
			(end -0.508 0.9398)
			(stroke
				(width 0.1524)
				(type default)
			)
			(layer "F.SilkS")
		)
		(fp_rect
			(start -0.508 0.9398)
			(end 0.508 -0.9398)
			(stroke
				(width 0)
				(type default)
			)
			(fill no)
			(layer "F.CrtYd")
		)
		(fp_rect
			(start -0.508 0.9398)
			(end 0.508 -0.9398)
			(stroke
				(width 0)
				(type default)
			)
			(fill no)
			(layer "F.Fab")
		)
		(pad "1" smd custom
			(at 0 -0.4445 90)
			(size 0.1397 0.1397)
			(layers "F.Cu" "F.Mask" "F.Paste")
			(net "SW_PWR_R_HDD14")
			(options
				(clearance outline)
				(anchor circle)
			)
			(primitives
				(gr_poly
					(pts
						(arc
							(start -0.1778 -0.2794)
							(mid -0.249642 -0.249642)
							(end -0.2794 -0.1778)
						)
						(arc
							(start -0.2794 0.1778)
							(mid -0.249642 0.249642)
							(end -0.1778 0.2794)
						)
						(arc
							(start 0.1778 0.2794)
							(mid 0.249642 0.249642)
							(end 0.2794 0.1778)
						)
						(arc
							(start 0.2794 -0.1778)
							(mid 0.249642 -0.249642)
							(end 0.1778 -0.2794)
						)
					)
					(width 0)
					(fill yes)
				)
			)
		)
		(pad "2" smd custom
			(at 0 0.4445 90)
			(size 0.1397 0.1397)
			(layers "F.Cu" "F.Mask" "F.Paste")
			(net "GND")
			(options
				(clearance outline)
				(anchor circle)
			)
			(primitives
				(gr_poly
					(pts
						(arc
							(start -0.1778 -0.2794)
							(mid -0.249642 -0.249642)
							(end -0.2794 -0.1778)
						)
						(arc
							(start -0.2794 0.1778)
							(mid -0.249642 0.249642)
							(end -0.1778 0.2794)
						)
						(arc
							(start 0.1778 0.2794)
							(mid 0.249642 0.249642)
							(end 0.2794 0.1778)
						)
						(arc
							(start 0.2794 -0.1778)
							(mid 0.249642 -0.249642)
							(end 0.1778 -0.2794)
						)
					)
					(width 0)
					(fill yes)
				)
			)
		)
	)
	(footprint ""
		(layer "F.Cu")
		(at 113.538 -35.687 90)
		(property "Reference" "R692"
			(at 0 0 90)
			(layer "F.SilkS")
			(hide yes)
			(effects
				(font
					(size 1.27 1.27)
				)
			)
		)
		(property "Value" "2R6F-GP"
			(at -0.0508 -4.8514 90)
			(unlocked yes)
			(layer "F.Fab")
			(hide yes)
			(effects
				(font
					(size 1.016 1.016)
					(thickness 0.1524)
				)
			)
		)
		(property "Device Type" "R1206H26"
			(at 0 -6.3754 90)
			(unlocked yes)
			(layer "F.Fab")
			(hide yes)
			(effects
				(font
					(size 1.016 1.016)
					(thickness 0.1524)
				)
			)
		)
		(duplicate_pad_numbers_are_jumpers no)
		(fp_line
			(start 1.016 -2.2352)
			(end 1.016 2.2352)
			(stroke
				(width 0.1524)
				(type default)
			)
			(layer "F.SilkS")
		)
		(fp_line
			(start -1.016 -2.2352)
			(end 1.016 -2.2352)
			(stroke
				(width 0.1524)
				(type default)
			)
			(layer "F.SilkS")
		)
		(fp_line
			(start 1.016 2.2352)
			(end -1.016 2.2352)
			(stroke
				(width 0.1524)
				(type default)
			)
			(layer "F.SilkS")
		)
		(fp_line
			(start -1.016 2.2352)
			(end -1.016 -2.2352)
			(stroke
				(width 0.1524)
				(type default)
			)
			(layer "F.SilkS")
		)
		(fp_rect
			(start -1.0922 2.3114)
			(end 1.0922 -2.3114)
			(stroke
				(width 0)
				(type default)
			)
			(fill no)
			(layer "F.CrtYd")
		)
		(fp_poly
			(pts
				(xy -1.0922 -2.3114) (xy 1.0922 -2.3114) (xy 1.0922 2.3114) (xy -1.0922 2.3114)
			)
			(stroke
				(width 0)
				(type default)
			)
			(fill no)
			(layer "F.Fab")
		)
		(pad "1" smd rect
			(at 0 -1.397 90)
			(size 1.651 1.27)
			(layers "F.Cu" "F.Mask" "F.Paste")
			(net "P12V_HDD27")
		)
		(pad "2" smd rect
			(at 0 1.397 90)
			(size 1.651 1.27)
			(layers "F.Cu" "F.Mask" "F.Paste")
			(net "12V_PRE_27")
		)
	)
	(footprint ""
		(layer "F.Cu")
		(at 242.697 -311.912)
		(property "Reference" "R1084"
			(at 0 0 0)
			(layer "F.SilkS")
			(hide yes)
			(effects
				(font
					(size 1.27 1.27)
				)
			)
		)
		(property "Value" "4K7R2F-GP"
			(at 0.064008 -3.993896 0)
			(unlocked yes)
			(layer "F.Fab")
			(hide yes)
			(effects
				(font
					(size 1.016 1.016)
					(thickness 0.1524)
				)
			)
		)
		(property "Device Type" "R402H16"
			(at 0.064008 -5.517896 0)
			(unlocked yes)
			(layer "F.Fab")
			(hide yes)
			(effects
				(font
					(size 1.016 1.016)
					(thickness 0.1524)
				)
			)
		)
		(duplicate_pad_numbers_are_jumpers no)
		(fp_line
			(start -0.508 -0.9398)
			(end -0.508 0.9398)
			(stroke
				(width 0.1524)
				(type default)
			)
			(layer "F.SilkS")
		)
		(fp_line
			(start 0.508 -0.9398)
			(end -0.508 -0.9398)
			(stroke
				(width 0.1524)
				(type default)
			)
			(layer "F.SilkS")
		)
		(fp_rect
			(start -0.508 0.9398)
			(end 0.508 -0.9398)
			(stroke
				(width 0)
				(type default)
			)
			(fill no)
			(layer "F.CrtYd")
		)
		(fp_rect
			(start -0.508 0.9398)
			(end 0.508 -0.9398)
			(stroke
				(width 0)
				(type default)
			)
			(fill no)
			(layer "F.Fab")
		)
		(pad "1" smd custom
			(at 0 -0.4445)
			(size 0.1397 0.1397)
			(layers "F.Cu" "F.Mask" "F.Paste")
			(net "P3V3_STBY_A")
			(options
				(clearance outline)
				(anchor circle)
			)
			(primitives
				(gr_poly
					(pts
						(arc
							(start -0.1778 -0.2794)
							(mid -0.249642 -0.249642)
							(end -0.2794 -0.1778)
						)
						(arc
							(start -0.2794 0.1778)
							(mid -0.249642 0.249642)
							(end -0.1778 0.2794)
						)
						(arc
							(start 0.1778 0.2794)
							(mid 0.249642 0.249642)
							(end 0.2794 0.1778)
						)
						(arc
							(start 0.2794 -0.1778)
							(mid 0.249642 -0.249642)
							(end 0.1778 -0.2794)
						)
					)
					(width 0)
					(fill yes)
				)
			)
		)
		(pad "2" smd custom
			(at 0 0.4445)
			(size 0.1397 0.1397)
			(layers "F.Cu" "F.Mask" "F.Paste")
			(net "MAX31790_A_ADD1")
			(options
				(clearance outline)
				(anchor circle)
			)
			(primitives
				(gr_poly
					(pts
						(arc
							(start -0.1778 -0.2794)
							(mid -0.249642 -0.249642)
							(end -0.2794 -0.1778)
						)
						(arc
							(start -0.2794 0.1778)
							(mid -0.249642 0.249642)
							(end -0.1778 0.2794)
						)
						(arc
							(start 0.1778 0.2794)
							(mid 0.249642 0.249642)
							(end 0.2794 0.1778)
						)
						(arc
							(start 0.2794 -0.1778)
							(mid 0.249642 -0.249642)
							(end 0.1778 -0.2794)
						)
					)
					(width 0)
					(fill yes)
				)
			)
		)
	)
	(footprint ""
		(layer "F.Cu")
		(at 160.485582 -244.990874 90)
		(property "Reference" "VIA9"
			(at 0 0 90)
			(layer "F.SilkS")
			(hide yes)
			(effects
				(font
					(size 1.27 1.27)
				)
			)
		)
		(property "Value" "100OHM-8L-2D36MM-L18-GP"
			(at 3.8989 0.5715 90)
			(unlocked yes)
			(layer "F.Fab")
			(hide yes)
			(effects
				(font
					(size 1.016 1.016)
					(thickness 0.1524)
				)
			)
		)
		(property "Device Type" "VIA-PCIE-4P-414097"
			(at 3.8989 -0.9525 90)
			(unlocked yes)
			(layer "F.Fab")
			(hide yes)
			(effects
				(font
					(size 1.016 1.016)
					(thickness 0.1524)
				)
			)
		)
		(duplicate_pad_numbers_are_jumpers no)
		(fp_rect
			(start -2.0701 0.4826)
			(end 2.0701 -0.4826)
			(stroke
				(width 0)
				(type default)
			)
			(fill no)
			(layer "F.CrtYd")
		)
		(fp_rect
			(start -2.0701 0.4826)
			(end 2.0701 -0.4826)
			(stroke
				(width 0)
				(type default)
			)
			(fill no)
			(layer "F.Fab")
		)
		(pad "1" thru_hole circle
			(at -1.5875 0 90)
			(size 0.508 0.508)
			(drill 0.254)
			(layers "*.Cu" "*.Mask")
			(remove_unused_layers no)
			(net "GND")
			(clearance 0.2286)
			(thermal_gap 0.2286)
		)
		(pad "2" thru_hole circle
			(at -0.5715 0 90)
			(size 0.508 0.508)
			(drill 0.254)
			(layers "*.Cu" "*.Mask")
			(remove_unused_layers no)
			(net "PHY_SCC_B_TO_DRV_B_4_DP")
			(clearance 0.2286)
			(thermal_gap 0.2286)
		)
		(pad "3" thru_hole circle
			(at 0.5715 0 90)
			(size 0.508 0.508)
			(drill 0.254)
			(layers "*.Cu" "*.Mask")
			(remove_unused_layers no)
			(net "PHY_SCC_B_TO_DRV_B_4_DN")
			(clearance 0.2286)
			(thermal_gap 0.2286)
		)
		(pad "4" thru_hole circle
			(at 1.5875 0 90)
			(size 0.508 0.508)
			(drill 0.254)
			(layers "*.Cu" "*.Mask")
			(remove_unused_layers no)
			(net "GND")
			(clearance 0.2286)
			(thermal_gap 0.2286)
		)
	)
	(footprint ""
		(layer "F.Cu")
		(at 247.761252 -368.784632 180)
		(property "Reference" "R1024"
			(at 0 0 180)
			(layer "F.SilkS")
			(hide yes)
			(effects
				(font
					(size 1.27 1.27)
				)
			)
		)
		(property "Value" "100R2D-GP"
			(at 0.064008 -3.993896 180)
			(unlocked yes)
			(layer "F.Fab")
			(hide yes)
			(effects
				(font
					(size 1.016 1.016)
					(thickness 0.1524)
				)
			)
		)
		(property "Device Type" "R402H14"
			(at 0.064008 -5.517896 180)
			(unlocked yes)
			(layer "F.Fab")
			(hide yes)
			(effects
				(font
					(size 1.016 1.016)
					(thickness 0.1524)
				)
			)
		)
		(duplicate_pad_numbers_are_jumpers no)
		(fp_line
			(start 0.508 -0.9398)
			(end -0.508 -0.9398)
			(stroke
				(width 0.1524)
				(type default)
			)
			(layer "F.SilkS")
		)
		(fp_line
			(start -0.508 -0.9398)
			(end -0.508 0.9398)
			(stroke
				(width 0.1524)
				(type default)
			)
			(layer "F.SilkS")
		)
		(fp_rect
			(start -0.508 0.9398)
			(end 0.508 -0.9398)
			(stroke
				(width 0)
				(type default)
			)
			(fill no)
			(layer "F.CrtYd")
		)
		(fp_rect
			(start -0.508 0.9398)
			(end 0.508 -0.9398)
			(stroke
				(width 0)
				(type default)
			)
			(fill no)
			(layer "F.Fab")
		)
		(pad "1" smd custom
			(at 0 -0.4445 180)
			(size 0.1397 0.1397)
			(layers "F.Cu" "F.Mask" "F.Paste")
			(net "MB3_TEMP")
			(options
				(clearance outline)
				(anchor circle)
			)
			(primitives
				(gr_poly
					(pts
						(arc
							(start -0.1778 -0.2794)
							(mid -0.249642 -0.249642)
							(end -0.2794 -0.1778)
						)
						(arc
							(start -0.2794 0.1778)
							(mid -0.249642 0.249642)
							(end -0.1778 0.2794)
						)
						(arc
							(start 0.1778 0.2794)
							(mid 0.249642 0.249642)
							(end 0.2794 0.1778)
						)
						(arc
							(start 0.2794 -0.1778)
							(mid 0.249642 -0.249642)
							(end 0.1778 -0.2794)
						)
					)
					(width 0)
					(fill yes)
				)
			)
		)
		(pad "2" smd custom
			(at 0 0.4445 180)
			(size 0.1397 0.1397)
			(layers "F.Cu" "F.Mask" "F.Paste")
			(net "MB3_TEMP_B")
			(options
				(clearance outline)
				(anchor circle)
			)
			(primitives
				(gr_poly
					(pts
						(arc
							(start -0.1778 -0.2794)
							(mid -0.249642 -0.249642)
							(end -0.2794 -0.1778)
						)
						(arc
							(start -0.2794 0.1778)
							(mid -0.249642 0.249642)
							(end -0.1778 0.2794)
						)
						(arc
							(start 0.1778 0.2794)
							(mid 0.249642 0.249642)
							(end 0.2794 0.1778)
						)
						(arc
							(start 0.2794 -0.1778)
							(mid 0.249642 -0.249642)
							(end 0.1778 -0.2794)
						)
					)
					(width 0)
					(fill yes)
				)
			)
		)
	)
	(footprint ""
		(layer "F.Cu")
		(at 209.423 -204.978 -90)
		(property "Reference" "R48"
			(at 0 0 270)
			(layer "F.SilkS")
			(hide yes)
			(effects
				(font
					(size 1.27 1.27)
				)
			)
		)
		(property "Value" "0R2J-2-GP"
			(at 0.064008 -3.993896 270)
			(unlocked yes)
			(layer "F.Fab")
			(hide yes)
			(effects
				(font
					(size 1.016 1.016)
					(thickness 0.1524)
				)
			)
		)
		(property "Device Type" "R402H16"
			(at 0.064008 -5.517896 270)
			(unlocked yes)
			(layer "F.Fab")
			(hide yes)
			(effects
				(font
					(size 1.016 1.016)
					(thickness 0.1524)
				)
			)
		)
		(duplicate_pad_numbers_are_jumpers no)
		(fp_line
			(start -0.508 -0.9398)
			(end -0.508 0.9398)
			(stroke
				(width 0.1524)
				(type default)
			)
			(layer "F.SilkS")
		)
		(fp_line
			(start 0.508 -0.9398)
			(end -0.508 -0.9398)
			(stroke
				(width 0.1524)
				(type default)
			)
			(layer "F.SilkS")
		)
		(fp_rect
			(start -0.508 0.9398)
			(end 0.508 -0.9398)
			(stroke
				(width 0)
				(type default)
			)
			(fill no)
			(layer "F.CrtYd")
		)
		(fp_rect
			(start -0.508 0.9398)
			(end 0.508 -0.9398)
			(stroke
				(width 0)
				(type default)
			)
			(fill no)
			(layer "F.Fab")
		)
		(pad "1" smd custom
			(at 0 -0.4445 270)
			(size 0.1397 0.1397)
			(layers "F.Cu" "F.Mask" "F.Paste")
			(net "IO_EXP5_SDA")
			(options
				(clearance outline)
				(anchor circle)
			)
			(primitives
				(gr_poly
					(pts
						(arc
							(start -0.1778 -0.2794)
							(mid -0.249642 -0.249642)
							(end -0.2794 -0.1778)
						)
						(arc
							(start -0.2794 0.1778)
							(mid -0.249642 0.249642)
							(end -0.1778 0.2794)
						)
						(arc
							(start 0.1778 0.2794)
							(mid 0.249642 0.249642)
							(end 0.2794 0.1778)
						)
						(arc
							(start 0.2794 -0.1778)
							(mid 0.249642 -0.249642)
							(end 0.1778 -0.2794)
						)
					)
					(width 0)
					(fill yes)
				)
			)
		)
		(pad "2" smd custom
			(at 0 0.4445 270)
			(size 0.1397 0.1397)
			(layers "F.Cu" "F.Mask" "F.Paste")
			(net "I2C_DRIVE_B_INS_SDA")
			(options
				(clearance outline)
				(anchor circle)
			)
			(primitives
				(gr_poly
					(pts
						(arc
							(start -0.1778 -0.2794)
							(mid -0.249642 -0.249642)
							(end -0.2794 -0.1778)
						)
						(arc
							(start -0.2794 0.1778)
							(mid -0.249642 0.249642)
							(end -0.1778 0.2794)
						)
						(arc
							(start 0.1778 0.2794)
							(mid 0.249642 0.249642)
							(end 0.2794 0.1778)
						)
						(arc
							(start 0.2794 -0.1778)
							(mid 0.249642 -0.249642)
							(end 0.1778 -0.2794)
						)
					)
					(width 0)
					(fill yes)
				)
			)
		)
	)
	(footprint ""
		(layer "F.Cu")
		(at 183.134 -366.649 90)
		(property "Reference" "R991"
			(at 0 0 90)
			(layer "F.SilkS")
			(hide yes)
			(effects
				(font
					(size 1.27 1.27)
				)
			)
		)
		(property "Value" "0R0603-PAD-2-GP-U"
			(at 2.1209 -0.1397 90)
			(unlocked yes)
			(layer "F.Fab")
			(hide yes)
			(effects
				(font
					(size 1.016 1.016)
					(thickness 0.1524)
				)
			)
		)
		(property "Device Type" "0R0603-PAD-1-U"
			(at 2.1209 -1.6637 90)
			(unlocked yes)
			(layer "F.Fab")
			(hide yes)
			(effects
				(font
					(size 1.016 1.016)
					(thickness 0.1524)
				)
			)
		)
		(duplicate_pad_numbers_are_jumpers no)
		(fp_rect
			(start -0.5842 1.3335)
			(end 0.5842 -1.3335)
			(stroke
				(width 0)
				(type default)
			)
			(fill no)
			(layer "F.CrtYd")
		)
		(fp_rect
			(start -0.5842 1.3335)
			(end 0.5842 -1.3335)
			(stroke
				(width 0)
				(type default)
			)
			(fill no)
			(layer "F.Fab")
		)
		(pad "1" smd custom
			(at 0 -0.762 90)
			(size 0.2159 0.2159)
			(layers "F.Cu" "F.Mask" "F.Paste")
			(net "AGND_CURRENT_MON")
			(options
				(clearance outline)
				(anchor circle)
			)
			(primitives
				(gr_poly
					(pts
						(arc
							(start -0.3302 -0.5842)
							(mid -0.402042 -0.554442)
							(end -0.4318 -0.4826)
						)
						(arc
							(start -0.4318 0.4826)
							(mid -0.402042 0.554442)
							(end -0.3302 0.5842)
						)
						(arc
							(start 0.3302 0.5842)
							(mid 0.402042 0.554442)
							(end 0.4318 0.4826)
						)
						(arc
							(start 0.4318 -0.4826)
							(mid 0.402042 -0.554442)
							(end 0.3302 -0.5842)
						)
					)
					(width 0)
					(fill yes)
				)
			)
		)
		(pad "2" smd custom
			(at 0 0.762 90)
			(size 0.2159 0.2159)
			(layers "F.Cu" "F.Mask" "F.Paste")
			(net "GND")
			(options
				(clearance outline)
				(anchor circle)
			)
			(primitives
				(gr_poly
					(pts
						(arc
							(start -0.4318 0.4826)
							(mid -0.402042 0.554442)
							(end -0.3302 0.5842)
						)
						(arc
							(start 0.3302 0.5842)
							(mid 0.402042 0.554442)
							(end 0.4318 0.4826)
						)
						(arc
							(start 0.4318 -0.4826)
							(mid 0.402042 -0.554442)
							(end 0.3302 -0.5842)
						)
						(arc
							(start -0.3302 -0.5842)
							(mid -0.402042 -0.554442)
							(end -0.4318 -0.4826)
						)
					)
					(width 0)
					(fill yes)
				)
			)
		)
	)
	(footprint ""
		(layer "F.Cu")
		(at 49.784 -214.249)
		(property "Reference" "R221"
			(at 0 0 0)
			(layer "F.SilkS")
			(hide yes)
			(effects
				(font
					(size 1.27 1.27)
				)
			)
		)
		(property "Value" "91R3F-1-GP"
			(at -0.0254 -2.5146 0)
			(unlocked yes)
			(layer "F.Fab")
			(hide yes)
			(effects
				(font
					(size 1.016 1.016)
					(thickness 0.1524)
				)
			)
		)
		(property "Device Type" "R603H22"
			(at -0.0254 -4.0386 0)
			(unlocked yes)
			(layer "F.Fab")
			(hide yes)
			(effects
				(font
					(size 1.016 1.016)
					(thickness 0.1524)
				)
			)
		)
		(duplicate_pad_numbers_are_jumpers no)
		(fp_line
			(start -0.4826 0)
			(end -0.2032 0)
			(stroke
				(width 0.2032)
				(type default)
			)
			(layer "F.SilkS")
		)
		(fp_line
			(start 0.2032 0)
			(end 0.4826 0)
			(stroke
				(width 0.2032)
				(type default)
			)
			(layer "F.SilkS")
		)
		(fp_rect
			(start -0.5842 1.3335)
			(end 0.5842 -1.3335)
			(stroke
				(width 0)
				(type default)
			)
			(fill no)
			(layer "F.CrtYd")
		)
		(fp_rect
			(start -0.5842 1.3335)
			(end 0.5842 -1.3335)
			(stroke
				(width 0)
				(type default)
			)
			(fill no)
			(layer "F.Fab")
		)
		(pad "1" smd custom
			(at 0 -0.762)
			(size 0.2159 0.2159)
			(layers "F.Cu" "F.Mask" "F.Paste")
			(net "P5V_B_1")
			(options
				(clearance outline)
				(anchor circle)
			)
			(primitives
				(gr_poly
					(pts
						(arc
							(start -0.3302 -0.4318)
							(mid -0.402042 -0.402042)
							(end -0.4318 -0.3302)
						)
						(arc
							(start -0.4318 0.3302)
							(mid -0.402042 0.402042)
							(end -0.3302 0.4318)
						)
						(arc
							(start 0.3302 0.4318)
							(mid 0.402042 0.402042)
							(end 0.4318 0.3302)
						)
						(arc
							(start 0.4318 -0.3302)
							(mid 0.402042 -0.402042)
							(end 0.3302 -0.4318)
						)
					)
					(width 0)
					(fill yes)
				)
			)
		)
		(pad "2" smd custom
			(at 0 0.762)
			(size 0.2159 0.2159)
			(layers "F.Cu" "F.Mask" "F.Paste")
			(net "DRV_ACT_1")
			(options
				(clearance outline)
				(anchor circle)
			)
			(primitives
				(gr_poly
					(pts
						(arc
							(start -0.3302 -0.4318)
							(mid -0.402042 -0.402042)
							(end -0.4318 -0.3302)
						)
						(arc
							(start -0.4318 0.3302)
							(mid -0.402042 0.402042)
							(end -0.3302 0.4318)
						)
						(arc
							(start 0.3302 0.4318)
							(mid 0.402042 0.402042)
							(end 0.4318 0.3302)
						)
						(arc
							(start 0.4318 -0.3302)
							(mid 0.402042 -0.402042)
							(end 0.3302 -0.4318)
						)
					)
					(width 0)
					(fill yes)
				)
			)
		)
	)
	(footprint ""
		(layer "F.Cu")
		(at 305.408076 -327.858882)
		(property "Reference" "R98"
			(at 0 0 0)
			(layer "F.SilkS")
			(hide yes)
			(effects
				(font
					(size 1.27 1.27)
				)
			)
		)
		(property "Value" "100KR2F-L1-GP"
			(at 0.064008 -3.993896 0)
			(unlocked yes)
			(layer "F.Fab")
			(hide yes)
			(effects
				(font
					(size 1.016 1.016)
					(thickness 0.1524)
				)
			)
		)
		(property "Device Type" "R402H16"
			(at 0.064008 -5.517896 0)
			(unlocked yes)
			(layer "F.Fab")
			(hide yes)
			(effects
				(font
					(size 1.016 1.016)
					(thickness 0.1524)
				)
			)
		)
		(duplicate_pad_numbers_are_jumpers no)
		(fp_line
			(start -0.508 -0.9398)
			(end -0.508 0.9398)
			(stroke
				(width 0.1524)
				(type default)
			)
			(layer "F.SilkS")
		)
		(fp_line
			(start 0.508 -0.9398)
			(end -0.508 -0.9398)
			(stroke
				(width 0.1524)
				(type default)
			)
			(layer "F.SilkS")
		)
		(fp_rect
			(start -0.508 0.9398)
			(end 0.508 -0.9398)
			(stroke
				(width 0)
				(type default)
			)
			(fill no)
			(layer "F.CrtYd")
		)
		(fp_rect
			(start -0.508 0.9398)
			(end 0.508 -0.9398)
			(stroke
				(width 0)
				(type default)
			)
			(fill no)
			(layer "F.Fab")
		)
		(pad "1" smd custom
			(at 0 -0.4445)
			(size 0.1397 0.1397)
			(layers "F.Cu" "F.Mask" "F.Paste")
			(net "PWM_BMC_B_ZONE_C")
			(options
				(clearance outline)
				(anchor circle)
			)
			(primitives
				(gr_poly
					(pts
						(arc
							(start -0.1778 -0.2794)
							(mid -0.249642 -0.249642)
							(end -0.2794 -0.1778)
						)
						(arc
							(start -0.2794 0.1778)
							(mid -0.249642 0.249642)
							(end -0.1778 0.2794)
						)
						(arc
							(start 0.1778 0.2794)
							(mid 0.249642 0.249642)
							(end 0.2794 0.1778)
						)
						(arc
							(start 0.2794 -0.1778)
							(mid 0.249642 -0.249642)
							(end 0.1778 -0.2794)
						)
					)
					(width 0)
					(fill yes)
				)
			)
		)
		(pad "2" smd custom
			(at 0 0.4445)
			(size 0.1397 0.1397)
			(layers "F.Cu" "F.Mask" "F.Paste")
			(net "GND")
			(options
				(clearance outline)
				(anchor circle)
			)
			(primitives
				(gr_poly
					(pts
						(arc
							(start -0.1778 -0.2794)
							(mid -0.249642 -0.249642)
							(end -0.2794 -0.1778)
						)
						(arc
							(start -0.2794 0.1778)
							(mid -0.249642 0.249642)
							(end -0.1778 0.2794)
						)
						(arc
							(start 0.1778 0.2794)
							(mid 0.249642 0.249642)
							(end 0.2794 0.1778)
						)
						(arc
							(start 0.2794 -0.1778)
							(mid 0.249642 -0.249642)
							(end 0.1778 -0.2794)
						)
					)
					(width 0)
					(fill yes)
				)
			)
		)
	)
	(footprint ""
		(layer "F.Cu")
		(at 475.107 -146.939 -90)
		(property "Reference" "C330"
			(at 0 0 270)
			(layer "F.SilkS")
			(hide yes)
			(effects
				(font
					(size 1.27 1.27)
				)
			)
		)
		(property "Value" "SC10U16V6KX-2GP"
			(at -0.0762 -5.1308 270)
			(unlocked yes)
			(layer "F.Fab")
			(hide yes)
			(effects
				(font
					(size 1.016 1.016)
					(thickness 0.1524)
				)
			)
		)
		(property "Device Type" "C1206H71"
			(at -0.127 -6.6548 270)
			(unlocked yes)
			(layer "F.Fab")
			(hide yes)
			(effects
				(font
					(size 1.016 1.016)
					(thickness 0.1524)
				)
			)
		)
		(duplicate_pad_numbers_are_jumpers no)
		(fp_line
			(start -1.016 2.2352)
			(end -1.016 0.8382)
			(stroke
				(width 0.1524)
				(type default)
			)
			(layer "F.SilkS")
		)
		(fp_line
			(start 1.016 2.2352)
			(end -1.016 2.2352)
			(stroke
				(width 0.1524)
				(type default)
			)
			(layer "F.SilkS")
		)
		(fp_line
			(start 1.016 0.8382)
			(end 1.016 2.2352)
			(stroke
				(width 0.1524)
				(type default)
			)
			(layer "F.SilkS")
		)
		(fp_line
			(start -1.016 -0.8382)
			(end -1.016 -2.2352)
			(stroke
				(width 0.1524)
				(type default)
			)
			(layer "F.SilkS")
		)
		(fp_line
			(start -1.016 -2.2352)
			(end 1.016 -2.2352)
			(stroke
				(width 0.1524)
				(type default)
			)
			(layer "F.SilkS")
		)
		(fp_line
			(start 1.016 -2.2352)
			(end 1.016 -0.8382)
			(stroke
				(width 0.1524)
				(type default)
			)
			(layer "F.SilkS")
		)
		(fp_rect
			(start -1.0922 2.3114)
			(end 1.0922 -2.3114)
			(stroke
				(width 0)
				(type default)
			)
			(fill no)
			(layer "F.CrtYd")
		)
		(fp_poly
			(pts
				(xy 1.0922 -2.3114) (xy 1.0922 2.3114) (xy -1.0922 2.3114) (xy -1.0922 -2.3114)
			)
			(stroke
				(width 0)
				(type default)
			)
			(fill no)
			(layer "F.Fab")
		)
		(pad "1" smd rect
			(at 0 -1.397 270)
			(size 1.651 1.27)
			(layers "F.Cu" "F.Mask" "F.Paste")
			(net "P5V_HDD23")
		)
		(pad "2" smd rect
			(at 0 1.397 270)
			(size 1.651 1.27)
			(layers "F.Cu" "F.Mask" "F.Paste")
			(net "GND")
		)
	)
	(footprint ""
		(layer "F.Cu")
		(at 368.3 -263.017)
		(property "Reference" "Q28"
			(at 0 0 0)
			(layer "F.SilkS")
			(hide yes)
			(effects
				(font
					(size 1.27 1.27)
				)
			)
		)
		(property "Value" "AO4407AL-GP"
			(at -3.707384 -1.5367 0)
			(unlocked yes)
			(layer "F.Fab")
			(hide yes)
			(effects
				(font
					(size 1.016 1.016)
					(thickness 0.1524)
				)
			)
		)
		(property "Device Type" "SOIC8H69"
			(at -3.707384 -3.0607 0)
			(unlocked yes)
			(layer "F.Fab")
			(hide yes)
			(effects
				(font
					(size 1.016 1.016)
					(thickness 0.1524)
				)
			)
		)
		(duplicate_pad_numbers_are_jumpers no)
		(fp_line
			(start -2.7432 -1.4224)
			(end -2.7432 1.4224)
			(stroke
				(width 0.1524)
				(type default)
			)
			(layer "F.SilkS")
		)
		(fp_line
			(start -2.7432 1.4224)
			(end -2.6416 1.4224)
			(stroke
				(width 0.1524)
				(type default)
			)
			(layer "F.SilkS")
		)
		(fp_line
			(start -2.7432 1.4224)
			(end 2.1336 1.4224)
			(stroke
				(width 0.1524)
				(type default)
			)
			(layer "F.SilkS")
		)
		(fp_line
			(start -2.7178 -0.508)
			(end -2.1844 -0.0508)
			(stroke
				(width 0.1524)
				(type default)
			)
			(layer "F.SilkS")
		)
		(fp_line
			(start -2.6289 3.4417)
			(end -2.6289 1.4732)
			(stroke
				(width 0.381)
				(type default)
			)
			(layer "F.SilkS")
		)
		(fp_line
			(start -2.1844 -0.0508)
			(end -2.7178 0.508)
			(stroke
				(width 0.1524)
				(type default)
			)
			(layer "F.SilkS")
		)
		(fp_line
			(start 2.1336 -1.4224)
			(end -2.7432 -1.4224)
			(stroke
				(width 0.1524)
				(type default)
			)
			(layer "F.SilkS")
		)
		(fp_line
			(start 2.1336 1.4224)
			(end 2.1336 -1.4224)
			(stroke
				(width 0.1524)
				(type default)
			)
			(layer "F.SilkS")
		)
		(fp_poly
			(pts
				(xy -2.2098 -1.4224) (xy -2.2098 1.4224) (xy 2.2098 1.4224) (xy 2.2098 -1.4224)
			)
			(stroke
				(width 0)
				(type default)
			)
			(fill yes)
			(layer "F.SilkS")
		)
		(fp_rect
			(start -2.450084 2.999994)
			(end 2.450084 -2.999994)
			(stroke
				(width 0)
				(type default)
			)
			(fill no)
			(layer "F.CrtYd")
		)
		(fp_poly
			(pts
				(xy -2.8194 3.6322) (xy -2.8194 -3.6322) (xy 2.8194 -3.6322) (xy 2.8194 1.18364) (xy 2.450084 1.18364)
				(xy 2.450084 -2.999994) (xy -2.450084 -2.999994) (xy -2.450084 2.999994) (xy 2.450084 2.999994)
				(xy 2.450084 1.18618) (xy 2.8194 1.18618) (xy 2.8194 3.6322)
			)
			(stroke
				(width 0)
				(type default)
			)
			(fill no)
			(layer "F.CrtYd")
		)
		(fp_rect
			(start -2.8194 3.6322)
			(end 2.8194 -3.6322)
			(stroke
				(width 0)
				(type default)
			)
			(fill no)
			(layer "F.Fab")
		)
		(pad "1" smd rect
			(at -1.905 2.54)
			(size 0.635 1.651)
			(layers "F.Cu" "F.Mask" "F.Paste")
			(net "P12V_B")
		)
		(pad "2" smd rect
			(at -0.635 2.54)
			(size 0.635 1.651)
			(layers "F.Cu" "F.Mask" "F.Paste")
			(net "P12V_B")
		)
		(pad "3" smd rect
			(at 0.635 2.54)
			(size 0.635 1.651)
			(layers "F.Cu" "F.Mask" "F.Paste")
			(net "P12V_B")
		)
		(pad "4" smd rect
			(at 1.905 2.54)
			(size 0.635 1.651)
			(layers "F.Cu" "F.Mask" "F.Paste")
			(net "SW_HDD_N7")
		)
		(pad "5" smd rect
			(at 1.905 -2.54)
			(size 0.635 1.651)
			(layers "F.Cu" "F.Mask" "F.Paste")
			(net "P12V_HDD7")
		)
		(pad "6" smd rect
			(at 0.635 -2.54)
			(size 0.635 1.651)
			(layers "F.Cu" "F.Mask" "F.Paste")
			(net "P12V_HDD7")
		)
		(pad "7" smd rect
			(at -0.635 -2.54)
			(size 0.635 1.651)
			(layers "F.Cu" "F.Mask" "F.Paste")
			(net "P12V_HDD7")
		)
		(pad "8" smd rect
			(at -1.905 -2.54)
			(size 0.635 1.651)
			(layers "F.Cu" "F.Mask" "F.Paste")
			(net "P12V_HDD7")
		)
	)
	(footprint ""
		(layer "F.Cu")
		(at 192.513966 -154.70505)
		(property "Reference" "TP106"
			(at 0 0 0)
			(layer "F.SilkS")
			(hide yes)
			(effects
				(font
					(size 1.27 1.27)
				)
			)
		)
		(property "Value" "*"
			(at -0.0508 -1.6764 0)
			(unlocked yes)
			(layer "F.Fab")
			(hide yes)
			(effects
				(font
					(size 1.016 1.016)
					(thickness 0.1524)
				)
			)
		)
		(property "Device Type" "TPAD32"
			(at -0.0508 -3.2004 0)
			(unlocked yes)
			(layer "F.Fab")
			(hide yes)
			(effects
				(font
					(size 1.016 1.016)
					(thickness 0.1524)
				)
			)
		)
		(duplicate_pad_numbers_are_jumpers no)
		(fp_poly
			(pts
				(arc
					(start 0.4064 0)
					(mid -0.4064 0)
					(end 0.4064 0)
				)
			)
			(stroke
				(width 0)
				(type default)
			)
			(fill no)
			(layer "F.CrtYd")
		)
		(fp_poly
			(pts
				(arc
					(start 0.7112 0)
					(mid -0.7112 0)
					(end 0.7112 0)
				)
			)
			(stroke
				(width 0)
				(type default)
			)
			(fill no)
			(layer "F.Fab")
		)
		(pad "1" smd circle
			(at 0 0)
			(size 0.8128 0.8128)
			(layers "F.Cu" "F.Mask" "F.Paste")
			(net "ACT_HDD_17")
		)
	)
	(footprint ""
		(layer "F.Cu")
		(at 109.1946 -99.7204 180)
		(property "Reference" "Q234"
			(at 0 0 180)
			(layer "F.SilkS")
			(hide yes)
			(effects
				(font
					(size 1.27 1.27)
				)
			)
		)
		(property "Value" "2N7002K-2-GP"
			(at 0.127 -8.9662 180)
			(unlocked yes)
			(layer "F.Fab")
			(hide yes)
			(effects
				(font
					(size 1.016 1.016)
					(thickness 0.1524)
				)
			)
		)
		(property "Device Type" "SOT23DGS2D4H44"
			(at 0.127 -10.4902 180)
			(unlocked yes)
			(layer "F.Fab")
			(hide yes)
			(effects
				(font
					(size 1.016 1.016)
					(thickness 0.1524)
				)
			)
		)
		(duplicate_pad_numbers_are_jumpers no)
		(fp_line
			(start 1.651 1.778)
			(end 1.651 -1.778)
			(stroke
				(width 0.1524)
				(type default)
			)
			(layer "F.SilkS")
		)
		(fp_line
			(start 1.651 -1.778)
			(end -1.651 -1.778)
			(stroke
				(width 0.1524)
				(type default)
			)
			(layer "F.SilkS")
		)
		(fp_line
			(start -1.651 1.778)
			(end 1.651 1.778)
			(stroke
				(width 0.1524)
				(type default)
			)
			(layer "F.SilkS")
		)
		(fp_line
			(start -1.651 -1.778)
			(end -1.651 1.778)
			(stroke
				(width 0.1524)
				(type default)
			)
			(layer "F.SilkS")
		)
		(fp_poly
			(pts
				(xy -1.778 1.8796) (xy -1.778 -1.8796) (xy 1.778 -1.8796) (xy 1.778 1.8796)
			)
			(stroke
				(width 0)
				(type default)
			)
			(fill no)
			(layer "F.CrtYd")
		)
		(fp_poly
			(pts
				(xy -1.778 1.8796) (xy -1.778 -1.8796) (xy 1.778 -1.8796) (xy 1.778 1.8796)
			)
			(stroke
				(width 0)
				(type default)
			)
			(fill no)
			(layer "F.Fab")
		)
		(pad "D" smd custom
			(at 0 -0.9525 180)
			(size 0.1905 0.1905)
			(layers "F.Cu" "F.Mask" "F.Paste")
			(net "FLT_HDD15_N")
			(options
				(clearance outline)
				(anchor circle)
			)
			(primitives
				(gr_poly
					(pts
						(arc
							(start -0.1778 0.5715)
							(mid -0.321484 0.511984)
							(end -0.381 0.3683)
						)
						(arc
							(start -0.381 -0.3683)
							(mid -0.321484 -0.511984)
							(end -0.1778 -0.5715)
						)
						(arc
							(start 0.1778 -0.5715)
							(mid 0.321484 -0.511984)
							(end 0.381 -0.3683)
						)
						(arc
							(start 0.381 0.3683)
							(mid 0.321484 0.511984)
							(end 0.1778 0.5715)
						)
					)
					(width 0)
					(fill yes)
				)
			)
		)
		(pad "G" smd custom
			(at -0.98425 0.9525 180)
			(size 0.1905 0.1905)
			(layers "F.Cu" "F.Mask" "F.Paste")
			(net "DRIVE_B_15_FLT_LED")
			(options
				(clearance outline)
				(anchor circle)
			)
			(primitives
				(gr_poly
					(pts
						(arc
							(start -0.1778 0.5715)
							(mid -0.321484 0.511984)
							(end -0.381 0.3683)
						)
						(arc
							(start -0.381 -0.3683)
							(mid -0.321484 -0.511984)
							(end -0.1778 -0.5715)
						)
						(arc
							(start 0.1778 -0.5715)
							(mid 0.321484 -0.511984)
							(end 0.381 -0.3683)
						)
						(arc
							(start 0.381 0.3683)
							(mid 0.321484 0.511984)
							(end 0.1778 0.5715)
						)
					)
					(width 0)
					(fill yes)
				)
			)
		)
		(pad "S" smd custom
			(at 0.98425 0.9525 180)
			(size 0.1905 0.1905)
			(layers "F.Cu" "F.Mask" "F.Paste")
			(net "GND")
			(options
				(clearance outline)
				(anchor circle)
			)
			(primitives
				(gr_poly
					(pts
						(arc
							(start -0.1778 0.5715)
							(mid -0.321484 0.511984)
							(end -0.381 0.3683)
						)
						(arc
							(start -0.381 -0.3683)
							(mid -0.321484 -0.511984)
							(end -0.1778 -0.5715)
						)
						(arc
							(start 0.1778 -0.5715)
							(mid 0.321484 -0.511984)
							(end 0.381 -0.3683)
						)
						(arc
							(start 0.381 0.3683)
							(mid 0.321484 0.511984)
							(end 0.1778 0.5715)
						)
					)
					(width 0)
					(fill yes)
				)
			)
		)
	)
	(footprint ""
		(layer "F.Cu")
		(at 215.9 -209.296 90)
		(property "Reference" "U6"
			(at 0 0 90)
			(layer "F.SilkS")
			(hide yes)
			(effects
				(font
					(size 1.27 1.27)
				)
			)
		)
		(property "Value" "TCA9555PWR-GP"
			(at 0 -6.9342 90)
			(unlocked yes)
			(layer "F.Fab")
			(hide yes)
			(effects
				(font
					(size 1.016 1.016)
					(thickness 0.1524)
				)
			)
		)
		(property "Device Type" "TSOIC24H48"
			(at 0 -8.5852 90)
			(unlocked yes)
			(layer "F.Fab")
			(hide yes)
			(effects
				(font
					(size 1.016 1.016)
					(thickness 0.1524)
				)
			)
		)
		(duplicate_pad_numbers_are_jumpers no)
		(fp_line
			(start 3.81 -1.397)
			(end 3.81 1.397)
			(stroke
				(width 0.1524)
				(type default)
			)
			(layer "F.SilkS")
		)
		(fp_line
			(start -4.2291 -1.397)
			(end 3.81 -1.397)
			(stroke
				(width 0.1524)
				(type default)
			)
			(layer "F.SilkS")
		)
		(fp_line
			(start -4.2291 -0.8001)
			(end -3.429 0)
			(stroke
				(width 0.1524)
				(type default)
			)
			(layer "F.SilkS")
		)
		(fp_line
			(start -3.429 0)
			(end -4.2291 0.8001)
			(stroke
				(width 0.1524)
				(type default)
			)
			(layer "F.SilkS")
		)
		(fp_line
			(start 3.81 1.397)
			(end -4.2291 1.397)
			(stroke
				(width 0.1524)
				(type default)
			)
			(layer "F.SilkS")
		)
		(fp_line
			(start -4.22656 3.81)
			(end -4.2291 1.397)
			(stroke
				(width 0.508)
				(type default)
			)
			(layer "F.SilkS")
		)
		(fp_line
			(start -4.2291 3.937)
			(end -4.2291 -1.397)
			(stroke
				(width 0.1524)
				(type default)
			)
			(layer "F.SilkS")
		)
		(fp_poly
			(pts
				(xy -3.90652 -1.8542) (xy 3.90652 -1.8542) (xy 3.90652 1.8542) (xy -3.90652 1.8542)
			)
			(stroke
				(width 0)
				(type default)
			)
			(fill yes)
			(layer "F.SilkS")
		)
		(fp_poly
			(pts
				(xy -4.2164 3.81) (xy 4.2164 3.81) (xy 4.22656 -3.81) (xy -4.2164 -3.81)
			)
			(stroke
				(width 0)
				(type default)
			)
			(fill no)
			(layer "F.CrtYd")
		)
		(fp_poly
			(pts
				(xy -4.22656 -3.81) (xy 4.22656 -3.81) (xy 4.22656 3.81) (xy -4.22656 3.81)
			)
			(stroke
				(width 0)
				(type default)
			)
			(fill no)
			(layer "F.Fab")
		)
		(pad "1" smd rect
			(at -3.57632 2.8194 90)
			(size 0.3556 1.524)
			(layers "F.Cu" "F.Mask" "F.Paste")
			(net "IO_EXP5_INT_N")
		)
		(pad "2" smd rect
			(at -2.92608 2.8194 90)
			(size 0.3556 1.524)
			(layers "F.Cu" "F.Mask" "F.Paste")
			(net "IO_EXP5_A1")
		)
		(pad "3" smd rect
			(at -2.27584 2.8194 90)
			(size 0.3556 1.524)
			(layers "F.Cu" "F.Mask" "F.Paste")
			(net "IO_EXP5_A2")
		)
		(pad "4" smd rect
			(at -1.6256 2.8194 90)
			(size 0.3556 1.524)
			(layers "F.Cu" "F.Mask" "F.Paste")
			(net "DRIVE_B_16_INS")
		)
		(pad "5" smd rect
			(at -0.97536 2.8194 90)
			(size 0.3556 1.524)
			(layers "F.Cu" "F.Mask" "F.Paste")
			(net "DRIVE_B_17_INS")
		)
		(pad "6" smd rect
			(at -0.32512 2.8194 90)
			(size 0.3556 1.524)
			(layers "F.Cu" "F.Mask" "F.Paste")
			(net "DRIVE_B_18_INS")
		)
		(pad "7" smd rect
			(at 0.32512 2.8194 90)
			(size 0.3556 1.524)
			(layers "F.Cu" "F.Mask" "F.Paste")
			(net "DRIVE_B_19_INS")
		)
		(pad "8" smd rect
			(at 0.97536 2.8194 90)
			(size 0.3556 1.524)
			(layers "F.Cu" "F.Mask" "F.Paste")
			(net "DRIVE_B_20_INS")
		)
		(pad "9" smd rect
			(at 1.6256 2.8194 90)
			(size 0.3556 1.524)
			(layers "F.Cu" "F.Mask" "F.Paste")
			(net "DRIVE_B_21_INS")
		)
		(pad "10" smd rect
			(at 2.27584 2.8194 90)
			(size 0.3556 1.524)
			(layers "F.Cu" "F.Mask" "F.Paste")
			(net "DRIVE_B_22_INS")
		)
		(pad "11" smd rect
			(at 2.92608 2.8194 90)
			(size 0.3556 1.524)
			(layers "F.Cu" "F.Mask" "F.Paste")
			(net "DRIVE_B_23_INS")
		)
		(pad "12" smd rect
			(at 3.57632 2.8194 90)
			(size 0.3556 1.524)
			(layers "F.Cu" "F.Mask" "F.Paste")
			(net "GND")
		)
		(pad "13" smd rect
			(at 3.57632 -2.8194 90)
			(size 0.3556 1.524)
			(layers "F.Cu" "F.Mask" "F.Paste")
			(net "DRIVE_B_24_INS")
		)
		(pad "14" smd rect
			(at 2.92608 -2.8194 90)
			(size 0.3556 1.524)
			(layers "F.Cu" "F.Mask" "F.Paste")
			(net "DRIVE_B_25_INS")
		)
		(pad "15" smd rect
			(at 2.27584 -2.8194 90)
			(size 0.3556 1.524)
			(layers "F.Cu" "F.Mask" "F.Paste")
			(net "DRIVE_B_26_INS")
		)
		(pad "16" smd rect
			(at 1.6256 -2.8194 90)
			(size 0.3556 1.524)
			(layers "F.Cu" "F.Mask" "F.Paste")
			(net "DRIVE_B_27_INS")
		)
		(pad "17" smd rect
			(at 0.97536 -2.8194 90)
			(size 0.3556 1.524)
			(layers "F.Cu" "F.Mask" "F.Paste")
			(net "DRIVE_B_28_INS")
		)
		(pad "18" smd rect
			(at 0.32512 -2.8194 90)
			(size 0.3556 1.524)
			(layers "F.Cu" "F.Mask" "F.Paste")
			(net "DRIVE_B_29_INS")
		)
		(pad "19" smd rect
			(at -0.32512 -2.8194 90)
			(size 0.3556 1.524)
			(layers "F.Cu" "F.Mask" "F.Paste")
			(net "DRIVE_B_30_INS")
		)
		(pad "20" smd rect
			(at -0.97536 -2.8194 90)
			(size 0.3556 1.524)
			(layers "F.Cu" "F.Mask" "F.Paste")
			(net "DRIVE_B_31_INS")
		)
		(pad "21" smd rect
			(at -1.6256 -2.8194 90)
			(size 0.3556 1.524)
			(layers "F.Cu" "F.Mask" "F.Paste")
			(net "IO_EXP5_A0")
		)
		(pad "22" smd rect
			(at -2.27584 -2.8194 90)
			(size 0.3556 1.524)
			(layers "F.Cu" "F.Mask" "F.Paste")
			(net "IO_EXP5_SCL")
		)
		(pad "23" smd rect
			(at -2.92608 -2.8194 90)
			(size 0.3556 1.524)
			(layers "F.Cu" "F.Mask" "F.Paste")
			(net "IO_EXP5_SDA")
		)
		(pad "24" smd rect
			(at -3.57632 -2.8194 90)
			(size 0.3556 1.524)
			(layers "F.Cu" "F.Mask" "F.Paste")
			(net "P3V3_STBY_B")
		)
	)
	(footprint ""
		(layer "F.Cu")
		(at 427.9646 -40.64 -90)
		(property "Reference" "R830"
			(at 0 0 270)
			(layer "F.SilkS")
			(hide yes)
			(effects
				(font
					(size 1.27 1.27)
				)
			)
		)
		(property "Value" "2R6F-GP"
			(at -0.0508 -4.8514 270)
			(unlocked yes)
			(layer "F.Fab")
			(hide yes)
			(effects
				(font
					(size 1.016 1.016)
					(thickness 0.1524)
				)
			)
		)
		(property "Device Type" "R1206H26"
			(at 0 -6.3754 270)
			(unlocked yes)
			(layer "F.Fab")
			(hide yes)
			(effects
				(font
					(size 1.016 1.016)
					(thickness 0.1524)
				)
			)
		)
		(duplicate_pad_numbers_are_jumpers no)
		(fp_line
			(start -1.016 2.2352)
			(end -1.016 -2.2352)
			(stroke
				(width 0.1524)
				(type default)
			)
			(layer "F.SilkS")
		)
		(fp_line
			(start 1.016 2.2352)
			(end -1.016 2.2352)
			(stroke
				(width 0.1524)
				(type default)
			)
			(layer "F.SilkS")
		)
		(fp_line
			(start -1.016 -2.2352)
			(end 1.016 -2.2352)
			(stroke
				(width 0.1524)
				(type default)
			)
			(layer "F.SilkS")
		)
		(fp_line
			(start 1.016 -2.2352)
			(end 1.016 2.2352)
			(stroke
				(width 0.1524)
				(type default)
			)
			(layer "F.SilkS")
		)
		(fp_rect
			(start -1.0922 2.3114)
			(end 1.0922 -2.3114)
			(stroke
				(width 0)
				(type default)
			)
			(fill no)
			(layer "F.CrtYd")
		)
		(fp_poly
			(pts
				(xy -1.0922 -2.3114) (xy 1.0922 -2.3114) (xy 1.0922 2.3114) (xy -1.0922 2.3114)
			)
			(stroke
				(width 0)
				(type default)
			)
			(fill no)
			(layer "F.Fab")
		)
		(pad "1" smd rect
			(at 0 -1.397 270)
			(size 1.651 1.27)
			(layers "F.Cu" "F.Mask" "F.Paste")
			(net "P12V_HDD33")
		)
		(pad "2" smd rect
			(at 0 1.397 270)
			(size 1.651 1.27)
			(layers "F.Cu" "F.Mask" "F.Paste")
			(net "12V_PRE_33")
		)
	)
	(footprint ""
		(layer "F.Cu")
		(at 17.800066 -65.39992)
		(property "Reference" "LED13"
			(at 0 0 0)
			(layer "F.SilkS")
			(hide yes)
			(effects
				(font
					(size 1.27 1.27)
				)
			)
		)
		(property "Value" "LED-BY-19-GP"
			(at -2.132076 1.414018 0)
			(unlocked yes)
			(layer "F.Fab")
			(hide yes)
			(effects
				(font
					(size 1.016 1.016)
					(thickness 0.1524)
				)
			)
		)
		(property "Device Type" "LED-1615-4PH26"
			(at -2.132076 -0.109982 0)
			(unlocked yes)
			(layer "F.Fab")
			(hide yes)
			(effects
				(font
					(size 1.016 1.016)
					(thickness 0.1524)
				)
			)
		)
		(duplicate_pad_numbers_are_jumpers no)
		(fp_line
			(start -1.2954 0.254)
			(end -1.2954 1.6002)
			(stroke
				(width 0.508)
				(type default)
			)
			(layer "F.SilkS")
		)
		(fp_line
			(start -1.2954 1.6002)
			(end 1.2954 1.6002)
			(stroke
				(width 0.508)
				(type default)
			)
			(layer "F.SilkS")
		)
		(fp_line
			(start -1.1176 -1.4224)
			(end 1.1176 -1.4224)
			(stroke
				(width 0.1524)
				(type default)
			)
			(layer "F.SilkS")
		)
		(fp_line
			(start -1.1176 1.4224)
			(end -1.1176 -1.4224)
			(stroke
				(width 0.1524)
				(type default)
			)
			(layer "F.SilkS")
		)
		(fp_line
			(start 1.1176 -1.4224)
			(end 1.1176 1.4224)
			(stroke
				(width 0.1524)
				(type default)
			)
			(layer "F.SilkS")
		)
		(fp_line
			(start 1.1176 1.4224)
			(end -1.1176 1.4224)
			(stroke
				(width 0.1524)
				(type default)
			)
			(layer "F.SilkS")
		)
		(fp_line
			(start 1.2954 1.6002)
			(end 1.2954 0.254)
			(stroke
				(width 0.508)
				(type default)
			)
			(layer "F.SilkS")
		)
		(fp_rect
			(start -0.7493 0.8001)
			(end 0.7493 -0.8001)
			(stroke
				(width 0)
				(type default)
			)
			(fill no)
			(layer "F.CrtYd")
		)
		(fp_poly
			(pts
				(xy -1.3716 1.6764) (xy -1.3716 -1.6764) (xy 1.3716 -1.6764) (xy 1.3716 0.0635) (xy 0.7493 0.0635)
				(xy 0.7493 -0.8001) (xy -0.7493 -0.8001) (xy -0.7493 0.8001) (xy 0.7493 0.8001) (xy 0.7493 0.0762)
				(xy 1.3716 0.0762) (xy 1.3716 1.6764)
			)
			(stroke
				(width 0)
				(type default)
			)
			(fill no)
			(layer "F.CrtYd")
		)
		(fp_rect
			(start -1.3716 1.6764)
			(end 1.3716 -1.6764)
			(stroke
				(width 0)
				(type default)
			)
			(fill no)
			(layer "F.Fab")
		)
		(pad "1" smd rect
			(at 0.50038 -0.73025)
			(size 0.7112 0.8636)
			(layers "F.Cu" "F.Mask" "F.Paste")
			(net "DRV_ACT_12")
		)
		(pad "2" smd rect
			(at -0.50038 -0.73025)
			(size 0.7112 0.8636)
			(layers "F.Cu" "F.Mask" "F.Paste")
			(net "FLT_HDD12")
		)
		(pad "3" smd rect
			(at 0.50038 0.73025)
			(size 0.7112 0.8636)
			(layers "F.Cu" "F.Mask" "F.Paste")
			(net "DRV_ACT_12_N")
		)
		(pad "4" smd rect
			(at -0.50038 0.73025)
			(size 0.7112 0.8636)
			(layers "F.Cu" "F.Mask" "F.Paste")
			(net "FLT_HDD12_N")
		)
	)
	(footprint ""
		(layer "F.Cu")
		(at 445.17056 -360.920284 90)
		(property "Reference" "C535"
			(at 0 0 90)
			(layer "F.SilkS")
			(hide yes)
			(effects
				(font
					(size 1.27 1.27)
				)
			)
		)
		(property "Value" "SC22U25V0MX-2-GP"
			(at -0.00254 -4.78536 90)
			(unlocked yes)
			(layer "F.Fab")
			(hide yes)
			(effects
				(font
					(size 1.016 1.016)
					(thickness 0.1524)
				)
			)
		)
		(property "Device Type" "C1210H111"
			(at -0.00254 -6.38048 90)
			(unlocked yes)
			(layer "F.Fab")
			(hide yes)
			(effects
				(font
					(size 1.016 1.016)
					(thickness 0.1524)
				)
			)
		)
		(duplicate_pad_numbers_are_jumpers no)
		(fp_line
			(start 1.5748 -2.3368)
			(end -1.5748 -2.3368)
			(stroke
				(width 0.1524)
				(type default)
			)
			(layer "F.SilkS")
		)
		(fp_line
			(start -1.5748 -2.3368)
			(end -1.5748 -0.762)
			(stroke
				(width 0.1524)
				(type default)
			)
			(layer "F.SilkS")
		)
		(fp_line
			(start 1.5748 -0.762)
			(end 1.5748 -2.3368)
			(stroke
				(width 0.1524)
				(type default)
			)
			(layer "F.SilkS")
		)
		(fp_line
			(start -1.5748 0.762)
			(end -1.5748 2.3368)
			(stroke
				(width 0.1524)
				(type default)
			)
			(layer "F.SilkS")
		)
		(fp_line
			(start 1.5748 2.3368)
			(end 1.5748 0.762)
			(stroke
				(width 0.1524)
				(type default)
			)
			(layer "F.SilkS")
		)
		(fp_line
			(start -1.5748 2.3368)
			(end 1.5748 2.3368)
			(stroke
				(width 0.1524)
				(type default)
			)
			(layer "F.SilkS")
		)
		(fp_rect
			(start -1.651 2.413)
			(end 1.651 -2.413)
			(stroke
				(width 0)
				(type default)
			)
			(fill no)
			(layer "F.CrtYd")
		)
		(fp_poly
			(pts
				(xy 1.651 2.413) (xy 1.651 -2.413) (xy -1.651 -2.413) (xy -1.651 2.413)
			)
			(stroke
				(width 0)
				(type default)
			)
			(fill no)
			(layer "F.Fab")
		)
		(pad "1" smd rect
			(at 0 -1.4732 90)
			(size 2.794 1.397)
			(layers "F.Cu" "F.Mask" "F.Paste")
			(net "P12V_FAN3")
		)
		(pad "2" smd rect
			(at 0 1.4732 90)
			(size 2.794 1.397)
			(layers "F.Cu" "F.Mask" "F.Paste")
			(net "GND")
		)
	)
	(footprint ""
		(layer "F.Cu")
		(at 476.2246 -5.969)
		(property "Reference" "R892"
			(at 0 0 0)
			(layer "F.SilkS")
			(hide yes)
			(effects
				(font
					(size 1.27 1.27)
				)
			)
		)
		(property "Value" "0R2J-2-GP"
			(at 0.064008 -3.993896 0)
			(unlocked yes)
			(layer "F.Fab")
			(hide yes)
			(effects
				(font
					(size 1.016 1.016)
					(thickness 0.1524)
				)
			)
		)
		(property "Device Type" "R402H16"
			(at 0.064008 -5.517896 0)
			(unlocked yes)
			(layer "F.Fab")
			(hide yes)
			(effects
				(font
					(size 1.016 1.016)
					(thickness 0.1524)
				)
			)
		)
		(duplicate_pad_numbers_are_jumpers no)
		(fp_line
			(start -0.508 -0.9398)
			(end -0.508 0.9398)
			(stroke
				(width 0.1524)
				(type default)
			)
			(layer "F.SilkS")
		)
		(fp_line
			(start 0.508 -0.9398)
			(end -0.508 -0.9398)
			(stroke
				(width 0.1524)
				(type default)
			)
			(layer "F.SilkS")
		)
		(fp_rect
			(start -0.508 0.9398)
			(end 0.508 -0.9398)
			(stroke
				(width 0)
				(type default)
			)
			(fill no)
			(layer "F.CrtYd")
		)
		(fp_rect
			(start -0.508 0.9398)
			(end 0.508 -0.9398)
			(stroke
				(width 0)
				(type default)
			)
			(fill no)
			(layer "F.Fab")
		)
		(pad "1" smd custom
			(at 0 -0.4445)
			(size 0.1397 0.1397)
			(layers "F.Cu" "F.Mask" "F.Paste")
			(net "SW_HDD_G35")
			(options
				(clearance outline)
				(anchor circle)
			)
			(primitives
				(gr_poly
					(pts
						(arc
							(start -0.1778 -0.2794)
							(mid -0.249642 -0.249642)
							(end -0.2794 -0.1778)
						)
						(arc
							(start -0.2794 0.1778)
							(mid -0.249642 0.249642)
							(end -0.1778 0.2794)
						)
						(arc
							(start 0.1778 0.2794)
							(mid 0.249642 0.249642)
							(end 0.2794 0.1778)
						)
						(arc
							(start 0.2794 -0.1778)
							(mid 0.249642 -0.249642)
							(end 0.1778 -0.2794)
						)
					)
					(width 0)
					(fill yes)
				)
			)
		)
		(pad "2" smd custom
			(at 0 0.4445)
			(size 0.1397 0.1397)
			(layers "F.Cu" "F.Mask" "F.Paste")
			(net "SW_HDD_R35")
			(options
				(clearance outline)
				(anchor circle)
			)
			(primitives
				(gr_poly
					(pts
						(arc
							(start -0.1778 -0.2794)
							(mid -0.249642 -0.249642)
							(end -0.2794 -0.1778)
						)
						(arc
							(start -0.2794 0.1778)
							(mid -0.249642 0.249642)
							(end -0.1778 0.2794)
						)
						(arc
							(start 0.1778 0.2794)
							(mid 0.249642 0.249642)
							(end 0.2794 0.1778)
						)
						(arc
							(start 0.2794 -0.1778)
							(mid 0.249642 -0.249642)
							(end 0.1778 -0.2794)
						)
					)
					(width 0)
					(fill yes)
				)
			)
		)
	)
	(footprint ""
		(layer "F.Cu")
		(at 460.314802 -229.49535 -90)
		(property "Reference" "C659"
			(at 0 0 270)
			(layer "F.SilkS")
			(hide yes)
			(effects
				(font
					(size 1.27 1.27)
				)
			)
		)
		(property "Value" "SC1U16V3KX-5GP"
			(at 0 -2.8194 270)
			(unlocked yes)
			(layer "F.Fab")
			(hide yes)
			(effects
				(font
					(size 1.016 1.016)
					(thickness 0.1524)
				)
			)
		)
		(property "Device Type" "C603H36"
			(at 0 -4.3434 270)
			(unlocked yes)
			(layer "F.Fab")
			(hide yes)
			(effects
				(font
					(size 1.016 1.016)
					(thickness 0.1524)
				)
			)
		)
		(duplicate_pad_numbers_are_jumpers no)
		(fp_line
			(start 0.508 0)
			(end -0.508 0)
			(stroke
				(width 0.2032)
				(type default)
			)
			(layer "F.SilkS")
		)
		(fp_rect
			(start -0.5842 1.3335)
			(end 0.5842 -1.3335)
			(stroke
				(width 0)
				(type default)
			)
			(fill no)
			(layer "F.CrtYd")
		)
		(fp_rect
			(start -0.5842 1.3335)
			(end 0.5842 -1.3335)
			(stroke
				(width 0)
				(type default)
			)
			(fill no)
			(layer "F.Fab")
		)
		(pad "1" smd custom
			(at 0 -0.762 270)
			(size 0.2159 0.2159)
			(layers "F.Cu" "F.Mask" "F.Paste")
			(net "P5V_B_3_EN_R")
			(options
				(clearance outline)
				(anchor circle)
			)
			(primitives
				(gr_poly
					(pts
						(arc
							(start -0.3302 -0.4318)
							(mid -0.402042 -0.402042)
							(end -0.4318 -0.3302)
						)
						(arc
							(start -0.4318 0.3302)
							(mid -0.402042 0.402042)
							(end -0.3302 0.4318)
						)
						(arc
							(start 0.3302 0.4318)
							(mid 0.402042 0.402042)
							(end 0.4318 0.3302)
						)
						(arc
							(start 0.4318 -0.3302)
							(mid 0.402042 -0.402042)
							(end 0.3302 -0.4318)
						)
					)
					(width 0)
					(fill yes)
				)
			)
		)
		(pad "2" smd custom
			(at 0 0.762 270)
			(size 0.2159 0.2159)
			(layers "F.Cu" "F.Mask" "F.Paste")
			(net "GND")
			(options
				(clearance outline)
				(anchor circle)
			)
			(primitives
				(gr_poly
					(pts
						(arc
							(start -0.3302 -0.4318)
							(mid -0.402042 -0.402042)
							(end -0.4318 -0.3302)
						)
						(arc
							(start -0.4318 0.3302)
							(mid -0.402042 0.402042)
							(end -0.3302 0.4318)
						)
						(arc
							(start 0.3302 0.4318)
							(mid 0.402042 0.402042)
							(end 0.4318 0.3302)
						)
						(arc
							(start 0.4318 -0.3302)
							(mid 0.402042 -0.402042)
							(end 0.3302 -0.4318)
						)
					)
					(width 0)
					(fill yes)
				)
			)
		)
	)
	(footprint ""
		(layer "F.Cu")
		(at 245.4402 -303.149 90)
		(property "Reference" "C616"
			(at 0 0 90)
			(layer "F.SilkS")
			(hide yes)
			(effects
				(font
					(size 1.27 1.27)
				)
			)
		)
		(property "Value" "SCD1U16V2KX-3GP"
			(at 1.1811 -2.7051 90)
			(unlocked yes)
			(layer "F.Fab")
			(hide yes)
			(effects
				(font
					(size 1.016 1.016)
					(thickness 0.1524)
				)
			)
		)
		(property "Device Type" "C402H22"
			(at 1.1811 -4.2291 90)
			(unlocked yes)
			(layer "F.Fab")
			(hide yes)
			(effects
				(font
					(size 1.016 1.016)
					(thickness 0.1524)
				)
			)
		)
		(duplicate_pad_numbers_are_jumpers no)
		(fp_rect
			(start -0.4318 0.9525)
			(end 0.4318 -0.9525)
			(stroke
				(width 0)
				(type default)
			)
			(fill no)
			(layer "F.CrtYd")
		)
		(fp_rect
			(start -0.4318 0.9525)
			(end 0.4318 -0.9525)
			(stroke
				(width 0)
				(type default)
			)
			(fill no)
			(layer "F.Fab")
		)
		(pad "1" smd custom
			(at 0 -0.4445 90)
			(size 0.1524 0.1524)
			(layers "F.Cu" "F.Mask" "F.Paste")
			(net "P3V3_STBY_A")
			(options
				(clearance outline)
				(anchor circle)
			)
			(primitives
				(gr_poly
					(pts
						(arc
							(start 0.3048 -0.2032)
							(mid 0.275042 -0.275042)
							(end 0.2032 -0.3048)
						)
						(arc
							(start -0.2032 -0.3048)
							(mid -0.275042 -0.275042)
							(end -0.3048 -0.2032)
						)
						(arc
							(start -0.3048 0.2032)
							(mid -0.275042 0.275042)
							(end -0.2032 0.3048)
						)
						(arc
							(start 0.2032 0.3048)
							(mid 0.275042 0.275042)
							(end 0.3048 0.2032)
						)
					)
					(width 0)
					(fill yes)
				)
			)
		)
		(pad "2" smd custom
			(at 0 0.4445 90)
			(size 0.1524 0.1524)
			(layers "F.Cu" "F.Mask" "F.Paste")
			(net "GND")
			(options
				(clearance outline)
				(anchor circle)
			)
			(primitives
				(gr_poly
					(pts
						(arc
							(start 0.3048 -0.2032)
							(mid 0.275042 -0.275042)
							(end 0.2032 -0.3048)
						)
						(arc
							(start -0.2032 -0.3048)
							(mid -0.275042 -0.275042)
							(end -0.3048 -0.2032)
						)
						(arc
							(start -0.3048 0.2032)
							(mid -0.275042 0.275042)
							(end -0.2032 0.3048)
						)
						(arc
							(start 0.2032 0.3048)
							(mid 0.275042 0.275042)
							(end 0.3048 0.2032)
						)
					)
					(width 0)
					(fill yes)
				)
			)
		)
	)
	(footprint ""
		(layer "F.Cu")
		(at 150.495 -160.401 180)
		(property "Reference" "C243"
			(at 0 0 180)
			(layer "F.SilkS")
			(hide yes)
			(effects
				(font
					(size 1.27 1.27)
				)
			)
		)
		(property "Value" "SC1U25V3KX-GP"
			(at 0 -2.8194 180)
			(unlocked yes)
			(layer "F.Fab")
			(hide yes)
			(effects
				(font
					(size 1.016 1.016)
					(thickness 0.1524)
				)
			)
		)
		(property "Device Type" "C603H36"
			(at 0 -4.3434 180)
			(unlocked yes)
			(layer "F.Fab")
			(hide yes)
			(effects
				(font
					(size 1.016 1.016)
					(thickness 0.1524)
				)
			)
		)
		(duplicate_pad_numbers_are_jumpers no)
		(fp_line
			(start 0.508 0)
			(end -0.508 0)
			(stroke
				(width 0.2032)
				(type default)
			)
			(layer "F.SilkS")
		)
		(fp_rect
			(start -0.5842 1.3335)
			(end 0.5842 -1.3335)
			(stroke
				(width 0)
				(type default)
			)
			(fill no)
			(layer "F.CrtYd")
		)
		(fp_rect
			(start -0.5842 1.3335)
			(end 0.5842 -1.3335)
			(stroke
				(width 0)
				(type default)
			)
			(fill no)
			(layer "F.Fab")
		)
		(pad "1" smd custom
			(at 0 -0.762 180)
			(size 0.2159 0.2159)
			(layers "F.Cu" "F.Mask" "F.Paste")
			(net "P12V_HDD16")
			(options
				(clearance outline)
				(anchor circle)
			)
			(primitives
				(gr_poly
					(pts
						(arc
							(start -0.3302 -0.4318)
							(mid -0.402042 -0.402042)
							(end -0.4318 -0.3302)
						)
						(arc
							(start -0.4318 0.3302)
							(mid -0.402042 0.402042)
							(end -0.3302 0.4318)
						)
						(arc
							(start 0.3302 0.4318)
							(mid 0.402042 0.402042)
							(end 0.4318 0.3302)
						)
						(arc
							(start 0.4318 -0.3302)
							(mid 0.402042 -0.402042)
							(end 0.3302 -0.4318)
						)
					)
					(width 0)
					(fill yes)
				)
			)
		)
		(pad "2" smd custom
			(at 0 0.762 180)
			(size 0.2159 0.2159)
			(layers "F.Cu" "F.Mask" "F.Paste")
			(net "GND")
			(options
				(clearance outline)
				(anchor circle)
			)
			(primitives
				(gr_poly
					(pts
						(arc
							(start -0.3302 -0.4318)
							(mid -0.402042 -0.402042)
							(end -0.4318 -0.3302)
						)
						(arc
							(start -0.4318 0.3302)
							(mid -0.402042 0.402042)
							(end -0.3302 0.4318)
						)
						(arc
							(start 0.3302 0.4318)
							(mid 0.402042 0.402042)
							(end 0.4318 0.3302)
						)
						(arc
							(start 0.4318 -0.3302)
							(mid 0.402042 -0.402042)
							(end 0.3302 -0.4318)
						)
					)
					(width 0)
					(fill yes)
				)
			)
		)
	)
	(footprint ""
		(layer "F.Cu")
		(at 54.0766 -131.2164 -90)
		(property "Reference" "R379"
			(at 0 0 270)
			(layer "F.SilkS")
			(hide yes)
			(effects
				(font
					(size 1.27 1.27)
				)
			)
		)
		(property "Value" "0R2J-2-GP"
			(at 0.064008 -3.993896 270)
			(unlocked yes)
			(layer "F.Fab")
			(hide yes)
			(effects
				(font
					(size 1.016 1.016)
					(thickness 0.1524)
				)
			)
		)
		(property "Device Type" "R402H16"
			(at 0.064008 -5.517896 270)
			(unlocked yes)
			(layer "F.Fab")
			(hide yes)
			(effects
				(font
					(size 1.016 1.016)
					(thickness 0.1524)
				)
			)
		)
		(duplicate_pad_numbers_are_jumpers no)
		(fp_line
			(start -0.508 -0.9398)
			(end -0.508 0.9398)
			(stroke
				(width 0.1524)
				(type default)
			)
			(layer "F.SilkS")
		)
		(fp_line
			(start 0.508 -0.9398)
			(end -0.508 -0.9398)
			(stroke
				(width 0.1524)
				(type default)
			)
			(layer "F.SilkS")
		)
		(fp_rect
			(start -0.508 0.9398)
			(end 0.508 -0.9398)
			(stroke
				(width 0)
				(type default)
			)
			(fill no)
			(layer "F.CrtYd")
		)
		(fp_rect
			(start -0.508 0.9398)
			(end 0.508 -0.9398)
			(stroke
				(width 0)
				(type default)
			)
			(fill no)
			(layer "F.Fab")
		)
		(pad "1" smd custom
			(at 0 -0.4445 270)
			(size 0.1397 0.1397)
			(layers "F.Cu" "F.Mask" "F.Paste")
			(net "DRIVE_B_13_PWR")
			(options
				(clearance outline)
				(anchor circle)
			)
			(primitives
				(gr_poly
					(pts
						(arc
							(start -0.1778 -0.2794)
							(mid -0.249642 -0.249642)
							(end -0.2794 -0.1778)
						)
						(arc
							(start -0.2794 0.1778)
							(mid -0.249642 0.249642)
							(end -0.1778 0.2794)
						)
						(arc
							(start 0.1778 0.2794)
							(mid 0.249642 0.249642)
							(end 0.2794 0.1778)
						)
						(arc
							(start 0.2794 -0.1778)
							(mid 0.249642 -0.249642)
							(end 0.1778 -0.2794)
						)
					)
					(width 0)
					(fill yes)
				)
			)
		)
		(pad "2" smd custom
			(at 0 0.4445 270)
			(size 0.1397 0.1397)
			(layers "F.Cu" "F.Mask" "F.Paste")
			(net "SW_PWR_R_HDD13")
			(options
				(clearance outline)
				(anchor circle)
			)
			(primitives
				(gr_poly
					(pts
						(arc
							(start -0.1778 -0.2794)
							(mid -0.249642 -0.249642)
							(end -0.2794 -0.1778)
						)
						(arc
							(start -0.2794 0.1778)
							(mid -0.249642 0.249642)
							(end -0.1778 0.2794)
						)
						(arc
							(start 0.1778 0.2794)
							(mid 0.249642 0.249642)
							(end 0.2794 0.1778)
						)
						(arc
							(start 0.2794 -0.1778)
							(mid 0.249642 -0.249642)
							(end 0.1778 -0.2794)
						)
					)
					(width 0)
					(fill yes)
				)
			)
		)
	)
	(footprint ""
		(layer "F.Cu")
		(at 86.106 -249.555 90)
		(property "Reference" "R199"
			(at 0 0 90)
			(layer "F.SilkS")
			(hide yes)
			(effects
				(font
					(size 1.27 1.27)
				)
			)
		)
		(property "Value" "4K7R2F-GP"
			(at 0.064008 -3.993896 90)
			(unlocked yes)
			(layer "F.Fab")
			(hide yes)
			(effects
				(font
					(size 1.016 1.016)
					(thickness 0.1524)
				)
			)
		)
		(property "Device Type" "R402H16"
			(at 0.064008 -5.517896 90)
			(unlocked yes)
			(layer "F.Fab")
			(hide yes)
			(effects
				(font
					(size 1.016 1.016)
					(thickness 0.1524)
				)
			)
		)
		(duplicate_pad_numbers_are_jumpers no)
		(fp_line
			(start 0.508 -0.9398)
			(end -0.508 -0.9398)
			(stroke
				(width 0.1524)
				(type default)
			)
			(layer "F.SilkS")
		)
		(fp_line
			(start -0.508 -0.9398)
			(end -0.508 0.9398)
			(stroke
				(width 0.1524)
				(type default)
			)
			(layer "F.SilkS")
		)
		(fp_rect
			(start -0.508 0.9398)
			(end 0.508 -0.9398)
			(stroke
				(width 0)
				(type default)
			)
			(fill no)
			(layer "F.CrtYd")
		)
		(fp_rect
			(start -0.508 0.9398)
			(end 0.508 -0.9398)
			(stroke
				(width 0)
				(type default)
			)
			(fill no)
			(layer "F.Fab")
		)
		(pad "1" smd custom
			(at 0 -0.4445 90)
			(size 0.1397 0.1397)
			(layers "F.Cu" "F.Mask" "F.Paste")
			(net "SW_PWR_R_HDD2")
			(options
				(clearance outline)
				(anchor circle)
			)
			(primitives
				(gr_poly
					(pts
						(arc
							(start -0.1778 -0.2794)
							(mid -0.249642 -0.249642)
							(end -0.2794 -0.1778)
						)
						(arc
							(start -0.2794 0.1778)
							(mid -0.249642 0.249642)
							(end -0.1778 0.2794)
						)
						(arc
							(start 0.1778 0.2794)
							(mid 0.249642 0.249642)
							(end 0.2794 0.1778)
						)
						(arc
							(start 0.2794 -0.1778)
							(mid 0.249642 -0.249642)
							(end 0.1778 -0.2794)
						)
					)
					(width 0)
					(fill yes)
				)
			)
		)
		(pad "2" smd custom
			(at 0 0.4445 90)
			(size 0.1397 0.1397)
			(layers "F.Cu" "F.Mask" "F.Paste")
			(net "GND")
			(options
				(clearance outline)
				(anchor circle)
			)
			(primitives
				(gr_poly
					(pts
						(arc
							(start -0.1778 -0.2794)
							(mid -0.249642 -0.249642)
							(end -0.2794 -0.1778)
						)
						(arc
							(start -0.2794 0.1778)
							(mid -0.249642 0.249642)
							(end -0.1778 0.2794)
						)
						(arc
							(start 0.1778 0.2794)
							(mid 0.249642 0.249642)
							(end 0.2794 0.1778)
						)
						(arc
							(start 0.2794 -0.1778)
							(mid 0.249642 -0.249642)
							(end 0.1778 -0.2794)
						)
					)
					(width 0)
					(fill yes)
				)
			)
		)
	)
	(footprint ""
		(layer "F.Cu")
		(at 301.979076 -340.812882 180)
		(property "Reference" "R95"
			(at 0 0 180)
			(layer "F.SilkS")
			(hide yes)
			(effects
				(font
					(size 1.27 1.27)
				)
			)
		)
		(property "Value" "0R2J-2-GP"
			(at 0.064008 -3.993896 180)
			(unlocked yes)
			(layer "F.Fab")
			(hide yes)
			(effects
				(font
					(size 1.016 1.016)
					(thickness 0.1524)
				)
			)
		)
		(property "Device Type" "R402H16"
			(at 0.064008 -5.517896 180)
			(unlocked yes)
			(layer "F.Fab")
			(hide yes)
			(effects
				(font
					(size 1.016 1.016)
					(thickness 0.1524)
				)
			)
		)
		(duplicate_pad_numbers_are_jumpers no)
		(fp_line
			(start 0.508 -0.9398)
			(end -0.508 -0.9398)
			(stroke
				(width 0.1524)
				(type default)
			)
			(layer "F.SilkS")
		)
		(fp_line
			(start -0.508 -0.9398)
			(end -0.508 0.9398)
			(stroke
				(width 0.1524)
				(type default)
			)
			(layer "F.SilkS")
		)
		(fp_rect
			(start -0.508 0.9398)
			(end 0.508 -0.9398)
			(stroke
				(width 0)
				(type default)
			)
			(fill no)
			(layer "F.CrtYd")
		)
		(fp_rect
			(start -0.508 0.9398)
			(end 0.508 -0.9398)
			(stroke
				(width 0)
				(type default)
			)
			(fill no)
			(layer "F.Fab")
		)
		(pad "1" smd custom
			(at 0 -0.4445 180)
			(size 0.1397 0.1397)
			(layers "F.Cu" "F.Mask" "F.Paste")
			(net "PWM_OUT_C_R")
			(options
				(clearance outline)
				(anchor circle)
			)
			(primitives
				(gr_poly
					(pts
						(arc
							(start -0.1778 -0.2794)
							(mid -0.249642 -0.249642)
							(end -0.2794 -0.1778)
						)
						(arc
							(start -0.2794 0.1778)
							(mid -0.249642 0.249642)
							(end -0.1778 0.2794)
						)
						(arc
							(start 0.1778 0.2794)
							(mid 0.249642 0.249642)
							(end 0.2794 0.1778)
						)
						(arc
							(start 0.2794 -0.1778)
							(mid 0.249642 -0.249642)
							(end 0.1778 -0.2794)
						)
					)
					(width 0)
					(fill yes)
				)
			)
		)
		(pad "2" smd custom
			(at 0 0.4445 180)
			(size 0.1397 0.1397)
			(layers "F.Cu" "F.Mask" "F.Paste")
			(net "PWM_OUT_C")
			(options
				(clearance outline)
				(anchor circle)
			)
			(primitives
				(gr_poly
					(pts
						(arc
							(start -0.1778 -0.2794)
							(mid -0.249642 -0.249642)
							(end -0.2794 -0.1778)
						)
						(arc
							(start -0.2794 0.1778)
							(mid -0.249642 0.249642)
							(end -0.1778 0.2794)
						)
						(arc
							(start 0.1778 0.2794)
							(mid 0.249642 0.249642)
							(end 0.2794 0.1778)
						)
						(arc
							(start 0.2794 -0.1778)
							(mid 0.249642 -0.249642)
							(end 0.1778 -0.2794)
						)
					)
					(width 0)
					(fill yes)
				)
			)
		)
	)
	(footprint ""
		(layer "F.Cu")
		(at 250.782582 -133.291072)
		(property "Reference" "R424"
			(at 0 0 0)
			(layer "F.SilkS")
			(hide yes)
			(effects
				(font
					(size 1.27 1.27)
				)
			)
		)
		(property "Value" "0R2J-2-GP"
			(at 0.064008 -3.993896 0)
			(unlocked yes)
			(layer "F.Fab")
			(hide yes)
			(effects
				(font
					(size 1.016 1.016)
					(thickness 0.1524)
				)
			)
		)
		(property "Device Type" "R402H16"
			(at 0.064008 -5.517896 0)
			(unlocked yes)
			(layer "F.Fab")
			(hide yes)
			(effects
				(font
					(size 1.016 1.016)
					(thickness 0.1524)
				)
			)
		)
		(duplicate_pad_numbers_are_jumpers no)
		(fp_line
			(start -0.508 -0.9398)
			(end -0.508 0.9398)
			(stroke
				(width 0.1524)
				(type default)
			)
			(layer "F.SilkS")
		)
		(fp_line
			(start 0.508 -0.9398)
			(end -0.508 -0.9398)
			(stroke
				(width 0.1524)
				(type default)
			)
			(layer "F.SilkS")
		)
		(fp_rect
			(start -0.508 0.9398)
			(end 0.508 -0.9398)
			(stroke
				(width 0)
				(type default)
			)
			(fill no)
			(layer "F.CrtYd")
		)
		(fp_rect
			(start -0.508 0.9398)
			(end 0.508 -0.9398)
			(stroke
				(width 0)
				(type default)
			)
			(fill no)
			(layer "F.Fab")
		)
		(pad "1" smd custom
			(at 0 -0.4445)
			(size 0.1397 0.1397)
			(layers "F.Cu" "F.Mask" "F.Paste")
			(net "I2C_DPB_B_SDA_BUF")
			(options
				(clearance outline)
				(anchor circle)
			)
			(primitives
				(gr_poly
					(pts
						(arc
							(start -0.1778 -0.2794)
							(mid -0.249642 -0.249642)
							(end -0.2794 -0.1778)
						)
						(arc
							(start -0.2794 0.1778)
							(mid -0.249642 0.249642)
							(end -0.1778 0.2794)
						)
						(arc
							(start 0.1778 0.2794)
							(mid 0.249642 0.249642)
							(end 0.2794 0.1778)
						)
						(arc
							(start 0.2794 -0.1778)
							(mid 0.249642 -0.249642)
							(end 0.1778 -0.2794)
						)
					)
					(width 0)
					(fill yes)
				)
			)
		)
		(pad "2" smd custom
			(at 0 0.4445)
			(size 0.1397 0.1397)
			(layers "F.Cu" "F.Mask" "F.Paste")
			(net "I2C_DPB_B_SDA")
			(options
				(clearance outline)
				(anchor circle)
			)
			(primitives
				(gr_poly
					(pts
						(arc
							(start -0.1778 -0.2794)
							(mid -0.249642 -0.249642)
							(end -0.2794 -0.1778)
						)
						(arc
							(start -0.2794 0.1778)
							(mid -0.249642 0.249642)
							(end -0.1778 0.2794)
						)
						(arc
							(start 0.1778 0.2794)
							(mid 0.249642 0.249642)
							(end 0.2794 0.1778)
						)
						(arc
							(start 0.2794 -0.1778)
							(mid 0.249642 -0.249642)
							(end 0.1778 -0.2794)
						)
					)
					(width 0)
					(fill yes)
				)
			)
		)
	)
	(footprint ""
		(layer "F.Cu")
		(at 239.776 -215.265)
		(property "Reference" "R84"
			(at 0 0 0)
			(layer "F.SilkS")
			(hide yes)
			(effects
				(font
					(size 1.27 1.27)
				)
			)
		)
		(property "Value" "4K7R2F-GP"
			(at 0.064008 -3.993896 0)
			(unlocked yes)
			(layer "F.Fab")
			(hide yes)
			(effects
				(font
					(size 1.016 1.016)
					(thickness 0.1524)
				)
			)
		)
		(property "Device Type" "R402H16"
			(at 0.064008 -5.517896 0)
			(unlocked yes)
			(layer "F.Fab")
			(hide yes)
			(effects
				(font
					(size 1.016 1.016)
					(thickness 0.1524)
				)
			)
		)
		(duplicate_pad_numbers_are_jumpers no)
		(fp_line
			(start -0.508 -0.9398)
			(end -0.508 0.9398)
			(stroke
				(width 0.1524)
				(type default)
			)
			(layer "F.SilkS")
		)
		(fp_line
			(start 0.508 -0.9398)
			(end -0.508 -0.9398)
			(stroke
				(width 0.1524)
				(type default)
			)
			(layer "F.SilkS")
		)
		(fp_rect
			(start -0.508 0.9398)
			(end 0.508 -0.9398)
			(stroke
				(width 0)
				(type default)
			)
			(fill no)
			(layer "F.CrtYd")
		)
		(fp_rect
			(start -0.508 0.9398)
			(end 0.508 -0.9398)
			(stroke
				(width 0)
				(type default)
			)
			(fill no)
			(layer "F.Fab")
		)
		(pad "1" smd custom
			(at 0 -0.4445)
			(size 0.1397 0.1397)
			(layers "F.Cu" "F.Mask" "F.Paste")
			(net "IO_EXP3_A0")
			(options
				(clearance outline)
				(anchor circle)
			)
			(primitives
				(gr_poly
					(pts
						(arc
							(start -0.1778 -0.2794)
							(mid -0.249642 -0.249642)
							(end -0.2794 -0.1778)
						)
						(arc
							(start -0.2794 0.1778)
							(mid -0.249642 0.249642)
							(end -0.1778 0.2794)
						)
						(arc
							(start 0.1778 0.2794)
							(mid 0.249642 0.249642)
							(end 0.2794 0.1778)
						)
						(arc
							(start 0.2794 -0.1778)
							(mid 0.249642 -0.249642)
							(end 0.1778 -0.2794)
						)
					)
					(width 0)
					(fill yes)
				)
			)
		)
		(pad "2" smd custom
			(at 0 0.4445)
			(size 0.1397 0.1397)
			(layers "F.Cu" "F.Mask" "F.Paste")
			(net "GND")
			(options
				(clearance outline)
				(anchor circle)
			)
			(primitives
				(gr_poly
					(pts
						(arc
							(start -0.1778 -0.2794)
							(mid -0.249642 -0.249642)
							(end -0.2794 -0.1778)
						)
						(arc
							(start -0.2794 0.1778)
							(mid -0.249642 0.249642)
							(end -0.1778 0.2794)
						)
						(arc
							(start 0.1778 0.2794)
							(mid 0.249642 0.249642)
							(end 0.2794 0.1778)
						)
						(arc
							(start 0.2794 -0.1778)
							(mid 0.249642 -0.249642)
							(end 0.1778 -0.2794)
						)
					)
					(width 0)
					(fill yes)
				)
			)
		)
	)
	(footprint ""
		(layer "F.Cu")
		(at 245.387622 -215.265 180)
		(property "Reference" "R82"
			(at 0 0 180)
			(layer "F.SilkS")
			(hide yes)
			(effects
				(font
					(size 1.27 1.27)
				)
			)
		)
		(property "Value" "4K7R2F-GP"
			(at 0.064008 -3.993896 180)
			(unlocked yes)
			(layer "F.Fab")
			(hide yes)
			(effects
				(font
					(size 1.016 1.016)
					(thickness 0.1524)
				)
			)
		)
		(property "Device Type" "R402H16"
			(at 0.064008 -5.517896 180)
			(unlocked yes)
			(layer "F.Fab")
			(hide yes)
			(effects
				(font
					(size 1.016 1.016)
					(thickness 0.1524)
				)
			)
		)
		(duplicate_pad_numbers_are_jumpers no)
		(fp_line
			(start 0.508 -0.9398)
			(end -0.508 -0.9398)
			(stroke
				(width 0.1524)
				(type default)
			)
			(layer "F.SilkS")
		)
		(fp_line
			(start -0.508 -0.9398)
			(end -0.508 0.9398)
			(stroke
				(width 0.1524)
				(type default)
			)
			(layer "F.SilkS")
		)
		(fp_rect
			(start -0.508 0.9398)
			(end 0.508 -0.9398)
			(stroke
				(width 0)
				(type default)
			)
			(fill no)
			(layer "F.CrtYd")
		)
		(fp_rect
			(start -0.508 0.9398)
			(end 0.508 -0.9398)
			(stroke
				(width 0)
				(type default)
			)
			(fill no)
			(layer "F.Fab")
		)
		(pad "1" smd custom
			(at 0 -0.4445 180)
			(size 0.1397 0.1397)
			(layers "F.Cu" "F.Mask" "F.Paste")
			(net "P3V3_STBY_B")
			(options
				(clearance outline)
				(anchor circle)
			)
			(primitives
				(gr_poly
					(pts
						(arc
							(start -0.1778 -0.2794)
							(mid -0.249642 -0.249642)
							(end -0.2794 -0.1778)
						)
						(arc
							(start -0.2794 0.1778)
							(mid -0.249642 0.249642)
							(end -0.1778 0.2794)
						)
						(arc
							(start 0.1778 0.2794)
							(mid 0.249642 0.249642)
							(end 0.2794 0.1778)
						)
						(arc
							(start 0.2794 -0.1778)
							(mid 0.249642 -0.249642)
							(end 0.1778 -0.2794)
						)
					)
					(width 0)
					(fill yes)
				)
			)
		)
		(pad "2" smd custom
			(at 0 0.4445 180)
			(size 0.1397 0.1397)
			(layers "F.Cu" "F.Mask" "F.Paste")
			(net "IO_EXP3_A2")
			(options
				(clearance outline)
				(anchor circle)
			)
			(primitives
				(gr_poly
					(pts
						(arc
							(start -0.1778 -0.2794)
							(mid -0.249642 -0.249642)
							(end -0.2794 -0.1778)
						)
						(arc
							(start -0.2794 0.1778)
							(mid -0.249642 0.249642)
							(end -0.1778 0.2794)
						)
						(arc
							(start 0.1778 0.2794)
							(mid 0.249642 0.249642)
							(end 0.2794 0.1778)
						)
						(arc
							(start 0.2794 -0.1778)
							(mid 0.249642 -0.249642)
							(end 0.1778 -0.2794)
						)
					)
					(width 0)
					(fill yes)
				)
			)
		)
	)
	(footprint ""
		(layer "F.Cu")
		(at 228.96449 -353.280726 180)
		(property "Reference" "C517"
			(at 0 0 180)
			(layer "F.SilkS")
			(hide yes)
			(effects
				(font
					(size 1.27 1.27)
				)
			)
		)
		(property "Value" "SC22U25V6KX-2-GP-U"
			(at -2.860802 -5.279644 180)
			(unlocked yes)
			(layer "F.Fab")
			(hide yes)
			(effects
				(font
					(size 1.016 1.016)
					(thickness 0.1524)
				)
			)
		)
		(property "Device Type" "C1206-TO0D3H75"
			(at -2.860802 -6.803644 180)
			(unlocked yes)
			(layer "F.Fab")
			(hide yes)
			(effects
				(font
					(size 1.016 1.016)
					(thickness 0.1524)
				)
			)
		)
		(duplicate_pad_numbers_are_jumpers no)
		(fp_line
			(start 1.3081 2.3749)
			(end -1.3081 2.3749)
			(stroke
				(width 0.1524)
				(type default)
			)
			(layer "F.SilkS")
		)
		(fp_line
			(start 1.3081 -2.3749)
			(end 1.3081 2.3749)
			(stroke
				(width 0.1524)
				(type default)
			)
			(layer "F.SilkS")
		)
		(fp_line
			(start -1.3081 2.3749)
			(end -1.3081 -2.3749)
			(stroke
				(width 0.1524)
				(type default)
			)
			(layer "F.SilkS")
		)
		(fp_line
			(start -1.3081 -2.3749)
			(end 1.3081 -2.3749)
			(stroke
				(width 0.1524)
				(type default)
			)
			(layer "F.SilkS")
		)
		(fp_rect
			(start -0.8001 1.6002)
			(end 0.8001 -1.6002)
			(stroke
				(width 0)
				(type default)
			)
			(fill no)
			(layer "F.CrtYd")
		)
		(fp_poly
			(pts
				(xy -1.5621 2.4511) (xy -1.5621 1.6002) (xy 0.8001 1.6002) (xy 0.8001 -1.6002) (xy -0.8001 -1.6002)
				(xy -0.8001 1.5875) (xy -1.5621 1.5875) (xy -1.5621 -2.4511) (xy 1.5621 -2.4511) (xy 1.5621 2.4511)
			)
			(stroke
				(width 0)
				(type default)
			)
			(fill no)
			(layer "F.CrtYd")
		)
		(fp_rect
			(start -1.5621 2.4511)
			(end 1.5621 -2.4511)
			(stroke
				(width 0)
				(type default)
			)
			(fill no)
			(layer "F.Fab")
		)
		(pad "1" smd rect
			(at 0 -1.392936 180)
			(size 2.1082 1.4478)
			(layers "F.Cu" "F.Mask" "F.Paste")
			(net "P12V_IN")
		)
		(pad "2" smd rect
			(at 0 1.392936 180)
			(size 2.1082 1.4478)
			(layers "F.Cu" "F.Mask" "F.Paste")
			(net "GND")
		)
	)
	(footprint ""
		(layer "F.Cu")
		(at 388.649972 -28.910026 -90)
		(property "Reference" "HDDSAS32"
			(at 0 0 270)
			(layer "F.SilkS")
			(hide yes)
			(effects
				(font
					(size 1.27 1.27)
				)
			)
		)
		(property "Value" "SKT-SAS15P-14P-45-GP"
			(at -20.7645 -8.9789 270)
			(unlocked yes)
			(layer "F.Fab")
			(hide yes)
			(effects
				(font
					(size 1.016 1.016)
					(thickness 0.1524)
				)
			)
		)
		(property "Device Type" "10120818-001C-TRLF"
			(at -20.7645 -10.5029 270)
			(unlocked yes)
			(layer "F.Fab")
			(hide yes)
			(effects
				(font
					(size 1.016 1.016)
					(thickness 0.1524)
				)
			)
		)
		(duplicate_pad_numbers_are_jumpers no)
		(fp_line
			(start 1.651 4.2926)
			(end 1.651 3.0099)
			(stroke
				(width 0.1524)
				(type default)
			)
			(layer "F.SilkS")
		)
		(fp_line
			(start 8.509 4.2926)
			(end 1.651 4.2926)
			(stroke
				(width 0.1524)
				(type default)
			)
			(layer "F.SilkS")
		)
		(fp_line
			(start -23.4188 3.0099)
			(end -23.4188 -3.2512)
			(stroke
				(width 0.1524)
				(type default)
			)
			(layer "F.SilkS")
		)
		(fp_line
			(start 1.651 3.0099)
			(end -23.4188 3.0099)
			(stroke
				(width 0.1524)
				(type default)
			)
			(layer "F.SilkS")
		)
		(fp_line
			(start 8.509 3.0099)
			(end 8.509 4.2926)
			(stroke
				(width 0.1524)
				(type default)
			)
			(layer "F.SilkS")
		)
		(fp_line
			(start 23.4188 3.0099)
			(end 8.509 3.0099)
			(stroke
				(width 0.1524)
				(type default)
			)
			(layer "F.SilkS")
		)
		(fp_line
			(start -23.4188 -3.2512)
			(end 23.4188 -3.2512)
			(stroke
				(width 0.1524)
				(type default)
			)
			(layer "F.SilkS")
		)
		(fp_line
			(start 23.4188 -3.2512)
			(end 23.4188 3.0099)
			(stroke
				(width 0.1524)
				(type default)
			)
			(layer "F.SilkS")
		)
		(fp_line
			(start 15.5067 -3.3401)
			(end 16.2687 -3.3401)
			(stroke
				(width 0.3302)
				(type default)
			)
			(layer "F.SilkS")
		)
		(fp_poly
			(pts
				(xy 15.868904 -3.230372) (xy 16.503904 -3.865372) (xy 15.233904 -3.865372)
			)
			(stroke
				(width 0)
				(type default)
			)
			(fill yes)
			(layer "F.SilkS")
		)
		(fp_poly
			(pts
				(xy -22.8727 -2.7559) (xy 22.8727 -2.7559) (xy 22.8727 2.7559) (xy 8.255 2.7559) (xy 8.255 3.5179)
				(xy 1.905 3.5179) (xy 1.905 2.7559) (xy -22.8727 2.7559)
			)
			(stroke
				(width 0)
				(type default)
			)
			(fill no)
			(layer "F.CrtYd")
		)
		(fp_poly
			(pts
				(xy 1.397 4.5466) (xy 1.397 3.2639) (xy -23.6728 3.2639) (xy -23.6728 -3.5052) (xy 23.6728 -3.5052)
				(xy 23.6728 -0.00635) (xy 22.8727 -0.00635) (xy 22.8727 -2.7559) (xy -22.8727 -2.7559) (xy -22.8727 2.7559)
				(xy 1.905 2.7559) (xy 1.905 3.5179) (xy 8.255 3.5179) (xy 8.255 2.7559) (xy 22.8727 2.7559) (xy 22.8727 0.00635)
				(xy 23.6728 0.00635) (xy 23.6728 3.2639) (xy 8.763 3.2639) (xy 8.763 4.5466)
			)
			(stroke
				(width 0)
				(type default)
			)
			(fill no)
			(layer "F.CrtYd")
		)
		(fp_poly
			(pts
				(xy 1.397 4.5466) (xy 1.397 3.2639) (xy -23.6728 3.2639) (xy -23.6728 -3.5052) (xy 23.6728 -3.5052)
				(xy 23.6728 3.2639) (xy 8.763 3.2639) (xy 8.763 4.5466)
			)
			(stroke
				(width 0)
				(type default)
			)
			(fill no)
			(layer "F.Fab")
		)
		(pad "" np_thru_hole circle
			(at -18.874994 0 270)
			(size 0.254 0.254)
			(drill 1.3462)
			(layers "*.Cu" "*.Mask")
			(clearance 0.9017)
			(thermal_gap 0.9017)
		)
		(pad "" np_thru_hole circle
			(at 18.874994 0 270)
			(size 0.254 0.254)
			(drill 0.9398)
			(layers "*.Cu" "*.Mask")
			(clearance 0.6985)
			(thermal_gap 0.6985)
		)
		(pad "G1" smd rect
			(at 21.874988 0 270)
			(size 2.5908 2.5908)
			(layers "F.Cu" "F.Mask" "F.Paste")
			(net "GND")
		)
		(pad "G2" smd rect
			(at -21.874988 0 270)
			(size 2.5908 2.5908)
			(layers "F.Cu" "F.Mask" "F.Paste")
			(net "GND")
		)
		(pad "P1" smd rect
			(at 1.905 -1.82499 270)
			(size 0.6096 2.3622)
			(layers "F.Cu" "F.Mask" "F.Paste")
			(net "Net_1634")
		)
		(pad "P2" smd rect
			(at 0.635 -1.82499 270)
			(size 0.6096 2.3622)
			(layers "F.Cu" "F.Mask" "F.Paste")
			(net "Net_1635")
		)
		(pad "P3" smd rect
			(at -0.635 -1.82499 270)
			(size 0.6096 2.3622)
			(layers "F.Cu" "F.Mask" "F.Paste")
			(net "Net_1636")
		)
		(pad "P4" smd rect
			(at -1.905 -1.82499 270)
			(size 0.6096 2.3622)
			(layers "F.Cu" "F.Mask" "F.Paste")
			(net "GND")
		)
		(pad "P5" smd rect
			(at -3.175 -1.82499 270)
			(size 0.6096 2.3622)
			(layers "F.Cu" "F.Mask" "F.Paste")
			(net "HDD_PRSNT_32")
		)
		(pad "P6" smd rect
			(at -4.445 -1.82499 270)
			(size 0.6096 2.3622)
			(layers "F.Cu" "F.Mask" "F.Paste")
			(net "GND")
		)
		(pad "P7" smd rect
			(at -5.715 -1.82499 270)
			(size 0.6096 2.3622)
			(layers "F.Cu" "F.Mask" "F.Paste")
			(net "5V_PRE_32")
		)
		(pad "P8" smd rect
			(at -6.985 -1.82499 270)
			(size 0.6096 2.3622)
			(layers "F.Cu" "F.Mask" "F.Paste")
			(net "P5V_HDD32")
		)
		(pad "P9" smd rect
			(at -8.255 -1.82499 270)
			(size 0.6096 2.3622)
			(layers "F.Cu" "F.Mask" "F.Paste")
			(net "P5V_HDD32")
		)
		(pad "P10" smd rect
			(at -9.525 -1.82499 270)
			(size 0.6096 2.3622)
			(layers "F.Cu" "F.Mask" "F.Paste")
			(net "GND")
		)
		(pad "P11" smd rect
			(at -10.795 -1.82499 270)
			(size 0.6096 2.3622)
			(layers "F.Cu" "F.Mask" "F.Paste")
			(net "ACT_HDD_32")
		)
		(pad "P12" smd rect
			(at -12.065 -1.82499 270)
			(size 0.6096 2.3622)
			(layers "F.Cu" "F.Mask" "F.Paste")
			(net "GND")
		)
		(pad "P13" smd rect
			(at -13.335 -1.82499 270)
			(size 0.6096 2.3622)
			(layers "F.Cu" "F.Mask" "F.Paste")
			(net "12V_PRE_32")
		)
		(pad "P14" smd rect
			(at -14.605 -1.82499 270)
			(size 0.6096 2.3622)
			(layers "F.Cu" "F.Mask" "F.Paste")
			(net "P12V_HDD32")
		)
		(pad "P15" smd rect
			(at -15.875 -1.82499 270)
			(size 0.6096 2.3622)
			(layers "F.Cu" "F.Mask" "F.Paste")
			(net "P12V_HDD32")
		)
		(pad "S1" smd rect
			(at 15.875 -1.82499 270)
			(size 0.6096 2.3622)
			(layers "F.Cu" "F.Mask" "F.Paste")
			(net "GND")
		)
		(pad "S2" smd rect
			(at 14.605 -1.82499 270)
			(size 0.6096 2.3622)
			(layers "F.Cu" "F.Mask" "F.Paste")
			(net "SAS_HDD_RX_P32")
		)
		(pad "S3" smd rect
			(at 13.335 -1.82499 270)
			(size 0.6096 2.3622)
			(layers "F.Cu" "F.Mask" "F.Paste")
			(net "SAS_HDD_RX_N32")
		)
		(pad "S4" smd rect
			(at 12.065 -1.82499 270)
			(size 0.6096 2.3622)
			(layers "F.Cu" "F.Mask" "F.Paste")
			(net "GND")
		)
		(pad "S5" smd rect
			(at 10.795 -1.82499 270)
			(size 0.6096 2.3622)
			(layers "F.Cu" "F.Mask" "F.Paste")
			(net "PHY_DRV_B_TO_SCC_B_32_DN")
		)
		(pad "S6" smd rect
			(at 9.525 -1.82499 270)
			(size 0.6096 2.3622)
			(layers "F.Cu" "F.Mask" "F.Paste")
			(net "PHY_DRV_B_TO_SCC_B_32_DP")
		)
		(pad "S7" smd rect
			(at 8.255 -1.82499 270)
			(size 0.6096 2.3622)
			(layers "F.Cu" "F.Mask" "F.Paste")
			(net "GND")
		)
		(pad "S8" smd rect
			(at 7.480046 2.845054 270)
			(size 0.508 2.3622)
			(layers "F.Cu" "F.Mask" "F.Paste")
			(net "GND")
		)
		(pad "S9" smd rect
			(at 6.679946 2.845054 270)
			(size 0.508 2.3622)
			(layers "F.Cu" "F.Mask" "F.Paste")
			(net "Net_457")
		)
		(pad "S10" smd rect
			(at 5.8801 2.845054 270)
			(size 0.508 2.3622)
			(layers "F.Cu" "F.Mask" "F.Paste")
			(net "Net_349")
		)
		(pad "S11" smd rect
			(at 5.08 2.845054 270)
			(size 0.508 2.3622)
			(layers "F.Cu" "F.Mask" "F.Paste")
			(net "GND")
		)
		(pad "S12" smd rect
			(at 4.2799 2.845054 270)
			(size 0.508 2.3622)
			(layers "F.Cu" "F.Mask" "F.Paste")
			(net "Net_385")
		)
		(pad "S13" smd rect
			(at 3.480054 2.845054 270)
			(size 0.508 2.3622)
			(layers "F.Cu" "F.Mask" "F.Paste")
			(net "Net_421")
		)
		(pad "S14" smd rect
			(at 2.679954 2.845054 270)
			(size 0.508 2.3622)
			(layers "F.Cu" "F.Mask" "F.Paste")
			(net "GND")
		)
		(zone
			(layer "F.Cu")
			(hatch none 0.5)
			(connect_pads
				(clearance 0)
			)
			(min_thickness 0.25)
			(keepout
				(tracks not_allowed)
				(vias allowed)
				(pads allowed)
				(copperpour not_allowed)
				(footprints allowed)
			)
			(placement
				(enabled no)
				(sheetname "")
			)
			(fill
				(thermal_gap 0.5)
				(thermal_bridge_width 0.5)
				(island_removal_mode 0)
			)
			(polygon
				(pts
					(xy 392.307572 -45.648626) (xy 385.233672 -45.648626) (xy 385.233672 -52.582826) (xy 386.338572 -52.582826)
					(xy 386.338572 -48.468026) (xy 390.961372 -48.468026) (xy 390.961372 -52.582826) (xy 392.307572 -52.582826)
				)
			)
		)
		(zone
			(layer "F.Cu")
			(hatch none 0.5)
			(connect_pads
				(clearance 0)
			)
			(min_thickness 0.25)
			(keepout
				(tracks allowed)
				(vias not_allowed)
				(pads allowed)
				(copperpour not_allowed)
				(footprints allowed)
			)
			(placement
				(enabled no)
				(sheetname "")
			)
			(fill
				(thermal_gap 0.5)
				(thermal_bridge_width 0.5)
				(island_removal_mode 0)
			)
			(polygon
				(pts
					(xy 392.307572 -45.648626) (xy 385.233672 -45.648626) (xy 385.233672 -52.582826) (xy 386.338572 -52.582826)
					(xy 386.338572 -48.468026) (xy 390.961372 -48.468026) (xy 390.961372 -52.582826) (xy 392.307572 -52.582826)
				)
			)
		)
		(zone
			(layer "F.Cu")
			(hatch none 0.5)
			(connect_pads
				(clearance 0)
			)
			(min_thickness 0.25)
			(keepout
				(tracks not_allowed)
				(vias allowed)
				(pads allowed)
				(copperpour not_allowed)
				(footprints allowed)
			)
			(placement
				(enabled no)
				(sheetname "")
			)
			(fill
				(thermal_gap 0.5)
				(thermal_bridge_width 0.5)
				(island_removal_mode 0)
			)
			(polygon
				(pts
					(xy 392.307572 -12.171426) (xy 385.233672 -12.171426) (xy 385.233672 -5.237226) (xy 386.338572 -5.237226)
					(xy 386.338572 -9.352026) (xy 390.961372 -9.352026) (xy 390.961372 -5.237226) (xy 392.307572 -5.237226)
				)
			)
		)
		(zone
			(layer "F.Cu")
			(hatch none 0.5)
			(connect_pads
				(clearance 0)
			)
			(min_thickness 0.25)
			(keepout
				(tracks allowed)
				(vias not_allowed)
				(pads allowed)
				(copperpour not_allowed)
				(footprints allowed)
			)
			(placement
				(enabled no)
				(sheetname "")
			)
			(fill
				(thermal_gap 0.5)
				(thermal_bridge_width 0.5)
				(island_removal_mode 0)
			)
			(polygon
				(pts
					(xy 392.307572 -12.171426) (xy 385.233672 -12.171426) (xy 385.233672 -5.237226) (xy 386.338572 -5.237226)
					(xy 386.338572 -9.352026) (xy 390.961372 -9.352026) (xy 390.961372 -5.237226) (xy 392.307572 -5.237226)
				)
			)
		)
		(zone
			(layers "F.Cu" "B.Cu" "In1.Cu" "In2.Cu" "In3.Cu" "In4.Cu" "In5.Cu" "In6.Cu")
			(hatch none 0.5)
			(connect_pads
				(clearance 0)
			)
			(min_thickness 0.25)
			(keepout
				(tracks not_allowed)
				(vias allowed)
				(pads allowed)
				(copperpour not_allowed)
				(footprints allowed)
			)
			(placement
				(enabled no)
				(sheetname "")
			)
			(fill
				(thermal_gap 0.5)
				(thermal_bridge_width 0.5)
				(island_removal_mode 0)
			)
			(polygon
				(pts
					(arc
						(start 389.424672 -10.035032)
						(mid 387.875272 -10.035032)
						(end 389.424672 -10.035032)
					)
				)
			)
		)
		(zone
			(layers "F.Cu" "B.Cu" "In1.Cu" "In2.Cu" "In3.Cu" "In4.Cu" "In5.Cu" "In6.Cu")
			(hatch none 0.5)
			(connect_pads
				(clearance 0)
			)
			(min_thickness 0.25)
			(keepout
				(tracks not_allowed)
				(vias allowed)
				(pads allowed)
				(copperpour not_allowed)
				(footprints allowed)
			)
			(placement
				(enabled no)
				(sheetname "")
			)
			(fill
				(thermal_gap 0.5)
				(thermal_bridge_width 0.5)
				(island_removal_mode 0)
			)
			(polygon
				(pts
					(arc
						(start 389.627872 -47.78502)
						(mid 387.672072 -47.78502)
						(end 389.627872 -47.78502)
					)
				)
			)
		)
	)
	(footprint ""
		(layer "F.Cu")
		(at 20.1676 -148.717 -90)
		(property "Reference" "C186"
			(at 0 0 270)
			(layer "F.SilkS")
			(hide yes)
			(effects
				(font
					(size 1.27 1.27)
				)
			)
		)
		(property "Value" "SC1U16V3KX-5GP"
			(at 0 -2.8194 270)
			(unlocked yes)
			(layer "F.Fab")
			(hide yes)
			(effects
				(font
					(size 1.016 1.016)
					(thickness 0.1524)
				)
			)
		)
		(property "Device Type" "C603H36"
			(at 0 -4.3434 270)
			(unlocked yes)
			(layer "F.Fab")
			(hide yes)
			(effects
				(font
					(size 1.016 1.016)
					(thickness 0.1524)
				)
			)
		)
		(duplicate_pad_numbers_are_jumpers no)
		(fp_line
			(start 0.508 0)
			(end -0.508 0)
			(stroke
				(width 0.2032)
				(type default)
			)
			(layer "F.SilkS")
		)
		(fp_rect
			(start -0.5842 1.3335)
			(end 0.5842 -1.3335)
			(stroke
				(width 0)
				(type default)
			)
			(fill no)
			(layer "F.CrtYd")
		)
		(fp_rect
			(start -0.5842 1.3335)
			(end 0.5842 -1.3335)
			(stroke
				(width 0)
				(type default)
			)
			(fill no)
			(layer "F.Fab")
		)
		(pad "1" smd custom
			(at 0 -0.762 270)
			(size 0.2159 0.2159)
			(layers "F.Cu" "F.Mask" "F.Paste")
			(net "P5V_HDD12")
			(options
				(clearance outline)
				(anchor circle)
			)
			(primitives
				(gr_poly
					(pts
						(arc
							(start -0.3302 -0.4318)
							(mid -0.402042 -0.402042)
							(end -0.4318 -0.3302)
						)
						(arc
							(start -0.4318 0.3302)
							(mid -0.402042 0.402042)
							(end -0.3302 0.4318)
						)
						(arc
							(start 0.3302 0.4318)
							(mid 0.402042 0.402042)
							(end 0.4318 0.3302)
						)
						(arc
							(start 0.4318 -0.3302)
							(mid 0.402042 -0.402042)
							(end 0.3302 -0.4318)
						)
					)
					(width 0)
					(fill yes)
				)
			)
		)
		(pad "2" smd custom
			(at 0 0.762 270)
			(size 0.2159 0.2159)
			(layers "F.Cu" "F.Mask" "F.Paste")
			(net "GND")
			(options
				(clearance outline)
				(anchor circle)
			)
			(primitives
				(gr_poly
					(pts
						(arc
							(start -0.3302 -0.4318)
							(mid -0.402042 -0.402042)
							(end -0.4318 -0.3302)
						)
						(arc
							(start -0.4318 0.3302)
							(mid -0.402042 0.402042)
							(end -0.3302 0.4318)
						)
						(arc
							(start 0.3302 0.4318)
							(mid 0.402042 0.402042)
							(end 0.4318 0.3302)
						)
						(arc
							(start 0.4318 -0.3302)
							(mid 0.402042 -0.402042)
							(end 0.3302 -0.4318)
						)
					)
					(width 0)
					(fill yes)
				)
			)
		)
	)
	(footprint ""
		(layer "F.Cu")
		(at 97.385632 -244.990874 90)
		(property "Reference" "VIA5"
			(at 0 0 90)
			(layer "F.SilkS")
			(hide yes)
			(effects
				(font
					(size 1.27 1.27)
				)
			)
		)
		(property "Value" "100OHM-8L-2D36MM-L18-GP"
			(at 3.8989 0.5715 90)
			(unlocked yes)
			(layer "F.Fab")
			(hide yes)
			(effects
				(font
					(size 1.016 1.016)
					(thickness 0.1524)
				)
			)
		)
		(property "Device Type" "VIA-PCIE-4P-414097"
			(at 3.8989 -0.9525 90)
			(unlocked yes)
			(layer "F.Fab")
			(hide yes)
			(effects
				(font
					(size 1.016 1.016)
					(thickness 0.1524)
				)
			)
		)
		(duplicate_pad_numbers_are_jumpers no)
		(fp_rect
			(start -2.0701 0.4826)
			(end 2.0701 -0.4826)
			(stroke
				(width 0)
				(type default)
			)
			(fill no)
			(layer "F.CrtYd")
		)
		(fp_rect
			(start -2.0701 0.4826)
			(end 2.0701 -0.4826)
			(stroke
				(width 0)
				(type default)
			)
			(fill no)
			(layer "F.Fab")
		)
		(pad "1" thru_hole circle
			(at -1.5875 0 90)
			(size 0.508 0.508)
			(drill 0.254)
			(layers "*.Cu" "*.Mask")
			(remove_unused_layers no)
			(net "GND")
			(clearance 0.2286)
			(thermal_gap 0.2286)
		)
		(pad "2" thru_hole circle
			(at -0.5715 0 90)
			(size 0.508 0.508)
			(drill 0.254)
			(layers "*.Cu" "*.Mask")
			(remove_unused_layers no)
			(net "PHY_SCC_B_TO_DRV_B_2_DP")
			(clearance 0.2286)
			(thermal_gap 0.2286)
		)
		(pad "3" thru_hole circle
			(at 0.5715 0 90)
			(size 0.508 0.508)
			(drill 0.254)
			(layers "*.Cu" "*.Mask")
			(remove_unused_layers no)
			(net "PHY_SCC_B_TO_DRV_B_2_DN")
			(clearance 0.2286)
			(thermal_gap 0.2286)
		)
		(pad "4" thru_hole circle
			(at 1.5875 0 90)
			(size 0.508 0.508)
			(drill 0.254)
			(layers "*.Cu" "*.Mask")
			(remove_unused_layers no)
			(net "GND")
			(clearance 0.2286)
			(thermal_gap 0.2286)
		)
	)
	(footprint ""
		(layer "F.Cu")
		(at 48.26 -138.049 90)
		(property "Reference" "R376"
			(at 0 0 90)
			(layer "F.SilkS")
			(hide yes)
			(effects
				(font
					(size 1.27 1.27)
				)
			)
		)
		(property "Value" "4K7R2J-2-GP"
			(at 0.064008 -3.993896 90)
			(unlocked yes)
			(layer "F.Fab")
			(hide yes)
			(effects
				(font
					(size 1.016 1.016)
					(thickness 0.1524)
				)
			)
		)
		(property "Device Type" "R402H16"
			(at 0.064008 -5.517896 90)
			(unlocked yes)
			(layer "F.Fab")
			(hide yes)
			(effects
				(font
					(size 1.016 1.016)
					(thickness 0.1524)
				)
			)
		)
		(duplicate_pad_numbers_are_jumpers no)
		(fp_line
			(start 0.508 -0.9398)
			(end -0.508 -0.9398)
			(stroke
				(width 0.1524)
				(type default)
			)
			(layer "F.SilkS")
		)
		(fp_line
			(start -0.508 -0.9398)
			(end -0.508 0.9398)
			(stroke
				(width 0.1524)
				(type default)
			)
			(layer "F.SilkS")
		)
		(fp_rect
			(start -0.508 0.9398)
			(end 0.508 -0.9398)
			(stroke
				(width 0)
				(type default)
			)
			(fill no)
			(layer "F.CrtYd")
		)
		(fp_rect
			(start -0.508 0.9398)
			(end 0.508 -0.9398)
			(stroke
				(width 0)
				(type default)
			)
			(fill no)
			(layer "F.Fab")
		)
		(pad "1" smd custom
			(at 0 -0.4445 90)
			(size 0.1397 0.1397)
			(layers "F.Cu" "F.Mask" "F.Paste")
			(net "P12V_B")
			(options
				(clearance outline)
				(anchor circle)
			)
			(primitives
				(gr_poly
					(pts
						(arc
							(start -0.1778 -0.2794)
							(mid -0.249642 -0.249642)
							(end -0.2794 -0.1778)
						)
						(arc
							(start -0.2794 0.1778)
							(mid -0.249642 0.249642)
							(end -0.1778 0.2794)
						)
						(arc
							(start 0.1778 0.2794)
							(mid 0.249642 0.249642)
							(end 0.2794 0.1778)
						)
						(arc
							(start 0.2794 -0.1778)
							(mid 0.249642 -0.249642)
							(end 0.1778 -0.2794)
						)
					)
					(width 0)
					(fill yes)
				)
			)
		)
		(pad "2" smd custom
			(at 0 0.4445 90)
			(size 0.1397 0.1397)
			(layers "F.Cu" "F.Mask" "F.Paste")
			(net "SW_HDD_P13")
			(options
				(clearance outline)
				(anchor circle)
			)
			(primitives
				(gr_poly
					(pts
						(arc
							(start -0.1778 -0.2794)
							(mid -0.249642 -0.249642)
							(end -0.2794 -0.1778)
						)
						(arc
							(start -0.2794 0.1778)
							(mid -0.249642 0.249642)
							(end -0.1778 0.2794)
						)
						(arc
							(start 0.1778 0.2794)
							(mid 0.249642 0.249642)
							(end 0.2794 0.1778)
						)
						(arc
							(start 0.2794 -0.1778)
							(mid 0.249642 -0.249642)
							(end 0.1778 -0.2794)
						)
					)
					(width 0)
					(fill yes)
				)
			)
		)
	)
	(footprint ""
		(layer "F.Cu")
		(at 127.15875 -248.750074 -90)
		(property "Reference" "VIA8"
			(at 0 0 270)
			(layer "F.SilkS")
			(hide yes)
			(effects
				(font
					(size 1.27 1.27)
				)
			)
		)
		(property "Value" "100OHM-8L-2D36MM-L16-GP"
			(at -3.4036 -0.4572 270)
			(unlocked yes)
			(layer "F.Fab")
			(hide yes)
			(effects
				(font
					(size 1.016 1.016)
					(thickness 0.1524)
				)
			)
		)
		(property "Device Type" "VIA-PCIE-4P-427097"
			(at -3.4036 -1.9812 270)
			(unlocked yes)
			(layer "F.Fab")
			(hide yes)
			(effects
				(font
					(size 1.016 1.016)
					(thickness 0.1524)
				)
			)
		)
		(duplicate_pad_numbers_are_jumpers no)
		(fp_rect
			(start -2.1336 0.4826)
			(end 2.1336 -0.4826)
			(stroke
				(width 0)
				(type default)
			)
			(fill no)
			(layer "F.CrtYd")
		)
		(fp_rect
			(start -2.1336 0.4826)
			(end 2.1336 -0.4826)
			(stroke
				(width 0)
				(type default)
			)
			(fill no)
			(layer "F.Fab")
		)
		(pad "1" thru_hole circle
			(at -1.651 0 270)
			(size 0.508 0.508)
			(drill 0.254)
			(layers "*.Cu" "*.Mask")
			(remove_unused_layers no)
			(net "GND")
			(clearance 0.2286)
			(thermal_gap 0.2286)
		)
		(pad "2" thru_hole circle
			(at -0.635 0 270)
			(size 0.508 0.508)
			(drill 0.254)
			(layers "*.Cu" "*.Mask")
			(remove_unused_layers no)
			(net "PHY_DRV_B_TO_SCC_B_3_DP")
			(clearance 0.2286)
			(thermal_gap 0.2286)
		)
		(pad "3" thru_hole circle
			(at 0.635 0 270)
			(size 0.508 0.508)
			(drill 0.254)
			(layers "*.Cu" "*.Mask")
			(remove_unused_layers no)
			(net "PHY_DRV_B_TO_SCC_B_3_DN")
			(clearance 0.2286)
			(thermal_gap 0.2286)
		)
		(pad "4" thru_hole circle
			(at 1.651 0 270)
			(size 0.508 0.508)
			(drill 0.254)
			(layers "*.Cu" "*.Mask")
			(remove_unused_layers no)
			(net "GND")
			(clearance 0.2286)
			(thermal_gap 0.2286)
		)
	)
	(footprint ""
		(layer "F.Cu")
		(at 386.6896 -248.750074 -90)
		(property "Reference" "VIA18"
			(at 0 0 270)
			(layer "F.SilkS")
			(hide yes)
			(effects
				(font
					(size 1.27 1.27)
				)
			)
		)
		(property "Value" "100OHM-8L-2D36MM-L16-GP"
			(at -3.4036 -0.4572 270)
			(unlocked yes)
			(layer "F.Fab")
			(hide yes)
			(effects
				(font
					(size 1.016 1.016)
					(thickness 0.1524)
				)
			)
		)
		(property "Device Type" "VIA-PCIE-4P-427097"
			(at -3.4036 -1.9812 270)
			(unlocked yes)
			(layer "F.Fab")
			(hide yes)
			(effects
				(font
					(size 1.016 1.016)
					(thickness 0.1524)
				)
			)
		)
		(duplicate_pad_numbers_are_jumpers no)
		(fp_rect
			(start -2.1336 0.4826)
			(end 2.1336 -0.4826)
			(stroke
				(width 0)
				(type default)
			)
			(fill no)
			(layer "F.CrtYd")
		)
		(fp_rect
			(start -2.1336 0.4826)
			(end 2.1336 -0.4826)
			(stroke
				(width 0)
				(type default)
			)
			(fill no)
			(layer "F.Fab")
		)
		(pad "1" thru_hole circle
			(at -1.651 0 270)
			(size 0.508 0.508)
			(drill 0.254)
			(layers "*.Cu" "*.Mask")
			(remove_unused_layers no)
			(net "GND")
			(clearance 0.2286)
			(thermal_gap 0.2286)
		)
		(pad "2" thru_hole circle
			(at -0.635 0 270)
			(size 0.508 0.508)
			(drill 0.254)
			(layers "*.Cu" "*.Mask")
			(remove_unused_layers no)
			(net "PHY_DRV_B_TO_SCC_B_8_DP")
			(clearance 0.2286)
			(thermal_gap 0.2286)
		)
		(pad "3" thru_hole circle
			(at 0.635 0 270)
			(size 0.508 0.508)
			(drill 0.254)
			(layers "*.Cu" "*.Mask")
			(remove_unused_layers no)
			(net "PHY_DRV_B_TO_SCC_B_8_DN")
			(clearance 0.2286)
			(thermal_gap 0.2286)
		)
		(pad "4" thru_hole circle
			(at 1.651 0 270)
			(size 0.508 0.508)
			(drill 0.254)
			(layers "*.Cu" "*.Mask")
			(remove_unused_layers no)
			(net "GND")
			(clearance 0.2286)
			(thermal_gap 0.2286)
		)
	)
	(footprint ""
		(layer "F.Cu")
		(at 326.992996 -364.236 -90)
		(property "Reference" "R951"
			(at 0 0 270)
			(layer "F.SilkS")
			(hide yes)
			(effects
				(font
					(size 1.27 1.27)
				)
			)
		)
		(property "Value" "10KR2F-2-GP"
			(at 0.064008 -3.993896 270)
			(unlocked yes)
			(layer "F.Fab")
			(hide yes)
			(effects
				(font
					(size 1.016 1.016)
					(thickness 0.1524)
				)
			)
		)
		(property "Device Type" "R402H16"
			(at 0.064008 -5.517896 270)
			(unlocked yes)
			(layer "F.Fab")
			(hide yes)
			(effects
				(font
					(size 1.016 1.016)
					(thickness 0.1524)
				)
			)
		)
		(duplicate_pad_numbers_are_jumpers no)
		(fp_line
			(start -0.508 -0.9398)
			(end -0.508 0.9398)
			(stroke
				(width 0.1524)
				(type default)
			)
			(layer "F.SilkS")
		)
		(fp_line
			(start 0.508 -0.9398)
			(end -0.508 -0.9398)
			(stroke
				(width 0.1524)
				(type default)
			)
			(layer "F.SilkS")
		)
		(fp_rect
			(start -0.508 0.9398)
			(end 0.508 -0.9398)
			(stroke
				(width 0)
				(type default)
			)
			(fill no)
			(layer "F.CrtYd")
		)
		(fp_rect
			(start -0.508 0.9398)
			(end 0.508 -0.9398)
			(stroke
				(width 0)
				(type default)
			)
			(fill no)
			(layer "F.Fab")
		)
		(pad "1" smd custom
			(at 0 -0.4445 270)
			(size 0.1397 0.1397)
			(layers "F.Cu" "F.Mask" "F.Paste")
			(net "GND")
			(options
				(clearance outline)
				(anchor circle)
			)
			(primitives
				(gr_poly
					(pts
						(arc
							(start -0.1778 -0.2794)
							(mid -0.249642 -0.249642)
							(end -0.2794 -0.1778)
						)
						(arc
							(start -0.2794 0.1778)
							(mid -0.249642 0.249642)
							(end -0.1778 0.2794)
						)
						(arc
							(start 0.1778 0.2794)
							(mid 0.249642 0.249642)
							(end 0.2794 0.1778)
						)
						(arc
							(start 0.2794 -0.1778)
							(mid 0.249642 -0.249642)
							(end 0.1778 -0.2794)
						)
					)
					(width 0)
					(fill yes)
				)
			)
		)
		(pad "2" smd custom
			(at 0 0.4445 270)
			(size 0.1397 0.1397)
			(layers "F.Cu" "F.Mask" "F.Paste")
			(net "FANTACH_F2")
			(options
				(clearance outline)
				(anchor circle)
			)
			(primitives
				(gr_poly
					(pts
						(arc
							(start -0.1778 -0.2794)
							(mid -0.249642 -0.249642)
							(end -0.2794 -0.1778)
						)
						(arc
							(start -0.2794 0.1778)
							(mid -0.249642 0.249642)
							(end -0.1778 0.2794)
						)
						(arc
							(start 0.1778 0.2794)
							(mid 0.249642 0.249642)
							(end 0.2794 0.1778)
						)
						(arc
							(start 0.2794 -0.1778)
							(mid 0.249642 -0.249642)
							(end 0.1778 -0.2794)
						)
					)
					(width 0)
					(fill yes)
				)
			)
		)
	)
	(footprint ""
		(layer "F.Cu")
		(at 430.403 -246.761 180)
		(property "Reference" "R315"
			(at 0 0 180)
			(layer "F.SilkS")
			(hide yes)
			(effects
				(font
					(size 1.27 1.27)
				)
			)
		)
		(property "Value" "0R2J-2-GP"
			(at 0.064008 -3.993896 180)
			(unlocked yes)
			(layer "F.Fab")
			(hide yes)
			(effects
				(font
					(size 1.016 1.016)
					(thickness 0.1524)
				)
			)
		)
		(property "Device Type" "R402H16"
			(at 0.064008 -5.517896 180)
			(unlocked yes)
			(layer "F.Fab")
			(hide yes)
			(effects
				(font
					(size 1.016 1.016)
					(thickness 0.1524)
				)
			)
		)
		(duplicate_pad_numbers_are_jumpers no)
		(fp_line
			(start 0.508 -0.9398)
			(end -0.508 -0.9398)
			(stroke
				(width 0.1524)
				(type default)
			)
			(layer "F.SilkS")
		)
		(fp_line
			(start -0.508 -0.9398)
			(end -0.508 0.9398)
			(stroke
				(width 0.1524)
				(type default)
			)
			(layer "F.SilkS")
		)
		(fp_rect
			(start -0.508 0.9398)
			(end 0.508 -0.9398)
			(stroke
				(width 0)
				(type default)
			)
			(fill no)
			(layer "F.CrtYd")
		)
		(fp_rect
			(start -0.508 0.9398)
			(end 0.508 -0.9398)
			(stroke
				(width 0)
				(type default)
			)
			(fill no)
			(layer "F.Fab")
		)
		(pad "1" smd custom
			(at 0 -0.4445 180)
			(size 0.1397 0.1397)
			(layers "F.Cu" "F.Mask" "F.Paste")
			(net "SW_HDD_G9")
			(options
				(clearance outline)
				(anchor circle)
			)
			(primitives
				(gr_poly
					(pts
						(arc
							(start -0.1778 -0.2794)
							(mid -0.249642 -0.249642)
							(end -0.2794 -0.1778)
						)
						(arc
							(start -0.2794 0.1778)
							(mid -0.249642 0.249642)
							(end -0.1778 0.2794)
						)
						(arc
							(start 0.1778 0.2794)
							(mid 0.249642 0.249642)
							(end 0.2794 0.1778)
						)
						(arc
							(start 0.2794 -0.1778)
							(mid 0.249642 -0.249642)
							(end 0.1778 -0.2794)
						)
					)
					(width 0)
					(fill yes)
				)
			)
		)
		(pad "2" smd custom
			(at 0 0.4445 180)
			(size 0.1397 0.1397)
			(layers "F.Cu" "F.Mask" "F.Paste")
			(net "SW_HDD_R9")
			(options
				(clearance outline)
				(anchor circle)
			)
			(primitives
				(gr_poly
					(pts
						(arc
							(start -0.1778 -0.2794)
							(mid -0.249642 -0.249642)
							(end -0.2794 -0.1778)
						)
						(arc
							(start -0.2794 0.1778)
							(mid -0.249642 0.249642)
							(end -0.1778 0.2794)
						)
						(arc
							(start 0.1778 0.2794)
							(mid 0.249642 0.249642)
							(end 0.2794 0.1778)
						)
						(arc
							(start 0.2794 -0.1778)
							(mid 0.249642 -0.249642)
							(end 0.1778 -0.2794)
						)
					)
					(width 0)
					(fill yes)
				)
			)
		)
	)
	(footprint ""
		(layer "F.Cu")
		(at 362.966 -262.001 -90)
		(property "Reference" "R270"
			(at 0 0 270)
			(layer "F.SilkS")
			(hide yes)
			(effects
				(font
					(size 1.27 1.27)
				)
			)
		)
		(property "Value" "2R6F-GP"
			(at -0.0508 -4.8514 270)
			(unlocked yes)
			(layer "F.Fab")
			(hide yes)
			(effects
				(font
					(size 1.016 1.016)
					(thickness 0.1524)
				)
			)
		)
		(property "Device Type" "R1206H26"
			(at 0 -6.3754 270)
			(unlocked yes)
			(layer "F.Fab")
			(hide yes)
			(effects
				(font
					(size 1.016 1.016)
					(thickness 0.1524)
				)
			)
		)
		(duplicate_pad_numbers_are_jumpers no)
		(fp_line
			(start -1.016 2.2352)
			(end -1.016 -2.2352)
			(stroke
				(width 0.1524)
				(type default)
			)
			(layer "F.SilkS")
		)
		(fp_line
			(start 1.016 2.2352)
			(end -1.016 2.2352)
			(stroke
				(width 0.1524)
				(type default)
			)
			(layer "F.SilkS")
		)
		(fp_line
			(start -1.016 -2.2352)
			(end 1.016 -2.2352)
			(stroke
				(width 0.1524)
				(type default)
			)
			(layer "F.SilkS")
		)
		(fp_line
			(start 1.016 -2.2352)
			(end 1.016 2.2352)
			(stroke
				(width 0.1524)
				(type default)
			)
			(layer "F.SilkS")
		)
		(fp_rect
			(start -1.0922 2.3114)
			(end 1.0922 -2.3114)
			(stroke
				(width 0)
				(type default)
			)
			(fill no)
			(layer "F.CrtYd")
		)
		(fp_poly
			(pts
				(xy -1.0922 -2.3114) (xy 1.0922 -2.3114) (xy 1.0922 2.3114) (xy -1.0922 2.3114)
			)
			(stroke
				(width 0)
				(type default)
			)
			(fill no)
			(layer "F.Fab")
		)
		(pad "1" smd rect
			(at 0 -1.397 270)
			(size 1.651 1.27)
			(layers "F.Cu" "F.Mask" "F.Paste")
			(net "P5V_HDD7")
		)
		(pad "2" smd rect
			(at 0 1.397 270)
			(size 1.651 1.27)
			(layers "F.Cu" "F.Mask" "F.Paste")
			(net "5V_PRE_7")
		)
	)
	(footprint ""
		(layer "F.Cu")
		(at 85.471 -246.2276 -90)
		(property "Reference" "R198"
			(at 0 0 270)
			(layer "F.SilkS")
			(hide yes)
			(effects
				(font
					(size 1.27 1.27)
				)
			)
		)
		(property "Value" "0R2J-2-GP"
			(at 0.064008 -3.993896 270)
			(unlocked yes)
			(layer "F.Fab")
			(hide yes)
			(effects
				(font
					(size 1.016 1.016)
					(thickness 0.1524)
				)
			)
		)
		(property "Device Type" "R402H16"
			(at 0.064008 -5.517896 270)
			(unlocked yes)
			(layer "F.Fab")
			(hide yes)
			(effects
				(font
					(size 1.016 1.016)
					(thickness 0.1524)
				)
			)
		)
		(duplicate_pad_numbers_are_jumpers no)
		(fp_line
			(start -0.508 -0.9398)
			(end -0.508 0.9398)
			(stroke
				(width 0.1524)
				(type default)
			)
			(layer "F.SilkS")
		)
		(fp_line
			(start 0.508 -0.9398)
			(end -0.508 -0.9398)
			(stroke
				(width 0.1524)
				(type default)
			)
			(layer "F.SilkS")
		)
		(fp_rect
			(start -0.508 0.9398)
			(end 0.508 -0.9398)
			(stroke
				(width 0)
				(type default)
			)
			(fill no)
			(layer "F.CrtYd")
		)
		(fp_rect
			(start -0.508 0.9398)
			(end 0.508 -0.9398)
			(stroke
				(width 0)
				(type default)
			)
			(fill no)
			(layer "F.Fab")
		)
		(pad "1" smd custom
			(at 0 -0.4445 270)
			(size 0.1397 0.1397)
			(layers "F.Cu" "F.Mask" "F.Paste")
			(net "DRIVE_B_2_PWR")
			(options
				(clearance outline)
				(anchor circle)
			)
			(primitives
				(gr_poly
					(pts
						(arc
							(start -0.1778 -0.2794)
							(mid -0.249642 -0.249642)
							(end -0.2794 -0.1778)
						)
						(arc
							(start -0.2794 0.1778)
							(mid -0.249642 0.249642)
							(end -0.1778 0.2794)
						)
						(arc
							(start 0.1778 0.2794)
							(mid 0.249642 0.249642)
							(end 0.2794 0.1778)
						)
						(arc
							(start 0.2794 -0.1778)
							(mid 0.249642 -0.249642)
							(end 0.1778 -0.2794)
						)
					)
					(width 0)
					(fill yes)
				)
			)
		)
		(pad "2" smd custom
			(at 0 0.4445 270)
			(size 0.1397 0.1397)
			(layers "F.Cu" "F.Mask" "F.Paste")
			(net "SW_PWR_R_HDD2")
			(options
				(clearance outline)
				(anchor circle)
			)
			(primitives
				(gr_poly
					(pts
						(arc
							(start -0.1778 -0.2794)
							(mid -0.249642 -0.249642)
							(end -0.2794 -0.1778)
						)
						(arc
							(start -0.2794 0.1778)
							(mid -0.249642 0.249642)
							(end -0.1778 0.2794)
						)
						(arc
							(start 0.1778 0.2794)
							(mid 0.249642 0.249642)
							(end 0.2794 0.1778)
						)
						(arc
							(start 0.2794 -0.1778)
							(mid 0.249642 -0.249642)
							(end 0.1778 -0.2794)
						)
					)
					(width 0)
					(fill yes)
				)
			)
		)
	)
	(footprint ""
		(layer "F.Cu")
		(at 403.351746 -212.390228 -90)
		(property "Reference" "R293"
			(at 0 0 270)
			(layer "F.SilkS")
			(hide yes)
			(effects
				(font
					(size 1.27 1.27)
				)
			)
		)
		(property "Value" "4K7R2F-GP"
			(at 0.064008 -3.993896 270)
			(unlocked yes)
			(layer "F.Fab")
			(hide yes)
			(effects
				(font
					(size 1.016 1.016)
					(thickness 0.1524)
				)
			)
		)
		(property "Device Type" "R402H16"
			(at 0.064008 -5.517896 270)
			(unlocked yes)
			(layer "F.Fab")
			(hide yes)
			(effects
				(font
					(size 1.016 1.016)
					(thickness 0.1524)
				)
			)
		)
		(duplicate_pad_numbers_are_jumpers no)
		(fp_line
			(start -0.508 -0.9398)
			(end -0.508 0.9398)
			(stroke
				(width 0.1524)
				(type default)
			)
			(layer "F.SilkS")
		)
		(fp_line
			(start 0.508 -0.9398)
			(end -0.508 -0.9398)
			(stroke
				(width 0.1524)
				(type default)
			)
			(layer "F.SilkS")
		)
		(fp_rect
			(start -0.508 0.9398)
			(end 0.508 -0.9398)
			(stroke
				(width 0)
				(type default)
			)
			(fill no)
			(layer "F.CrtYd")
		)
		(fp_rect
			(start -0.508 0.9398)
			(end 0.508 -0.9398)
			(stroke
				(width 0)
				(type default)
			)
			(fill no)
			(layer "F.Fab")
		)
		(pad "1" smd custom
			(at 0 -0.4445 270)
			(size 0.1397 0.1397)
			(layers "F.Cu" "F.Mask" "F.Paste")
			(net "DRIVE_B_9_ACT")
			(options
				(clearance outline)
				(anchor circle)
			)
			(primitives
				(gr_poly
					(pts
						(arc
							(start -0.1778 -0.2794)
							(mid -0.249642 -0.249642)
							(end -0.2794 -0.1778)
						)
						(arc
							(start -0.2794 0.1778)
							(mid -0.249642 0.249642)
							(end -0.1778 0.2794)
						)
						(arc
							(start 0.1778 0.2794)
							(mid 0.249642 0.249642)
							(end 0.2794 0.1778)
						)
						(arc
							(start 0.2794 -0.1778)
							(mid 0.249642 -0.249642)
							(end 0.1778 -0.2794)
						)
					)
					(width 0)
					(fill yes)
				)
			)
		)
		(pad "2" smd custom
			(at 0 0.4445 270)
			(size 0.1397 0.1397)
			(layers "F.Cu" "F.Mask" "F.Paste")
			(net "GND")
			(options
				(clearance outline)
				(anchor circle)
			)
			(primitives
				(gr_poly
					(pts
						(arc
							(start -0.1778 -0.2794)
							(mid -0.249642 -0.249642)
							(end -0.2794 -0.1778)
						)
						(arc
							(start -0.2794 0.1778)
							(mid -0.249642 0.249642)
							(end -0.1778 0.2794)
						)
						(arc
							(start 0.1778 0.2794)
							(mid 0.249642 0.249642)
							(end 0.2794 0.1778)
						)
						(arc
							(start 0.2794 -0.1778)
							(mid 0.249642 -0.249642)
							(end 0.1778 -0.2794)
						)
					)
					(width 0)
					(fill yes)
				)
			)
		)
	)
	(footprint ""
		(layer "F.Cu")
		(at 220.853 -226.568 90)
		(property "Reference" "C3"
			(at 0 0 90)
			(layer "F.SilkS")
			(hide yes)
			(effects
				(font
					(size 1.27 1.27)
				)
			)
		)
		(property "Value" "SC1U16V3KX-5GP"
			(at 0 -2.8194 90)
			(unlocked yes)
			(layer "F.Fab")
			(hide yes)
			(effects
				(font
					(size 1.016 1.016)
					(thickness 0.1524)
				)
			)
		)
		(property "Device Type" "C603H36"
			(at 0 -4.3434 90)
			(unlocked yes)
			(layer "F.Fab")
			(hide yes)
			(effects
				(font
					(size 1.016 1.016)
					(thickness 0.1524)
				)
			)
		)
		(duplicate_pad_numbers_are_jumpers no)
		(fp_line
			(start 0.508 0)
			(end -0.508 0)
			(stroke
				(width 0.2032)
				(type default)
			)
			(layer "F.SilkS")
		)
		(fp_rect
			(start -0.5842 1.3335)
			(end 0.5842 -1.3335)
			(stroke
				(width 0)
				(type default)
			)
			(fill no)
			(layer "F.CrtYd")
		)
		(fp_rect
			(start -0.5842 1.3335)
			(end 0.5842 -1.3335)
			(stroke
				(width 0)
				(type default)
			)
			(fill no)
			(layer "F.Fab")
		)
		(pad "1" smd custom
			(at 0 -0.762 90)
			(size 0.2159 0.2159)
			(layers "F.Cu" "F.Mask" "F.Paste")
			(net "P3V3_STBY_B")
			(options
				(clearance outline)
				(anchor circle)
			)
			(primitives
				(gr_poly
					(pts
						(arc
							(start -0.3302 -0.4318)
							(mid -0.402042 -0.402042)
							(end -0.4318 -0.3302)
						)
						(arc
							(start -0.4318 0.3302)
							(mid -0.402042 0.402042)
							(end -0.3302 0.4318)
						)
						(arc
							(start 0.3302 0.4318)
							(mid 0.402042 0.402042)
							(end 0.4318 0.3302)
						)
						(arc
							(start 0.4318 -0.3302)
							(mid 0.402042 -0.402042)
							(end 0.3302 -0.4318)
						)
					)
					(width 0)
					(fill yes)
				)
			)
		)
		(pad "2" smd custom
			(at 0 0.762 90)
			(size 0.2159 0.2159)
			(layers "F.Cu" "F.Mask" "F.Paste")
			(net "GND")
			(options
				(clearance outline)
				(anchor circle)
			)
			(primitives
				(gr_poly
					(pts
						(arc
							(start -0.3302 -0.4318)
							(mid -0.402042 -0.402042)
							(end -0.4318 -0.3302)
						)
						(arc
							(start -0.4318 0.3302)
							(mid -0.402042 0.402042)
							(end -0.3302 0.4318)
						)
						(arc
							(start 0.3302 0.4318)
							(mid 0.402042 0.402042)
							(end 0.4318 0.3302)
						)
						(arc
							(start 0.4318 -0.3302)
							(mid 0.402042 -0.402042)
							(end 0.3302 -0.4318)
						)
					)
					(width 0)
					(fill yes)
				)
			)
		)
	)
	(footprint ""
		(layer "F.Cu")
		(at 426.2882 -134.6454 90)
		(property "Reference" "R560"
			(at 0 0 90)
			(layer "F.SilkS")
			(hide yes)
			(effects
				(font
					(size 1.27 1.27)
				)
			)
		)
		(property "Value" "4K7R2J-2-GP"
			(at 0.064008 -3.993896 90)
			(unlocked yes)
			(layer "F.Fab")
			(hide yes)
			(effects
				(font
					(size 1.016 1.016)
					(thickness 0.1524)
				)
			)
		)
		(property "Device Type" "R402H16"
			(at 0.064008 -5.517896 90)
			(unlocked yes)
			(layer "F.Fab")
			(hide yes)
			(effects
				(font
					(size 1.016 1.016)
					(thickness 0.1524)
				)
			)
		)
		(duplicate_pad_numbers_are_jumpers no)
		(fp_line
			(start 0.508 -0.9398)
			(end -0.508 -0.9398)
			(stroke
				(width 0.1524)
				(type default)
			)
			(layer "F.SilkS")
		)
		(fp_line
			(start -0.508 -0.9398)
			(end -0.508 0.9398)
			(stroke
				(width 0.1524)
				(type default)
			)
			(layer "F.SilkS")
		)
		(fp_rect
			(start -0.508 0.9398)
			(end 0.508 -0.9398)
			(stroke
				(width 0)
				(type default)
			)
			(fill no)
			(layer "F.CrtYd")
		)
		(fp_rect
			(start -0.508 0.9398)
			(end 0.508 -0.9398)
			(stroke
				(width 0)
				(type default)
			)
			(fill no)
			(layer "F.Fab")
		)
		(pad "1" smd custom
			(at 0 -0.4445 90)
			(size 0.1397 0.1397)
			(layers "F.Cu" "F.Mask" "F.Paste")
			(net "P12V_B")
			(options
				(clearance outline)
				(anchor circle)
			)
			(primitives
				(gr_poly
					(pts
						(arc
							(start -0.1778 -0.2794)
							(mid -0.249642 -0.249642)
							(end -0.2794 -0.1778)
						)
						(arc
							(start -0.2794 0.1778)
							(mid -0.249642 0.249642)
							(end -0.1778 0.2794)
						)
						(arc
							(start 0.1778 0.2794)
							(mid 0.249642 0.249642)
							(end 0.2794 0.1778)
						)
						(arc
							(start 0.2794 -0.1778)
							(mid 0.249642 -0.249642)
							(end 0.1778 -0.2794)
						)
					)
					(width 0)
					(fill yes)
				)
			)
		)
		(pad "2" smd custom
			(at 0 0.4445 90)
			(size 0.1397 0.1397)
			(layers "F.Cu" "F.Mask" "F.Paste")
			(net "SW_HDD_P21")
			(options
				(clearance outline)
				(anchor circle)
			)
			(primitives
				(gr_poly
					(pts
						(arc
							(start -0.1778 -0.2794)
							(mid -0.249642 -0.249642)
							(end -0.2794 -0.1778)
						)
						(arc
							(start -0.2794 0.1778)
							(mid -0.249642 0.249642)
							(end -0.1778 0.2794)
						)
						(arc
							(start 0.1778 0.2794)
							(mid 0.249642 0.249642)
							(end 0.2794 0.1778)
						)
						(arc
							(start 0.2794 -0.1778)
							(mid 0.249642 -0.249642)
							(end 0.1778 -0.2794)
						)
					)
					(width 0)
					(fill yes)
				)
			)
		)
	)
	(footprint ""
		(layer "F.Cu")
		(at 191.0588 -146.6342 180)
		(property "Reference" "R461"
			(at 0 0 180)
			(layer "F.SilkS")
			(hide yes)
			(effects
				(font
					(size 1.27 1.27)
				)
			)
		)
		(property "Value" "10KR2F-2-GP"
			(at 0.064008 -3.993896 180)
			(unlocked yes)
			(layer "F.Fab")
			(hide yes)
			(effects
				(font
					(size 1.016 1.016)
					(thickness 0.1524)
				)
			)
		)
		(property "Device Type" "R402H16"
			(at 0.064008 -5.517896 180)
			(unlocked yes)
			(layer "F.Fab")
			(hide yes)
			(effects
				(font
					(size 1.016 1.016)
					(thickness 0.1524)
				)
			)
		)
		(duplicate_pad_numbers_are_jumpers no)
		(fp_line
			(start 0.508 -0.9398)
			(end -0.508 -0.9398)
			(stroke
				(width 0.1524)
				(type default)
			)
			(layer "F.SilkS")
		)
		(fp_line
			(start -0.508 -0.9398)
			(end -0.508 0.9398)
			(stroke
				(width 0.1524)
				(type default)
			)
			(layer "F.SilkS")
		)
		(fp_rect
			(start -0.508 0.9398)
			(end 0.508 -0.9398)
			(stroke
				(width 0)
				(type default)
			)
			(fill no)
			(layer "F.CrtYd")
		)
		(fp_rect
			(start -0.508 0.9398)
			(end 0.508 -0.9398)
			(stroke
				(width 0)
				(type default)
			)
			(fill no)
			(layer "F.Fab")
		)
		(pad "1" smd custom
			(at 0 -0.4445 180)
			(size 0.1397 0.1397)
			(layers "F.Cu" "F.Mask" "F.Paste")
			(net "P3V3_STBY_B")
			(options
				(clearance outline)
				(anchor circle)
			)
			(primitives
				(gr_poly
					(pts
						(arc
							(start -0.1778 -0.2794)
							(mid -0.249642 -0.249642)
							(end -0.2794 -0.1778)
						)
						(arc
							(start -0.2794 0.1778)
							(mid -0.249642 0.249642)
							(end -0.1778 0.2794)
						)
						(arc
							(start 0.1778 0.2794)
							(mid 0.249642 0.249642)
							(end 0.2794 0.1778)
						)
						(arc
							(start 0.2794 -0.1778)
							(mid 0.249642 -0.249642)
							(end 0.1778 -0.2794)
						)
					)
					(width 0)
					(fill yes)
				)
			)
		)
		(pad "2" smd custom
			(at 0 0.4445 180)
			(size 0.1397 0.1397)
			(layers "F.Cu" "F.Mask" "F.Paste")
			(net "HDD_PRSNT_17")
			(options
				(clearance outline)
				(anchor circle)
			)
			(primitives
				(gr_poly
					(pts
						(arc
							(start -0.1778 -0.2794)
							(mid -0.249642 -0.249642)
							(end -0.2794 -0.1778)
						)
						(arc
							(start -0.2794 0.1778)
							(mid -0.249642 0.249642)
							(end -0.1778 0.2794)
						)
						(arc
							(start 0.1778 0.2794)
							(mid 0.249642 0.249642)
							(end 0.2794 0.1778)
						)
						(arc
							(start 0.2794 -0.1778)
							(mid 0.249642 -0.249642)
							(end 0.1778 -0.2794)
						)
					)
					(width 0)
					(fill yes)
				)
			)
		)
	)
	(footprint ""
		(layer "F.Cu")
		(at 280.444448 -354.399342 -90)
		(property "Reference" "R1076"
			(at 0 0 270)
			(layer "F.SilkS")
			(hide yes)
			(effects
				(font
					(size 1.27 1.27)
				)
			)
		)
		(property "Value" "0R2J-2-GP"
			(at 0.064008 -3.993896 270)
			(unlocked yes)
			(layer "F.Fab")
			(hide yes)
			(effects
				(font
					(size 1.016 1.016)
					(thickness 0.1524)
				)
			)
		)
		(property "Device Type" "R402H16"
			(at 0.064008 -5.517896 270)
			(unlocked yes)
			(layer "F.Fab")
			(hide yes)
			(effects
				(font
					(size 1.016 1.016)
					(thickness 0.1524)
				)
			)
		)
		(duplicate_pad_numbers_are_jumpers no)
		(fp_line
			(start -0.508 -0.9398)
			(end -0.508 0.9398)
			(stroke
				(width 0.1524)
				(type default)
			)
			(layer "F.SilkS")
		)
		(fp_line
			(start 0.508 -0.9398)
			(end -0.508 -0.9398)
			(stroke
				(width 0.1524)
				(type default)
			)
			(layer "F.SilkS")
		)
		(fp_rect
			(start -0.508 0.9398)
			(end 0.508 -0.9398)
			(stroke
				(width 0)
				(type default)
			)
			(fill no)
			(layer "F.CrtYd")
		)
		(fp_rect
			(start -0.508 0.9398)
			(end 0.508 -0.9398)
			(stroke
				(width 0)
				(type default)
			)
			(fill no)
			(layer "F.Fab")
		)
		(pad "1" smd custom
			(at 0 -0.4445 270)
			(size 0.1397 0.1397)
			(layers "F.Cu" "F.Mask" "F.Paste")
			(net "MAX31790_B_SCL")
			(options
				(clearance outline)
				(anchor circle)
			)
			(primitives
				(gr_poly
					(pts
						(arc
							(start -0.1778 -0.2794)
							(mid -0.249642 -0.249642)
							(end -0.2794 -0.1778)
						)
						(arc
							(start -0.2794 0.1778)
							(mid -0.249642 0.249642)
							(end -0.1778 0.2794)
						)
						(arc
							(start 0.1778 0.2794)
							(mid 0.249642 0.249642)
							(end 0.2794 0.1778)
						)
						(arc
							(start 0.2794 -0.1778)
							(mid 0.249642 -0.249642)
							(end 0.1778 -0.2794)
						)
					)
					(width 0)
					(fill yes)
				)
			)
		)
		(pad "2" smd custom
			(at 0 0.4445 270)
			(size 0.1397 0.1397)
			(layers "F.Cu" "F.Mask" "F.Paste")
			(net "I2C_DPB_B_SCL_BUF")
			(options
				(clearance outline)
				(anchor circle)
			)
			(primitives
				(gr_poly
					(pts
						(arc
							(start -0.1778 -0.2794)
							(mid -0.249642 -0.249642)
							(end -0.2794 -0.1778)
						)
						(arc
							(start -0.2794 0.1778)
							(mid -0.249642 0.249642)
							(end -0.1778 0.2794)
						)
						(arc
							(start 0.1778 0.2794)
							(mid 0.249642 0.249642)
							(end 0.2794 0.1778)
						)
						(arc
							(start 0.2794 -0.1778)
							(mid 0.249642 -0.249642)
							(end 0.1778 -0.2794)
						)
					)
					(width 0)
					(fill yes)
				)
			)
		)
	)
	(footprint ""
		(layer "F.Cu")
		(at 27.298396 -370.9416 180)
		(property "Reference" "C710"
			(at 0 0 180)
			(layer "F.SilkS")
			(hide yes)
			(effects
				(font
					(size 1.27 1.27)
				)
			)
		)
		(property "Value" "SCD1U16V2KX-3GP"
			(at 1.1811 -2.7051 180)
			(unlocked yes)
			(layer "F.Fab")
			(hide yes)
			(effects
				(font
					(size 1.016 1.016)
					(thickness 0.1524)
				)
			)
		)
		(property "Device Type" "C402H22"
			(at 1.1811 -4.2291 180)
			(unlocked yes)
			(layer "F.Fab")
			(hide yes)
			(effects
				(font
					(size 1.016 1.016)
					(thickness 0.1524)
				)
			)
		)
		(duplicate_pad_numbers_are_jumpers no)
		(fp_rect
			(start -0.4318 0.9525)
			(end 0.4318 -0.9525)
			(stroke
				(width 0)
				(type default)
			)
			(fill no)
			(layer "F.CrtYd")
		)
		(fp_rect
			(start -0.4318 0.9525)
			(end 0.4318 -0.9525)
			(stroke
				(width 0)
				(type default)
			)
			(fill no)
			(layer "F.Fab")
		)
		(pad "1" smd custom
			(at 0 -0.4445 180)
			(size 0.1524 0.1524)
			(layers "F.Cu" "F.Mask" "F.Paste")
			(net "P3V3_IN")
			(options
				(clearance outline)
				(anchor circle)
			)
			(primitives
				(gr_poly
					(pts
						(arc
							(start 0.3048 -0.2032)
							(mid 0.275042 -0.275042)
							(end 0.2032 -0.3048)
						)
						(arc
							(start -0.2032 -0.3048)
							(mid -0.275042 -0.275042)
							(end -0.3048 -0.2032)
						)
						(arc
							(start -0.3048 0.2032)
							(mid -0.275042 0.275042)
							(end -0.2032 0.3048)
						)
						(arc
							(start 0.2032 0.3048)
							(mid 0.275042 0.275042)
							(end 0.3048 0.2032)
						)
					)
					(width 0)
					(fill yes)
				)
			)
		)
		(pad "2" smd custom
			(at 0 0.4445 180)
			(size 0.1524 0.1524)
			(layers "F.Cu" "F.Mask" "F.Paste")
			(net "GND")
			(options
				(clearance outline)
				(anchor circle)
			)
			(primitives
				(gr_poly
					(pts
						(arc
							(start 0.3048 -0.2032)
							(mid 0.275042 -0.275042)
							(end 0.2032 -0.3048)
						)
						(arc
							(start -0.2032 -0.3048)
							(mid -0.275042 -0.275042)
							(end -0.3048 -0.2032)
						)
						(arc
							(start -0.3048 0.2032)
							(mid -0.275042 0.275042)
							(end -0.2032 0.3048)
						)
						(arc
							(start 0.2032 0.3048)
							(mid 0.275042 0.275042)
							(end 0.3048 0.2032)
						)
					)
					(width 0)
					(fill yes)
				)
			)
		)
	)
	(footprint ""
		(layer "F.Cu")
		(at 245.888002 -132.958078 -90)
		(property "Reference" "U23"
			(at 0 0 270)
			(layer "F.SilkS")
			(hide yes)
			(effects
				(font
					(size 1.27 1.27)
				)
			)
		)
		(property "Value" "PCA9511ADP-T-GP"
			(at 0 -13.1572 270)
			(unlocked yes)
			(layer "F.Fab")
			(hide yes)
			(effects
				(font
					(size 1.016 1.016)
					(thickness 0.1524)
				)
			)
		)
		(property "Device Type" "SSOIC8-2H44"
			(at 0 -15.1892 270)
			(unlocked yes)
			(layer "F.Fab")
			(hide yes)
			(effects
				(font
					(size 1.016 1.016)
					(thickness 0.1524)
				)
			)
		)
		(duplicate_pad_numbers_are_jumpers no)
		(fp_line
			(start -1.7018 1.0414)
			(end -1.7018 2.9718)
			(stroke
				(width 0.635)
				(type default)
			)
			(layer "F.SilkS")
		)
		(fp_line
			(start -1.9304 1.016)
			(end -1.9304 -1.016)
			(stroke
				(width 0.1524)
				(type default)
			)
			(layer "F.SilkS")
		)
		(fp_line
			(start 1.0922 1.016)
			(end -1.9304 1.016)
			(stroke
				(width 0.1524)
				(type default)
			)
			(layer "F.SilkS")
		)
		(fp_line
			(start -1.524 0)
			(end -1.9304 0.4064)
			(stroke
				(width 0.1524)
				(type default)
			)
			(layer "F.SilkS")
		)
		(fp_line
			(start -1.524 0)
			(end -1.9304 -0.4064)
			(stroke
				(width 0.1524)
				(type default)
			)
			(layer "F.SilkS")
		)
		(fp_line
			(start -1.9304 -1.016)
			(end 1.0922 -1.016)
			(stroke
				(width 0.1524)
				(type default)
			)
			(layer "F.SilkS")
		)
		(fp_line
			(start 1.0922 -1.016)
			(end 1.0922 1.016)
			(stroke
				(width 0.1524)
				(type default)
			)
			(layer "F.SilkS")
		)
		(fp_poly
			(pts
				(xy -1.1938 -1.016) (xy 1.0922 -1.016) (xy 1.0922 1.016) (xy -1.1938 1.016)
			)
			(stroke
				(width 0)
				(type default)
			)
			(fill yes)
			(layer "F.SilkS")
		)
		(fp_rect
			(start -2.0066 3.3401)
			(end 2.0066 -3.3401)
			(stroke
				(width 0)
				(type default)
			)
			(fill no)
			(layer "F.CrtYd")
		)
		(fp_poly
			(pts
				(xy -2.0066 -3.3401) (xy 2.0066 -3.3401) (xy 2.0066 3.3401) (xy -2.0066 3.3401)
			)
			(stroke
				(width 0)
				(type default)
			)
			(fill no)
			(layer "F.Fab")
		)
		(pad "1" smd rect
			(at -0.97536 2.0701 270)
			(size 0.4064 1.524)
			(layers "F.Cu" "F.Mask" "F.Paste")
			(net "I2C_DPB_BUFF_EN")
		)
		(pad "2" smd rect
			(at -0.32512 2.0701 270)
			(size 0.4064 1.524)
			(layers "F.Cu" "F.Mask" "F.Paste")
			(net "I2C_DPB_B_SCL_BUF")
		)
		(pad "3" smd rect
			(at 0.32512 2.0701 270)
			(size 0.4064 1.524)
			(layers "F.Cu" "F.Mask" "F.Paste")
			(net "I2C_DPB_B_SCL")
		)
		(pad "4" smd rect
			(at 0.97536 2.0701 270)
			(size 0.4064 1.524)
			(layers "F.Cu" "F.Mask" "F.Paste")
			(net "GND")
		)
		(pad "5" smd rect
			(at 0.97536 -2.0701 270)
			(size 0.4064 1.524)
			(layers "F.Cu" "F.Mask" "F.Paste")
			(net "I2C_DPB_BUFF_READY")
		)
		(pad "6" smd rect
			(at 0.32512 -2.0701 270)
			(size 0.4064 1.524)
			(layers "F.Cu" "F.Mask" "F.Paste")
			(net "I2C_DPB_B_SDA")
		)
		(pad "7" smd rect
			(at -0.32512 -2.0701 270)
			(size 0.4064 1.524)
			(layers "F.Cu" "F.Mask" "F.Paste")
			(net "I2C_DPB_B_SDA_BUF")
		)
		(pad "8" smd rect
			(at -0.97536 -2.0701 270)
			(size 0.4064 1.524)
			(layers "F.Cu" "F.Mask" "F.Paste")
			(net "P3V3_STBY_B")
		)
	)
	(footprint ""
		(layer "F.Cu")
		(at 355.139752 -248.750074 -90)
		(property "Reference" "VIA16"
			(at 0 0 270)
			(layer "F.SilkS")
			(hide yes)
			(effects
				(font
					(size 1.27 1.27)
				)
			)
		)
		(property "Value" "100OHM-8L-2D36MM-L16-GP"
			(at -3.4036 -0.4572 270)
			(unlocked yes)
			(layer "F.Fab")
			(hide yes)
			(effects
				(font
					(size 1.016 1.016)
					(thickness 0.1524)
				)
			)
		)
		(property "Device Type" "VIA-PCIE-4P-427097"
			(at -3.4036 -1.9812 270)
			(unlocked yes)
			(layer "F.Fab")
			(hide yes)
			(effects
				(font
					(size 1.016 1.016)
					(thickness 0.1524)
				)
			)
		)
		(duplicate_pad_numbers_are_jumpers no)
		(fp_rect
			(start -2.1336 0.4826)
			(end 2.1336 -0.4826)
			(stroke
				(width 0)
				(type default)
			)
			(fill no)
			(layer "F.CrtYd")
		)
		(fp_rect
			(start -2.1336 0.4826)
			(end 2.1336 -0.4826)
			(stroke
				(width 0)
				(type default)
			)
			(fill no)
			(layer "F.Fab")
		)
		(pad "1" thru_hole circle
			(at -1.651 0 270)
			(size 0.508 0.508)
			(drill 0.254)
			(layers "*.Cu" "*.Mask")
			(remove_unused_layers no)
			(net "GND")
			(clearance 0.2286)
			(thermal_gap 0.2286)
		)
		(pad "2" thru_hole circle
			(at -0.635 0 270)
			(size 0.508 0.508)
			(drill 0.254)
			(layers "*.Cu" "*.Mask")
			(remove_unused_layers no)
			(net "PHY_DRV_B_TO_SCC_B_7_DP")
			(clearance 0.2286)
			(thermal_gap 0.2286)
		)
		(pad "3" thru_hole circle
			(at 0.635 0 270)
			(size 0.508 0.508)
			(drill 0.254)
			(layers "*.Cu" "*.Mask")
			(remove_unused_layers no)
			(net "PHY_DRV_B_TO_SCC_B_7_DN")
			(clearance 0.2286)
			(thermal_gap 0.2286)
		)
		(pad "4" thru_hole circle
			(at 1.651 0 270)
			(size 0.508 0.508)
			(drill 0.254)
			(layers "*.Cu" "*.Mask")
			(remove_unused_layers no)
			(net "GND")
			(clearance 0.2286)
			(thermal_gap 0.2286)
		)
	)
	(footprint ""
		(layer "F.Cu")
		(at 393.674854 -63.799974)
		(property "Reference" ""
			(at 0 0 0)
			(layer "F.SilkS")
			(hide yes)
			(effects
				(font
					(size 1.27 1.27)
				)
			)
		)
		(property "Value" "*"
			(at -8.398764 -8.057642 0)
			(unlocked yes)
			(layer "F.Fab")
			(hide yes)
			(effects
				(font
					(size 1.016 1.016)
					(thickness 0.1524)
				)
			)
		)
		(duplicate_pad_numbers_are_jumpers no)
		(fp_poly
			(pts
				(arc
					(start 7.3152 0)
					(mid 0 7.3152)
					(end -7.3152 0)
				)
				(arc
					(start -7.3152 -5.9944)
					(mid 0 -13.3096)
					(end 7.3152 -5.9944)
				)
			)
			(stroke
				(width 0)
				(type default)
			)
			(fill no)
			(layer "B.CrtYd")
		)
		(fp_poly
			(pts
				(arc
					(start 7.3152 0)
					(mid 0 7.3152)
					(end -7.3152 0)
				)
				(arc
					(start -7.3152 -5.9944)
					(mid 0 -13.3096)
					(end 7.3152 -5.9944)
				)
			)
			(stroke
				(width 0)
				(type default)
			)
			(fill no)
			(layer "F.CrtYd")
		)
		(fp_poly
			(pts
				(arc
					(start 7.3152 0)
					(mid 0 7.3152)
					(end -7.3152 0)
				)
				(arc
					(start -7.3152 -5.9944)
					(mid 0 -13.3096)
					(end 7.3152 -5.9944)
				)
			)
			(stroke
				(width 0)
				(type default)
			)
			(fill no)
			(layer "B.Fab")
		)
		(fp_poly
			(pts
				(arc
					(start 7.3152 0)
					(mid 0 7.3152)
					(end -7.3152 0)
				)
				(arc
					(start -7.3152 -5.9944)
					(mid 0 -13.3096)
					(end 7.3152 -5.9944)
				)
			)
			(stroke
				(width 0)
				(type default)
			)
			(fill no)
			(layer "F.Fab")
		)
		(pad "1" thru_hole oval
			(at 0 0)
			(size 14.0208 20.0152)
			(drill 0.0254
				(offset 0 -2.9972)
			)
			(layers "*.Cu" "*.Mask")
			(remove_unused_layers no)
			(net "Net_51")
			(clearance -1.002284)
			(thermal_gap 0.1524)
			(padstack
				(mode front_inner_back)
				(layer "Inner"
					(shape custom)
					(size 2.928012 2.928012)
					(options
						(anchor circle)
					)
					(primitives
						(gr_poly
							(pts
								(arc
									(start 4.571746 -2.084324)
									(mid 0.000333 7.430372)
									(end -4.571492 -2.084324)
								)
								(arc
									(start -4.571492 -2.084324)
									(mid -3.570296 -3.611977)
									(end -2.875026 -5.30098)
								)
								(arc
									(start -2.875026 -5.30098)
									(mid 0.000217 -7.43089)
									(end 2.87528 -5.30098)
								)
								(arc
									(start 2.87528 -5.30098)
									(mid 3.570511 -3.611956)
									(end 4.571746 -2.084324)
								)
							)
							(width 0)
							(fill yes)
						)
					)
					(clearance 0.1524)
				)
				(layer "B.Cu"
					(shape oval)
					(size 14.0208 20.0152)
					(offset 0 -2.9972)
					(clearance -1.002284)
				)
			)
		)
		(zone
			(layers "F.Cu" "B.Cu" "In1.Cu" "In2.Cu" "In3.Cu" "In4.Cu" "In5.Cu" "In6.Cu")
			(hatch none 0.5)
			(connect_pads
				(clearance 0)
			)
			(min_thickness 0.25)
			(keepout
				(tracks not_allowed)
				(vias allowed)
				(pads allowed)
				(copperpour not_allowed)
				(footprints allowed)
			)
			(placement
				(enabled no)
				(sheetname "")
			)
			(fill
				(thermal_gap 0.5)
				(thermal_bridge_width 0.5)
				(island_removal_mode 0)
			)
			(polygon
				(pts
					(arc
						(start 386.664454 -69.794374)
						(mid 393.674854 -76.804774)
						(end 400.685254 -69.794374)
					)
					(arc
						(start 400.685254 -63.799974)
						(mid 393.674854 -56.789574)
						(end 386.664454 -63.799974)
					)
				)
			)
		)
	)
	(footprint ""
		(layer "F.Cu")
		(at 398.907 -246.761 180)
		(property "Reference" "R299"
			(at 0 0 180)
			(layer "F.SilkS")
			(hide yes)
			(effects
				(font
					(size 1.27 1.27)
				)
			)
		)
		(property "Value" "0R2J-2-GP"
			(at 0.064008 -3.993896 180)
			(unlocked yes)
			(layer "F.Fab")
			(hide yes)
			(effects
				(font
					(size 1.016 1.016)
					(thickness 0.1524)
				)
			)
		)
		(property "Device Type" "R402H16"
			(at 0.064008 -5.517896 180)
			(unlocked yes)
			(layer "F.Fab")
			(hide yes)
			(effects
				(font
					(size 1.016 1.016)
					(thickness 0.1524)
				)
			)
		)
		(duplicate_pad_numbers_are_jumpers no)
		(fp_line
			(start 0.508 -0.9398)
			(end -0.508 -0.9398)
			(stroke
				(width 0.1524)
				(type default)
			)
			(layer "F.SilkS")
		)
		(fp_line
			(start -0.508 -0.9398)
			(end -0.508 0.9398)
			(stroke
				(width 0.1524)
				(type default)
			)
			(layer "F.SilkS")
		)
		(fp_rect
			(start -0.508 0.9398)
			(end 0.508 -0.9398)
			(stroke
				(width 0)
				(type default)
			)
			(fill no)
			(layer "F.CrtYd")
		)
		(fp_rect
			(start -0.508 0.9398)
			(end 0.508 -0.9398)
			(stroke
				(width 0)
				(type default)
			)
			(fill no)
			(layer "F.Fab")
		)
		(pad "1" smd custom
			(at 0 -0.4445 180)
			(size 0.1397 0.1397)
			(layers "F.Cu" "F.Mask" "F.Paste")
			(net "SW_HDD_G8")
			(options
				(clearance outline)
				(anchor circle)
			)
			(primitives
				(gr_poly
					(pts
						(arc
							(start -0.1778 -0.2794)
							(mid -0.249642 -0.249642)
							(end -0.2794 -0.1778)
						)
						(arc
							(start -0.2794 0.1778)
							(mid -0.249642 0.249642)
							(end -0.1778 0.2794)
						)
						(arc
							(start 0.1778 0.2794)
							(mid 0.249642 0.249642)
							(end 0.2794 0.1778)
						)
						(arc
							(start 0.2794 -0.1778)
							(mid 0.249642 -0.249642)
							(end 0.1778 -0.2794)
						)
					)
					(width 0)
					(fill yes)
				)
			)
		)
		(pad "2" smd custom
			(at 0 0.4445 180)
			(size 0.1397 0.1397)
			(layers "F.Cu" "F.Mask" "F.Paste")
			(net "SW_HDD_R8")
			(options
				(clearance outline)
				(anchor circle)
			)
			(primitives
				(gr_poly
					(pts
						(arc
							(start -0.1778 -0.2794)
							(mid -0.249642 -0.249642)
							(end -0.2794 -0.1778)
						)
						(arc
							(start -0.2794 0.1778)
							(mid -0.249642 0.249642)
							(end -0.1778 0.2794)
						)
						(arc
							(start 0.1778 0.2794)
							(mid 0.249642 0.249642)
							(end 0.2794 0.1778)
						)
						(arc
							(start 0.2794 -0.1778)
							(mid 0.249642 -0.249642)
							(end 0.1778 -0.2794)
						)
					)
					(width 0)
					(fill yes)
				)
			)
		)
	)
	(footprint ""
		(layer "F.Cu")
		(at 172.847 -99.314)
		(property "Reference" "R412"
			(at 0 0 0)
			(layer "F.SilkS")
			(hide yes)
			(effects
				(font
					(size 1.27 1.27)
				)
			)
		)
		(property "Value" "130R3F-GP"
			(at -0.0254 -2.5146 0)
			(unlocked yes)
			(layer "F.Fab")
			(hide yes)
			(effects
				(font
					(size 1.016 1.016)
					(thickness 0.1524)
				)
			)
		)
		(property "Device Type" "R603H22"
			(at -0.0254 -4.0386 0)
			(unlocked yes)
			(layer "F.Fab")
			(hide yes)
			(effects
				(font
					(size 1.016 1.016)
					(thickness 0.1524)
				)
			)
		)
		(duplicate_pad_numbers_are_jumpers no)
		(fp_line
			(start -0.4826 0)
			(end -0.2032 0)
			(stroke
				(width 0.2032)
				(type default)
			)
			(layer "F.SilkS")
		)
		(fp_line
			(start 0.2032 0)
			(end 0.4826 0)
			(stroke
				(width 0.2032)
				(type default)
			)
			(layer "F.SilkS")
		)
		(fp_rect
			(start -0.5842 1.3335)
			(end 0.5842 -1.3335)
			(stroke
				(width 0)
				(type default)
			)
			(fill no)
			(layer "F.CrtYd")
		)
		(fp_rect
			(start -0.5842 1.3335)
			(end 0.5842 -1.3335)
			(stroke
				(width 0)
				(type default)
			)
			(fill no)
			(layer "F.Fab")
		)
		(pad "1" smd custom
			(at 0 -0.762)
			(size 0.2159 0.2159)
			(layers "F.Cu" "F.Mask" "F.Paste")
			(net "P5V_B_2")
			(options
				(clearance outline)
				(anchor circle)
			)
			(primitives
				(gr_poly
					(pts
						(arc
							(start -0.3302 -0.4318)
							(mid -0.402042 -0.402042)
							(end -0.4318 -0.3302)
						)
						(arc
							(start -0.4318 0.3302)
							(mid -0.402042 0.402042)
							(end -0.3302 0.4318)
						)
						(arc
							(start 0.3302 0.4318)
							(mid 0.402042 0.402042)
							(end 0.4318 0.3302)
						)
						(arc
							(start 0.4318 -0.3302)
							(mid 0.402042 -0.402042)
							(end 0.3302 -0.4318)
						)
					)
					(width 0)
					(fill yes)
				)
			)
		)
		(pad "2" smd custom
			(at 0 0.762)
			(size 0.2159 0.2159)
			(layers "F.Cu" "F.Mask" "F.Paste")
			(net "FLT_HDD17")
			(options
				(clearance outline)
				(anchor circle)
			)
			(primitives
				(gr_poly
					(pts
						(arc
							(start -0.3302 -0.4318)
							(mid -0.402042 -0.402042)
							(end -0.4318 -0.3302)
						)
						(arc
							(start -0.4318 0.3302)
							(mid -0.402042 0.402042)
							(end -0.3302 0.4318)
						)
						(arc
							(start 0.3302 0.4318)
							(mid 0.402042 0.402042)
							(end 0.4318 0.3302)
						)
						(arc
							(start 0.4318 -0.3302)
							(mid 0.402042 -0.402042)
							(end 0.3302 -0.4318)
						)
					)
					(width 0)
					(fill yes)
				)
			)
		)
	)
	(footprint ""
		(layer "F.Cu")
		(at 455.93 -267.843 180)
		(property "Reference" "C160"
			(at 0 0 180)
			(layer "F.SilkS")
			(hide yes)
			(effects
				(font
					(size 1.27 1.27)
				)
			)
		)
		(property "Value" "SC1U16V3KX-5GP"
			(at 0 -2.8194 180)
			(unlocked yes)
			(layer "F.Fab")
			(hide yes)
			(effects
				(font
					(size 1.016 1.016)
					(thickness 0.1524)
				)
			)
		)
		(property "Device Type" "C603H36"
			(at 0 -4.3434 180)
			(unlocked yes)
			(layer "F.Fab")
			(hide yes)
			(effects
				(font
					(size 1.016 1.016)
					(thickness 0.1524)
				)
			)
		)
		(duplicate_pad_numbers_are_jumpers no)
		(fp_line
			(start 0.508 0)
			(end -0.508 0)
			(stroke
				(width 0.2032)
				(type default)
			)
			(layer "F.SilkS")
		)
		(fp_rect
			(start -0.5842 1.3335)
			(end 0.5842 -1.3335)
			(stroke
				(width 0)
				(type default)
			)
			(fill no)
			(layer "F.CrtYd")
		)
		(fp_rect
			(start -0.5842 1.3335)
			(end 0.5842 -1.3335)
			(stroke
				(width 0)
				(type default)
			)
			(fill no)
			(layer "F.Fab")
		)
		(pad "1" smd custom
			(at 0 -0.762 180)
			(size 0.2159 0.2159)
			(layers "F.Cu" "F.Mask" "F.Paste")
			(net "P5V_HDD10")
			(options
				(clearance outline)
				(anchor circle)
			)
			(primitives
				(gr_poly
					(pts
						(arc
							(start -0.3302 -0.4318)
							(mid -0.402042 -0.402042)
							(end -0.4318 -0.3302)
						)
						(arc
							(start -0.4318 0.3302)
							(mid -0.402042 0.402042)
							(end -0.3302 0.4318)
						)
						(arc
							(start 0.3302 0.4318)
							(mid 0.402042 0.402042)
							(end 0.4318 0.3302)
						)
						(arc
							(start 0.4318 -0.3302)
							(mid 0.402042 -0.402042)
							(end 0.3302 -0.4318)
						)
					)
					(width 0)
					(fill yes)
				)
			)
		)
		(pad "2" smd custom
			(at 0 0.762 180)
			(size 0.2159 0.2159)
			(layers "F.Cu" "F.Mask" "F.Paste")
			(net "GND")
			(options
				(clearance outline)
				(anchor circle)
			)
			(primitives
				(gr_poly
					(pts
						(arc
							(start -0.3302 -0.4318)
							(mid -0.402042 -0.402042)
							(end -0.4318 -0.3302)
						)
						(arc
							(start -0.4318 0.3302)
							(mid -0.402042 0.402042)
							(end -0.3302 0.4318)
						)
						(arc
							(start 0.3302 0.4318)
							(mid 0.402042 0.402042)
							(end 0.4318 0.3302)
						)
						(arc
							(start 0.4318 -0.3302)
							(mid 0.402042 -0.402042)
							(end 0.3302 -0.4318)
						)
					)
					(width 0)
					(fill yes)
				)
			)
		)
	)
	(footprint ""
		(layer "F.Cu")
		(at 102.616 -357.632 -90)
		(property "Reference" "C549"
			(at 0 0 270)
			(layer "F.SilkS")
			(hide yes)
			(effects
				(font
					(size 1.27 1.27)
				)
			)
		)
		(property "Value" "SCD1U25V2KX-2-GP"
			(at 1.1811 -2.7051 270)
			(unlocked yes)
			(layer "F.Fab")
			(hide yes)
			(effects
				(font
					(size 1.016 1.016)
					(thickness 0.1524)
				)
			)
		)
		(property "Device Type" "C402H22"
			(at 1.1811 -4.2291 270)
			(unlocked yes)
			(layer "F.Fab")
			(hide yes)
			(effects
				(font
					(size 1.016 1.016)
					(thickness 0.1524)
				)
			)
		)
		(duplicate_pad_numbers_are_jumpers no)
		(fp_rect
			(start -0.4318 0.9525)
			(end 0.4318 -0.9525)
			(stroke
				(width 0)
				(type default)
			)
			(fill no)
			(layer "F.CrtYd")
		)
		(fp_rect
			(start -0.4318 0.9525)
			(end 0.4318 -0.9525)
			(stroke
				(width 0)
				(type default)
			)
			(fill no)
			(layer "F.Fab")
		)
		(pad "1" smd custom
			(at 0 -0.4445 270)
			(size 0.1524 0.1524)
			(layers "F.Cu" "F.Mask" "F.Paste")
			(net "P12V_CLIP")
			(options
				(clearance outline)
				(anchor circle)
			)
			(primitives
				(gr_poly
					(pts
						(arc
							(start 0.3048 -0.2032)
							(mid 0.275042 -0.275042)
							(end 0.2032 -0.3048)
						)
						(arc
							(start -0.2032 -0.3048)
							(mid -0.275042 -0.275042)
							(end -0.3048 -0.2032)
						)
						(arc
							(start -0.3048 0.2032)
							(mid -0.275042 0.275042)
							(end -0.2032 0.3048)
						)
						(arc
							(start 0.2032 0.3048)
							(mid 0.275042 0.275042)
							(end 0.3048 0.2032)
						)
					)
					(width 0)
					(fill yes)
				)
			)
		)
		(pad "2" smd custom
			(at 0 0.4445 270)
			(size 0.1524 0.1524)
			(layers "F.Cu" "F.Mask" "F.Paste")
			(net "GND")
			(options
				(clearance outline)
				(anchor circle)
			)
			(primitives
				(gr_poly
					(pts
						(arc
							(start 0.3048 -0.2032)
							(mid 0.275042 -0.275042)
							(end 0.2032 -0.3048)
						)
						(arc
							(start -0.2032 -0.3048)
							(mid -0.275042 -0.275042)
							(end -0.3048 -0.2032)
						)
						(arc
							(start -0.3048 0.2032)
							(mid -0.275042 0.275042)
							(end -0.2032 0.3048)
						)
						(arc
							(start 0.2032 0.3048)
							(mid 0.275042 0.275042)
							(end 0.3048 0.2032)
						)
					)
					(width 0)
					(fill yes)
				)
			)
		)
	)
	(footprint ""
		(layer "F.Cu")
		(at 470.662 -244.348 180)
		(property "Reference" "R340"
			(at 0 0 180)
			(layer "F.SilkS")
			(hide yes)
			(effects
				(font
					(size 1.27 1.27)
				)
			)
		)
		(property "Value" "1KR2F-3-GP"
			(at 0.064008 -3.993896 180)
			(unlocked yes)
			(layer "F.Fab")
			(hide yes)
			(effects
				(font
					(size 1.016 1.016)
					(thickness 0.1524)
				)
			)
		)
		(property "Device Type" "R402H16"
			(at 0.064008 -5.517896 180)
			(unlocked yes)
			(layer "F.Fab")
			(hide yes)
			(effects
				(font
					(size 1.016 1.016)
					(thickness 0.1524)
				)
			)
		)
		(duplicate_pad_numbers_are_jumpers no)
		(fp_line
			(start 0.508 -0.9398)
			(end -0.508 -0.9398)
			(stroke
				(width 0.1524)
				(type default)
			)
			(layer "F.SilkS")
		)
		(fp_line
			(start -0.508 -0.9398)
			(end -0.508 0.9398)
			(stroke
				(width 0.1524)
				(type default)
			)
			(layer "F.SilkS")
		)
		(fp_rect
			(start -0.508 0.9398)
			(end 0.508 -0.9398)
			(stroke
				(width 0)
				(type default)
			)
			(fill no)
			(layer "F.CrtYd")
		)
		(fp_rect
			(start -0.508 0.9398)
			(end 0.508 -0.9398)
			(stroke
				(width 0)
				(type default)
			)
			(fill no)
			(layer "F.Fab")
		)
		(pad "1" smd custom
			(at 0 -0.4445 180)
			(size 0.1397 0.1397)
			(layers "F.Cu" "F.Mask" "F.Paste")
			(net "P3V3_STBY_B")
			(options
				(clearance outline)
				(anchor circle)
			)
			(primitives
				(gr_poly
					(pts
						(arc
							(start -0.1778 -0.2794)
							(mid -0.249642 -0.249642)
							(end -0.2794 -0.1778)
						)
						(arc
							(start -0.2794 0.1778)
							(mid -0.249642 0.249642)
							(end -0.1778 0.2794)
						)
						(arc
							(start 0.1778 0.2794)
							(mid 0.249642 0.249642)
							(end 0.2794 0.1778)
						)
						(arc
							(start 0.2794 -0.1778)
							(mid 0.249642 -0.249642)
							(end 0.1778 -0.2794)
						)
					)
					(width 0)
					(fill yes)
				)
			)
		)
		(pad "2" smd custom
			(at 0 0.4445 180)
			(size 0.1397 0.1397)
			(layers "F.Cu" "F.Mask" "F.Paste")
			(net "SW_PWR_R_HDD11")
			(options
				(clearance outline)
				(anchor circle)
			)
			(primitives
				(gr_poly
					(pts
						(arc
							(start -0.1778 -0.2794)
							(mid -0.249642 -0.249642)
							(end -0.2794 -0.1778)
						)
						(arc
							(start -0.2794 0.1778)
							(mid -0.249642 0.249642)
							(end -0.1778 0.2794)
						)
						(arc
							(start 0.1778 0.2794)
							(mid 0.249642 0.249642)
							(end 0.2794 0.1778)
						)
						(arc
							(start 0.2794 -0.1778)
							(mid 0.249642 -0.249642)
							(end 0.1778 -0.2794)
						)
					)
					(width 0)
					(fill yes)
				)
			)
		)
	)
	(footprint ""
		(layer "F.Cu")
		(at 252.544834 -372.342918)
		(property "Reference" "R1036"
			(at 0 0 0)
			(layer "F.SilkS")
			(hide yes)
			(effects
				(font
					(size 1.27 1.27)
				)
			)
		)
		(property "Value" "100KR2F-L1-GP"
			(at 0.064008 -3.993896 0)
			(unlocked yes)
			(layer "F.Fab")
			(hide yes)
			(effects
				(font
					(size 1.016 1.016)
					(thickness 0.1524)
				)
			)
		)
		(property "Device Type" "R402H16"
			(at 0.064008 -5.517896 0)
			(unlocked yes)
			(layer "F.Fab")
			(hide yes)
			(effects
				(font
					(size 1.016 1.016)
					(thickness 0.1524)
				)
			)
		)
		(duplicate_pad_numbers_are_jumpers no)
		(fp_line
			(start -0.508 -0.9398)
			(end -0.508 0.9398)
			(stroke
				(width 0.1524)
				(type default)
			)
			(layer "F.SilkS")
		)
		(fp_line
			(start 0.508 -0.9398)
			(end -0.508 -0.9398)
			(stroke
				(width 0.1524)
				(type default)
			)
			(layer "F.SilkS")
		)
		(fp_rect
			(start -0.508 0.9398)
			(end 0.508 -0.9398)
			(stroke
				(width 0)
				(type default)
			)
			(fill no)
			(layer "F.CrtYd")
		)
		(fp_rect
			(start -0.508 0.9398)
			(end 0.508 -0.9398)
			(stroke
				(width 0)
				(type default)
			)
			(fill no)
			(layer "F.Fab")
		)
		(pad "1" smd custom
			(at 0 -0.4445)
			(size 0.1397 0.1397)
			(layers "F.Cu" "F.Mask" "F.Paste")
			(net "P12V_B")
			(options
				(clearance outline)
				(anchor circle)
			)
			(primitives
				(gr_poly
					(pts
						(arc
							(start -0.1778 -0.2794)
							(mid -0.249642 -0.249642)
							(end -0.2794 -0.1778)
						)
						(arc
							(start -0.2794 0.1778)
							(mid -0.249642 0.249642)
							(end -0.1778 0.2794)
						)
						(arc
							(start 0.1778 0.2794)
							(mid 0.249642 0.249642)
							(end 0.2794 0.1778)
						)
						(arc
							(start 0.2794 -0.1778)
							(mid 0.249642 -0.249642)
							(end 0.1778 -0.2794)
						)
					)
					(width 0)
					(fill yes)
				)
			)
		)
		(pad "2" smd custom
			(at 0 0.4445)
			(size 0.1397 0.1397)
			(layers "F.Cu" "F.Mask" "F.Paste")
			(net "MB3_P12V_PWGIN_R")
			(options
				(clearance outline)
				(anchor circle)
			)
			(primitives
				(gr_poly
					(pts
						(arc
							(start -0.1778 -0.2794)
							(mid -0.249642 -0.249642)
							(end -0.2794 -0.1778)
						)
						(arc
							(start -0.2794 0.1778)
							(mid -0.249642 0.249642)
							(end -0.1778 0.2794)
						)
						(arc
							(start 0.1778 0.2794)
							(mid 0.249642 0.249642)
							(end 0.2794 0.1778)
						)
						(arc
							(start 0.2794 -0.1778)
							(mid 0.249642 -0.249642)
							(end 0.1778 -0.2794)
						)
					)
					(width 0)
					(fill yes)
				)
			)
		)
	)
	(footprint ""
		(layer "F.Cu")
		(at 43.40606 -119.783606 -90)
		(property "Reference" "R1131"
			(at 0 0 270)
			(layer "F.SilkS")
			(hide yes)
			(effects
				(font
					(size 1.27 1.27)
				)
			)
		)
		(property "Value" "143KR2F-L-1-GP"
			(at 0.064008 -3.993896 270)
			(unlocked yes)
			(layer "F.Fab")
			(hide yes)
			(effects
				(font
					(size 1.016 1.016)
					(thickness 0.1524)
				)
			)
		)
		(property "Device Type" "R402H16"
			(at 0.064008 -5.517896 270)
			(unlocked yes)
			(layer "F.Fab")
			(hide yes)
			(effects
				(font
					(size 1.016 1.016)
					(thickness 0.1524)
				)
			)
		)
		(duplicate_pad_numbers_are_jumpers no)
		(fp_line
			(start -0.508 -0.9398)
			(end -0.508 0.9398)
			(stroke
				(width 0.1524)
				(type default)
			)
			(layer "F.SilkS")
		)
		(fp_line
			(start 0.508 -0.9398)
			(end -0.508 -0.9398)
			(stroke
				(width 0.1524)
				(type default)
			)
			(layer "F.SilkS")
		)
		(fp_rect
			(start -0.508 0.9398)
			(end 0.508 -0.9398)
			(stroke
				(width 0)
				(type default)
			)
			(fill no)
			(layer "F.CrtYd")
		)
		(fp_rect
			(start -0.508 0.9398)
			(end 0.508 -0.9398)
			(stroke
				(width 0)
				(type default)
			)
			(fill no)
			(layer "F.Fab")
		)
		(pad "1" smd custom
			(at 0 -0.4445 270)
			(size 0.1397 0.1397)
			(layers "F.Cu" "F.Mask" "F.Paste")
			(net "AGND_P5V_B_2")
			(options
				(clearance outline)
				(anchor circle)
			)
			(primitives
				(gr_poly
					(pts
						(arc
							(start -0.1778 -0.2794)
							(mid -0.249642 -0.249642)
							(end -0.2794 -0.1778)
						)
						(arc
							(start -0.2794 0.1778)
							(mid -0.249642 0.249642)
							(end -0.1778 0.2794)
						)
						(arc
							(start 0.1778 0.2794)
							(mid 0.249642 0.249642)
							(end 0.2794 0.1778)
						)
						(arc
							(start 0.2794 -0.1778)
							(mid 0.249642 -0.249642)
							(end 0.1778 -0.2794)
						)
					)
					(width 0)
					(fill yes)
				)
			)
		)
		(pad "2" smd custom
			(at 0 0.4445 270)
			(size 0.1397 0.1397)
			(layers "F.Cu" "F.Mask" "F.Paste")
			(net "P5V_B_2_TRIP")
			(options
				(clearance outline)
				(anchor circle)
			)
			(primitives
				(gr_poly
					(pts
						(arc
							(start -0.1778 -0.2794)
							(mid -0.249642 -0.249642)
							(end -0.2794 -0.1778)
						)
						(arc
							(start -0.2794 0.1778)
							(mid -0.249642 0.249642)
							(end -0.1778 0.2794)
						)
						(arc
							(start 0.1778 0.2794)
							(mid 0.249642 0.249642)
							(end 0.2794 0.1778)
						)
						(arc
							(start 0.2794 -0.1778)
							(mid 0.249642 -0.249642)
							(end 0.1778 -0.2794)
						)
					)
					(width 0)
					(fill yes)
				)
			)
		)
	)
	(footprint ""
		(layer "F.Cu")
		(at 394.589 -147.066 -90)
		(property "Reference" "R529"
			(at 0 0 270)
			(layer "F.SilkS")
			(hide yes)
			(effects
				(font
					(size 1.27 1.27)
				)
			)
		)
		(property "Value" "2R6F-GP"
			(at -0.0508 -4.8514 270)
			(unlocked yes)
			(layer "F.Fab")
			(hide yes)
			(effects
				(font
					(size 1.016 1.016)
					(thickness 0.1524)
				)
			)
		)
		(property "Device Type" "R1206H26"
			(at 0 -6.3754 270)
			(unlocked yes)
			(layer "F.Fab")
			(hide yes)
			(effects
				(font
					(size 1.016 1.016)
					(thickness 0.1524)
				)
			)
		)
		(duplicate_pad_numbers_are_jumpers no)
		(fp_line
			(start -1.016 2.2352)
			(end -1.016 -2.2352)
			(stroke
				(width 0.1524)
				(type default)
			)
			(layer "F.SilkS")
		)
		(fp_line
			(start 1.016 2.2352)
			(end -1.016 2.2352)
			(stroke
				(width 0.1524)
				(type default)
			)
			(layer "F.SilkS")
		)
		(fp_line
			(start -1.016 -2.2352)
			(end 1.016 -2.2352)
			(stroke
				(width 0.1524)
				(type default)
			)
			(layer "F.SilkS")
		)
		(fp_line
			(start 1.016 -2.2352)
			(end 1.016 2.2352)
			(stroke
				(width 0.1524)
				(type default)
			)
			(layer "F.SilkS")
		)
		(fp_rect
			(start -1.0922 2.3114)
			(end 1.0922 -2.3114)
			(stroke
				(width 0)
				(type default)
			)
			(fill no)
			(layer "F.CrtYd")
		)
		(fp_poly
			(pts
				(xy -1.0922 -2.3114) (xy 1.0922 -2.3114) (xy 1.0922 2.3114) (xy -1.0922 2.3114)
			)
			(stroke
				(width 0)
				(type default)
			)
			(fill no)
			(layer "F.Fab")
		)
		(pad "1" smd rect
			(at 0 -1.397 270)
			(size 1.651 1.27)
			(layers "F.Cu" "F.Mask" "F.Paste")
			(net "P5V_HDD20")
		)
		(pad "2" smd rect
			(at 0 1.397 270)
			(size 1.651 1.27)
			(layers "F.Cu" "F.Mask" "F.Paste")
			(net "5V_PRE_20")
		)
	)
	(footprint ""
		(layer "F.Cu")
		(at 466.5218 -7.4422 -90)
		(property "Reference" "R136"
			(at 0 0 270)
			(layer "F.SilkS")
			(hide yes)
			(effects
				(font
					(size 1.27 1.27)
				)
			)
		)
		(property "Value" "4K7R2F-GP"
			(at 0.064008 -3.993896 270)
			(unlocked yes)
			(layer "F.Fab")
			(hide yes)
			(effects
				(font
					(size 1.016 1.016)
					(thickness 0.1524)
				)
			)
		)
		(property "Device Type" "R402H16"
			(at 0.064008 -5.517896 270)
			(unlocked yes)
			(layer "F.Fab")
			(hide yes)
			(effects
				(font
					(size 1.016 1.016)
					(thickness 0.1524)
				)
			)
		)
		(duplicate_pad_numbers_are_jumpers no)
		(fp_line
			(start -0.508 -0.9398)
			(end -0.508 0.9398)
			(stroke
				(width 0.1524)
				(type default)
			)
			(layer "F.SilkS")
		)
		(fp_line
			(start 0.508 -0.9398)
			(end -0.508 -0.9398)
			(stroke
				(width 0.1524)
				(type default)
			)
			(layer "F.SilkS")
		)
		(fp_rect
			(start -0.508 0.9398)
			(end 0.508 -0.9398)
			(stroke
				(width 0)
				(type default)
			)
			(fill no)
			(layer "F.CrtYd")
		)
		(fp_rect
			(start -0.508 0.9398)
			(end 0.508 -0.9398)
			(stroke
				(width 0)
				(type default)
			)
			(fill no)
			(layer "F.Fab")
		)
		(pad "1" smd custom
			(at 0 -0.4445 270)
			(size 0.1397 0.1397)
			(layers "F.Cu" "F.Mask" "F.Paste")
			(net "P3V3_STBY_B")
			(options
				(clearance outline)
				(anchor circle)
			)
			(primitives
				(gr_poly
					(pts
						(arc
							(start -0.1778 -0.2794)
							(mid -0.249642 -0.249642)
							(end -0.2794 -0.1778)
						)
						(arc
							(start -0.2794 0.1778)
							(mid -0.249642 0.249642)
							(end -0.1778 0.2794)
						)
						(arc
							(start 0.1778 0.2794)
							(mid 0.249642 0.249642)
							(end 0.2794 0.1778)
						)
						(arc
							(start 0.2794 -0.1778)
							(mid 0.249642 -0.249642)
							(end 0.1778 -0.2794)
						)
					)
					(width 0)
					(fill yes)
				)
			)
		)
		(pad "2" smd custom
			(at 0 0.4445 270)
			(size 0.1397 0.1397)
			(layers "F.Cu" "F.Mask" "F.Paste")
			(net "TEMP2_A0")
			(options
				(clearance outline)
				(anchor circle)
			)
			(primitives
				(gr_poly
					(pts
						(arc
							(start -0.1778 -0.2794)
							(mid -0.249642 -0.249642)
							(end -0.2794 -0.1778)
						)
						(arc
							(start -0.2794 0.1778)
							(mid -0.249642 0.249642)
							(end -0.1778 0.2794)
						)
						(arc
							(start 0.1778 0.2794)
							(mid 0.249642 0.249642)
							(end 0.2794 0.1778)
						)
						(arc
							(start 0.2794 -0.1778)
							(mid 0.249642 -0.249642)
							(end 0.1778 -0.2794)
						)
					)
					(width 0)
					(fill yes)
				)
			)
		)
	)
	(footprint ""
		(layer "F.Cu")
		(at 363.1184 -249.5296 90)
		(property "Reference" "R275"
			(at 0 0 90)
			(layer "F.SilkS")
			(hide yes)
			(effects
				(font
					(size 1.27 1.27)
				)
			)
		)
		(property "Value" "4K7R2J-2-GP"
			(at 0.064008 -3.993896 90)
			(unlocked yes)
			(layer "F.Fab")
			(hide yes)
			(effects
				(font
					(size 1.016 1.016)
					(thickness 0.1524)
				)
			)
		)
		(property "Device Type" "R402H16"
			(at 0.064008 -5.517896 90)
			(unlocked yes)
			(layer "F.Fab")
			(hide yes)
			(effects
				(font
					(size 1.016 1.016)
					(thickness 0.1524)
				)
			)
		)
		(duplicate_pad_numbers_are_jumpers no)
		(fp_line
			(start 0.508 -0.9398)
			(end -0.508 -0.9398)
			(stroke
				(width 0.1524)
				(type default)
			)
			(layer "F.SilkS")
		)
		(fp_line
			(start -0.508 -0.9398)
			(end -0.508 0.9398)
			(stroke
				(width 0.1524)
				(type default)
			)
			(layer "F.SilkS")
		)
		(fp_rect
			(start -0.508 0.9398)
			(end 0.508 -0.9398)
			(stroke
				(width 0)
				(type default)
			)
			(fill no)
			(layer "F.CrtYd")
		)
		(fp_rect
			(start -0.508 0.9398)
			(end 0.508 -0.9398)
			(stroke
				(width 0)
				(type default)
			)
			(fill no)
			(layer "F.Fab")
		)
		(pad "1" smd custom
			(at 0 -0.4445 90)
			(size 0.1397 0.1397)
			(layers "F.Cu" "F.Mask" "F.Paste")
			(net "P12V_B")
			(options
				(clearance outline)
				(anchor circle)
			)
			(primitives
				(gr_poly
					(pts
						(arc
							(start -0.1778 -0.2794)
							(mid -0.249642 -0.249642)
							(end -0.2794 -0.1778)
						)
						(arc
							(start -0.2794 0.1778)
							(mid -0.249642 0.249642)
							(end -0.1778 0.2794)
						)
						(arc
							(start 0.1778 0.2794)
							(mid 0.249642 0.249642)
							(end 0.2794 0.1778)
						)
						(arc
							(start 0.2794 -0.1778)
							(mid 0.249642 -0.249642)
							(end 0.1778 -0.2794)
						)
					)
					(width 0)
					(fill yes)
				)
			)
		)
		(pad "2" smd custom
			(at 0 0.4445 90)
			(size 0.1397 0.1397)
			(layers "F.Cu" "F.Mask" "F.Paste")
			(net "SW_HDD_P7")
			(options
				(clearance outline)
				(anchor circle)
			)
			(primitives
				(gr_poly
					(pts
						(arc
							(start -0.1778 -0.2794)
							(mid -0.249642 -0.249642)
							(end -0.2794 -0.1778)
						)
						(arc
							(start -0.2794 0.1778)
							(mid -0.249642 0.249642)
							(end -0.1778 0.2794)
						)
						(arc
							(start 0.1778 0.2794)
							(mid 0.249642 0.249642)
							(end 0.2794 0.1778)
						)
						(arc
							(start 0.2794 -0.1778)
							(mid 0.249642 -0.249642)
							(end 0.1778 -0.2794)
						)
					)
					(width 0)
					(fill yes)
				)
			)
		)
	)
	(footprint ""
		(layer "F.Cu")
		(at 426.085 -32.004 -90)
		(property "Reference" "R828"
			(at 0 0 270)
			(layer "F.SilkS")
			(hide yes)
			(effects
				(font
					(size 1.27 1.27)
				)
			)
		)
		(property "Value" "2R6F-GP"
			(at -0.0508 -4.8514 270)
			(unlocked yes)
			(layer "F.Fab")
			(hide yes)
			(effects
				(font
					(size 1.016 1.016)
					(thickness 0.1524)
				)
			)
		)
		(property "Device Type" "R1206H26"
			(at 0 -6.3754 270)
			(unlocked yes)
			(layer "F.Fab")
			(hide yes)
			(effects
				(font
					(size 1.016 1.016)
					(thickness 0.1524)
				)
			)
		)
		(duplicate_pad_numbers_are_jumpers no)
		(fp_line
			(start -1.016 2.2352)
			(end -1.016 -2.2352)
			(stroke
				(width 0.1524)
				(type default)
			)
			(layer "F.SilkS")
		)
		(fp_line
			(start 1.016 2.2352)
			(end -1.016 2.2352)
			(stroke
				(width 0.1524)
				(type default)
			)
			(layer "F.SilkS")
		)
		(fp_line
			(start -1.016 -2.2352)
			(end 1.016 -2.2352)
			(stroke
				(width 0.1524)
				(type default)
			)
			(layer "F.SilkS")
		)
		(fp_line
			(start 1.016 -2.2352)
			(end 1.016 2.2352)
			(stroke
				(width 0.1524)
				(type default)
			)
			(layer "F.SilkS")
		)
		(fp_rect
			(start -1.0922 2.3114)
			(end 1.0922 -2.3114)
			(stroke
				(width 0)
				(type default)
			)
			(fill no)
			(layer "F.CrtYd")
		)
		(fp_poly
			(pts
				(xy -1.0922 -2.3114) (xy 1.0922 -2.3114) (xy 1.0922 2.3114) (xy -1.0922 2.3114)
			)
			(stroke
				(width 0)
				(type default)
			)
			(fill no)
			(layer "F.Fab")
		)
		(pad "1" smd rect
			(at 0 -1.397 270)
			(size 1.651 1.27)
			(layers "F.Cu" "F.Mask" "F.Paste")
			(net "P5V_HDD33")
		)
		(pad "2" smd rect
			(at 0 1.397 270)
			(size 1.651 1.27)
			(layers "F.Cu" "F.Mask" "F.Paste")
			(net "5V_PRE_33")
		)
	)
	(footprint ""
		(layer "F.Cu")
		(at 158.663386 -245.219474 90)
		(property "Reference" "C81"
			(at 0 0 90)
			(layer "F.SilkS")
			(hide yes)
			(effects
				(font
					(size 1.27 1.27)
				)
			)
		)
		(property "Value" "SCD01U16V1KX-GP"
			(at -2.8321 -1.7399 90)
			(unlocked yes)
			(layer "F.Fab")
			(hide yes)
			(effects
				(font
					(size 1.016 1.016)
					(thickness 0.1524)
				)
			)
		)
		(property "Device Type" "C0201H13"
			(at -2.8321 -3.2639 90)
			(unlocked yes)
			(layer "F.Fab")
			(hide yes)
			(effects
				(font
					(size 1.016 1.016)
					(thickness 0.1524)
				)
			)
		)
		(duplicate_pad_numbers_are_jumpers no)
		(fp_rect
			(start -0.2794 0.6477)
			(end 0.2794 -0.6477)
			(stroke
				(width 0)
				(type default)
			)
			(fill no)
			(layer "F.CrtYd")
		)
		(fp_rect
			(start -0.2794 0.6477)
			(end 0.2794 -0.6477)
			(stroke
				(width 0)
				(type default)
			)
			(fill no)
			(layer "F.Fab")
		)
		(pad "1" smd custom
			(at 0 -0.2794 90)
			(size 0.0762 0.0762)
			(layers "F.Cu" "F.Mask" "F.Paste")
			(net "SAS_HDD_RX_N4")
			(options
				(clearance outline)
				(anchor circle)
			)
			(primitives
				(gr_poly
					(pts
						(arc
							(start 0.1524 -0.127)
							(mid 0.137521 -0.162921)
							(end 0.1016 -0.1778)
						)
						(arc
							(start -0.1016 -0.1778)
							(mid -0.137521 -0.162921)
							(end -0.1524 -0.127)
						)
						(arc
							(start -0.1524 0.127)
							(mid -0.137521 0.162921)
							(end -0.1016 0.1778)
						)
						(arc
							(start 0.1016 0.1778)
							(mid 0.137521 0.162921)
							(end 0.1524 0.127)
						)
					)
					(width 0)
					(fill yes)
				)
			)
		)
		(pad "2" smd custom
			(at 0 0.2794 90)
			(size 0.0762 0.0762)
			(layers "F.Cu" "F.Mask" "F.Paste")
			(net "PHY_SCC_B_TO_DRV_B_4_DN")
			(options
				(clearance outline)
				(anchor circle)
			)
			(primitives
				(gr_poly
					(pts
						(arc
							(start 0.1524 -0.127)
							(mid 0.137521 -0.162921)
							(end 0.1016 -0.1778)
						)
						(arc
							(start -0.1016 -0.1778)
							(mid -0.137521 -0.162921)
							(end -0.1524 -0.127)
						)
						(arc
							(start -0.1524 0.127)
							(mid -0.137521 0.162921)
							(end -0.1016 0.1778)
						)
						(arc
							(start 0.1016 0.1778)
							(mid 0.137521 0.162921)
							(end 0.1524 0.127)
						)
					)
					(width 0)
					(fill yes)
				)
			)
		)
	)
	(footprint ""
		(layer "F.Cu")
		(at 212.5218 -204.343 90)
		(property "Reference" "C10"
			(at 0 0 90)
			(layer "F.SilkS")
			(hide yes)
			(effects
				(font
					(size 1.27 1.27)
				)
			)
		)
		(property "Value" "SCD1U16V2KX-3GP"
			(at 1.1811 -2.7051 90)
			(unlocked yes)
			(layer "F.Fab")
			(hide yes)
			(effects
				(font
					(size 1.016 1.016)
					(thickness 0.1524)
				)
			)
		)
		(property "Device Type" "C402H22"
			(at 1.1811 -4.2291 90)
			(unlocked yes)
			(layer "F.Fab")
			(hide yes)
			(effects
				(font
					(size 1.016 1.016)
					(thickness 0.1524)
				)
			)
		)
		(duplicate_pad_numbers_are_jumpers no)
		(fp_rect
			(start -0.4318 0.9525)
			(end 0.4318 -0.9525)
			(stroke
				(width 0)
				(type default)
			)
			(fill no)
			(layer "F.CrtYd")
		)
		(fp_rect
			(start -0.4318 0.9525)
			(end 0.4318 -0.9525)
			(stroke
				(width 0)
				(type default)
			)
			(fill no)
			(layer "F.Fab")
		)
		(pad "1" smd custom
			(at 0 -0.4445 90)
			(size 0.1524 0.1524)
			(layers "F.Cu" "F.Mask" "F.Paste")
			(net "P3V3_STBY_B")
			(options
				(clearance outline)
				(anchor circle)
			)
			(primitives
				(gr_poly
					(pts
						(arc
							(start 0.3048 -0.2032)
							(mid 0.275042 -0.275042)
							(end 0.2032 -0.3048)
						)
						(arc
							(start -0.2032 -0.3048)
							(mid -0.275042 -0.275042)
							(end -0.3048 -0.2032)
						)
						(arc
							(start -0.3048 0.2032)
							(mid -0.275042 0.275042)
							(end -0.2032 0.3048)
						)
						(arc
							(start 0.2032 0.3048)
							(mid 0.275042 0.275042)
							(end 0.3048 0.2032)
						)
					)
					(width 0)
					(fill yes)
				)
			)
		)
		(pad "2" smd custom
			(at 0 0.4445 90)
			(size 0.1524 0.1524)
			(layers "F.Cu" "F.Mask" "F.Paste")
			(net "GND")
			(options
				(clearance outline)
				(anchor circle)
			)
			(primitives
				(gr_poly
					(pts
						(arc
							(start 0.3048 -0.2032)
							(mid 0.275042 -0.275042)
							(end 0.2032 -0.3048)
						)
						(arc
							(start -0.2032 -0.3048)
							(mid -0.275042 -0.275042)
							(end -0.3048 -0.2032)
						)
						(arc
							(start -0.3048 0.2032)
							(mid -0.275042 0.275042)
							(end -0.2032 0.3048)
						)
						(arc
							(start 0.2032 0.3048)
							(mid 0.275042 0.275042)
							(end 0.3048 0.2032)
						)
					)
					(width 0)
					(fill yes)
				)
			)
		)
	)
	(footprint ""
		(layer "F.Cu")
		(at 244.662452 -362.284772)
		(property "Reference" "R1051"
			(at 0 0 0)
			(layer "F.SilkS")
			(hide yes)
			(effects
				(font
					(size 1.27 1.27)
				)
			)
		)
		(property "Value" "4K99R2F-L-GP"
			(at 0.064008 -3.993896 0)
			(unlocked yes)
			(layer "F.Fab")
			(hide yes)
			(effects
				(font
					(size 1.016 1.016)
					(thickness 0.1524)
				)
			)
		)
		(property "Device Type" "R402H16"
			(at 0.064008 -5.517896 0)
			(unlocked yes)
			(layer "F.Fab")
			(hide yes)
			(effects
				(font
					(size 1.016 1.016)
					(thickness 0.1524)
				)
			)
		)
		(duplicate_pad_numbers_are_jumpers no)
		(fp_line
			(start -0.508 -0.9398)
			(end -0.508 0.9398)
			(stroke
				(width 0.1524)
				(type default)
			)
			(layer "F.SilkS")
		)
		(fp_line
			(start 0.508 -0.9398)
			(end -0.508 -0.9398)
			(stroke
				(width 0.1524)
				(type default)
			)
			(layer "F.SilkS")
		)
		(fp_rect
			(start -0.508 0.9398)
			(end 0.508 -0.9398)
			(stroke
				(width 0)
				(type default)
			)
			(fill no)
			(layer "F.CrtYd")
		)
		(fp_rect
			(start -0.508 0.9398)
			(end 0.508 -0.9398)
			(stroke
				(width 0)
				(type default)
			)
			(fill no)
			(layer "F.Fab")
		)
		(pad "1" smd custom
			(at 0 -0.4445)
			(size 0.1397 0.1397)
			(layers "F.Cu" "F.Mask" "F.Paste")
			(net "MB3_CM_UV_R")
			(options
				(clearance outline)
				(anchor circle)
			)
			(primitives
				(gr_poly
					(pts
						(arc
							(start -0.1778 -0.2794)
							(mid -0.249642 -0.249642)
							(end -0.2794 -0.1778)
						)
						(arc
							(start -0.2794 0.1778)
							(mid -0.249642 0.249642)
							(end -0.1778 0.2794)
						)
						(arc
							(start 0.1778 0.2794)
							(mid 0.249642 0.249642)
							(end 0.2794 0.1778)
						)
						(arc
							(start 0.2794 -0.1778)
							(mid 0.249642 -0.249642)
							(end 0.1778 -0.2794)
						)
					)
					(width 0)
					(fill yes)
				)
			)
		)
		(pad "2" smd custom
			(at 0 0.4445)
			(size 0.1397 0.1397)
			(layers "F.Cu" "F.Mask" "F.Paste")
			(net "AGND_CURRENT_DPB")
			(options
				(clearance outline)
				(anchor circle)
			)
			(primitives
				(gr_poly
					(pts
						(arc
							(start -0.1778 -0.2794)
							(mid -0.249642 -0.249642)
							(end -0.2794 -0.1778)
						)
						(arc
							(start -0.2794 0.1778)
							(mid -0.249642 0.249642)
							(end -0.1778 0.2794)
						)
						(arc
							(start 0.1778 0.2794)
							(mid 0.249642 0.249642)
							(end 0.2794 0.1778)
						)
						(arc
							(start 0.2794 -0.1778)
							(mid 0.249642 -0.249642)
							(end 0.1778 -0.2794)
						)
					)
					(width 0)
					(fill yes)
				)
			)
		)
	)
	(footprint ""
		(layer "F.Cu")
		(at 467.741 -250.571 90)
		(property "Reference" "R344"
			(at 0 0 90)
			(layer "F.SilkS")
			(hide yes)
			(effects
				(font
					(size 1.27 1.27)
				)
			)
		)
		(property "Value" "4K7R2J-2-GP"
			(at 0.064008 -3.993896 90)
			(unlocked yes)
			(layer "F.Fab")
			(hide yes)
			(effects
				(font
					(size 1.016 1.016)
					(thickness 0.1524)
				)
			)
		)
		(property "Device Type" "R402H16"
			(at 0.064008 -5.517896 90)
			(unlocked yes)
			(layer "F.Fab")
			(hide yes)
			(effects
				(font
					(size 1.016 1.016)
					(thickness 0.1524)
				)
			)
		)
		(duplicate_pad_numbers_are_jumpers no)
		(fp_line
			(start 0.508 -0.9398)
			(end -0.508 -0.9398)
			(stroke
				(width 0.1524)
				(type default)
			)
			(layer "F.SilkS")
		)
		(fp_line
			(start -0.508 -0.9398)
			(end -0.508 0.9398)
			(stroke
				(width 0.1524)
				(type default)
			)
			(layer "F.SilkS")
		)
		(fp_rect
			(start -0.508 0.9398)
			(end 0.508 -0.9398)
			(stroke
				(width 0)
				(type default)
			)
			(fill no)
			(layer "F.CrtYd")
		)
		(fp_rect
			(start -0.508 0.9398)
			(end 0.508 -0.9398)
			(stroke
				(width 0)
				(type default)
			)
			(fill no)
			(layer "F.Fab")
		)
		(pad "1" smd custom
			(at 0 -0.4445 90)
			(size 0.1397 0.1397)
			(layers "F.Cu" "F.Mask" "F.Paste")
			(net "P12V_B")
			(options
				(clearance outline)
				(anchor circle)
			)
			(primitives
				(gr_poly
					(pts
						(arc
							(start -0.1778 -0.2794)
							(mid -0.249642 -0.249642)
							(end -0.2794 -0.1778)
						)
						(arc
							(start -0.2794 0.1778)
							(mid -0.249642 0.249642)
							(end -0.1778 0.2794)
						)
						(arc
							(start 0.1778 0.2794)
							(mid 0.249642 0.249642)
							(end 0.2794 0.1778)
						)
						(arc
							(start 0.2794 -0.1778)
							(mid 0.249642 -0.249642)
							(end 0.1778 -0.2794)
						)
					)
					(width 0)
					(fill yes)
				)
			)
		)
		(pad "2" smd custom
			(at 0 0.4445 90)
			(size 0.1397 0.1397)
			(layers "F.Cu" "F.Mask" "F.Paste")
			(net "SW_HDD_R11")
			(options
				(clearance outline)
				(anchor circle)
			)
			(primitives
				(gr_poly
					(pts
						(arc
							(start -0.1778 -0.2794)
							(mid -0.249642 -0.249642)
							(end -0.2794 -0.1778)
						)
						(arc
							(start -0.2794 0.1778)
							(mid -0.249642 0.249642)
							(end -0.1778 0.2794)
						)
						(arc
							(start 0.1778 0.2794)
							(mid 0.249642 0.249642)
							(end 0.2794 0.1778)
						)
						(arc
							(start 0.2794 -0.1778)
							(mid 0.249642 -0.249642)
							(end 0.1778 -0.2794)
						)
					)
					(width 0)
					(fill yes)
				)
			)
		)
	)
	(footprint ""
		(layer "F.Cu")
		(at 177.419 -361.696)
		(property "Reference" "C540"
			(at 0 0 0)
			(layer "F.SilkS")
			(hide yes)
			(effects
				(font
					(size 1.27 1.27)
				)
			)
		)
		(property "Value" "SCD22U16V2KX-GP"
			(at 1.1811 -2.7051 0)
			(unlocked yes)
			(layer "F.Fab")
			(hide yes)
			(effects
				(font
					(size 1.016 1.016)
					(thickness 0.1524)
				)
			)
		)
		(property "Device Type" "C402H22"
			(at 1.1811 -4.2291 0)
			(unlocked yes)
			(layer "F.Fab")
			(hide yes)
			(effects
				(font
					(size 1.016 1.016)
					(thickness 0.1524)
				)
			)
		)
		(duplicate_pad_numbers_are_jumpers no)
		(fp_rect
			(start -0.4318 0.9525)
			(end 0.4318 -0.9525)
			(stroke
				(width 0)
				(type default)
			)
			(fill no)
			(layer "F.CrtYd")
		)
		(fp_rect
			(start -0.4318 0.9525)
			(end 0.4318 -0.9525)
			(stroke
				(width 0)
				(type default)
			)
			(fill no)
			(layer "F.Fab")
		)
		(pad "1" smd custom
			(at 0 -0.4445)
			(size 0.1524 0.1524)
			(layers "F.Cu" "F.Mask" "F.Paste")
			(net "MB0_TIME_R")
			(options
				(clearance outline)
				(anchor circle)
			)
			(primitives
				(gr_poly
					(pts
						(arc
							(start 0.3048 -0.2032)
							(mid 0.275042 -0.275042)
							(end 0.2032 -0.3048)
						)
						(arc
							(start -0.2032 -0.3048)
							(mid -0.275042 -0.275042)
							(end -0.3048 -0.2032)
						)
						(arc
							(start -0.3048 0.2032)
							(mid -0.275042 0.275042)
							(end -0.2032 0.3048)
						)
						(arc
							(start 0.2032 0.3048)
							(mid 0.275042 0.275042)
							(end 0.3048 0.2032)
						)
					)
					(width 0)
					(fill yes)
				)
			)
		)
		(pad "2" smd custom
			(at 0 0.4445)
			(size 0.1524 0.1524)
			(layers "F.Cu" "F.Mask" "F.Paste")
			(net "AGND_CURRENT_MON")
			(options
				(clearance outline)
				(anchor circle)
			)
			(primitives
				(gr_poly
					(pts
						(arc
							(start 0.3048 -0.2032)
							(mid 0.275042 -0.275042)
							(end 0.2032 -0.3048)
						)
						(arc
							(start -0.2032 -0.3048)
							(mid -0.275042 -0.275042)
							(end -0.3048 -0.2032)
						)
						(arc
							(start -0.3048 0.2032)
							(mid -0.275042 0.275042)
							(end -0.2032 0.3048)
						)
						(arc
							(start 0.2032 0.3048)
							(mid 0.275042 0.275042)
							(end 0.3048 0.2032)
						)
					)
					(width 0)
					(fill yes)
				)
			)
		)
	)
	(footprint ""
		(layer "F.Cu")
		(at 299.722286 -333.032862 180)
		(property "Reference" "C22"
			(at 0 0 180)
			(layer "F.SilkS")
			(hide yes)
			(effects
				(font
					(size 1.27 1.27)
				)
			)
		)
		(property "Value" "SC1U16V3KX-5GP"
			(at 0 -2.8194 180)
			(unlocked yes)
			(layer "F.Fab")
			(hide yes)
			(effects
				(font
					(size 1.016 1.016)
					(thickness 0.1524)
				)
			)
		)
		(property "Device Type" "C603H36"
			(at 0 -4.3434 180)
			(unlocked yes)
			(layer "F.Fab")
			(hide yes)
			(effects
				(font
					(size 1.016 1.016)
					(thickness 0.1524)
				)
			)
		)
		(duplicate_pad_numbers_are_jumpers no)
		(fp_line
			(start 0.508 0)
			(end -0.508 0)
			(stroke
				(width 0.2032)
				(type default)
			)
			(layer "F.SilkS")
		)
		(fp_rect
			(start -0.5842 1.3335)
			(end 0.5842 -1.3335)
			(stroke
				(width 0)
				(type default)
			)
			(fill no)
			(layer "F.CrtYd")
		)
		(fp_rect
			(start -0.5842 1.3335)
			(end 0.5842 -1.3335)
			(stroke
				(width 0)
				(type default)
			)
			(fill no)
			(layer "F.Fab")
		)
		(pad "1" smd custom
			(at 0 -0.762 180)
			(size 0.2159 0.2159)
			(layers "F.Cu" "F.Mask" "F.Paste")
			(net "P3V3_IN")
			(options
				(clearance outline)
				(anchor circle)
			)
			(primitives
				(gr_poly
					(pts
						(arc
							(start -0.3302 -0.4318)
							(mid -0.402042 -0.402042)
							(end -0.4318 -0.3302)
						)
						(arc
							(start -0.4318 0.3302)
							(mid -0.402042 0.402042)
							(end -0.3302 0.4318)
						)
						(arc
							(start 0.3302 0.4318)
							(mid 0.402042 0.402042)
							(end 0.4318 0.3302)
						)
						(arc
							(start 0.4318 -0.3302)
							(mid 0.402042 -0.402042)
							(end 0.3302 -0.4318)
						)
					)
					(width 0)
					(fill yes)
				)
			)
		)
		(pad "2" smd custom
			(at 0 0.762 180)
			(size 0.2159 0.2159)
			(layers "F.Cu" "F.Mask" "F.Paste")
			(net "GND")
			(options
				(clearance outline)
				(anchor circle)
			)
			(primitives
				(gr_poly
					(pts
						(arc
							(start -0.3302 -0.4318)
							(mid -0.402042 -0.402042)
							(end -0.4318 -0.3302)
						)
						(arc
							(start -0.4318 0.3302)
							(mid -0.402042 0.402042)
							(end -0.3302 0.4318)
						)
						(arc
							(start 0.3302 0.4318)
							(mid 0.402042 0.402042)
							(end 0.4318 0.3302)
						)
						(arc
							(start 0.4318 -0.3302)
							(mid 0.402042 -0.402042)
							(end 0.3302 -0.4318)
						)
					)
					(width 0)
					(fill yes)
				)
			)
		)
	)
	(footprint ""
		(layer "F.Cu")
		(at 220.6752 -193.294 90)
		(property "Reference" "R34"
			(at 0 0 90)
			(layer "F.SilkS")
			(hide yes)
			(effects
				(font
					(size 1.27 1.27)
				)
			)
		)
		(property "Value" "4K7R2F-GP"
			(at 0.064008 -3.993896 90)
			(unlocked yes)
			(layer "F.Fab")
			(hide yes)
			(effects
				(font
					(size 1.016 1.016)
					(thickness 0.1524)
				)
			)
		)
		(property "Device Type" "R402H16"
			(at 0.064008 -5.517896 90)
			(unlocked yes)
			(layer "F.Fab")
			(hide yes)
			(effects
				(font
					(size 1.016 1.016)
					(thickness 0.1524)
				)
			)
		)
		(duplicate_pad_numbers_are_jumpers no)
		(fp_line
			(start 0.508 -0.9398)
			(end -0.508 -0.9398)
			(stroke
				(width 0.1524)
				(type default)
			)
			(layer "F.SilkS")
		)
		(fp_line
			(start -0.508 -0.9398)
			(end -0.508 0.9398)
			(stroke
				(width 0.1524)
				(type default)
			)
			(layer "F.SilkS")
		)
		(fp_rect
			(start -0.508 0.9398)
			(end 0.508 -0.9398)
			(stroke
				(width 0)
				(type default)
			)
			(fill no)
			(layer "F.CrtYd")
		)
		(fp_rect
			(start -0.508 0.9398)
			(end 0.508 -0.9398)
			(stroke
				(width 0)
				(type default)
			)
			(fill no)
			(layer "F.Fab")
		)
		(pad "1" smd custom
			(at 0 -0.4445 90)
			(size 0.1397 0.1397)
			(layers "F.Cu" "F.Mask" "F.Paste")
			(net "IO_EXP2_HDD_FAULT_A0")
			(options
				(clearance outline)
				(anchor circle)
			)
			(primitives
				(gr_poly
					(pts
						(arc
							(start -0.1778 -0.2794)
							(mid -0.249642 -0.249642)
							(end -0.2794 -0.1778)
						)
						(arc
							(start -0.2794 0.1778)
							(mid -0.249642 0.249642)
							(end -0.1778 0.2794)
						)
						(arc
							(start 0.1778 0.2794)
							(mid 0.249642 0.249642)
							(end 0.2794 0.1778)
						)
						(arc
							(start 0.2794 -0.1778)
							(mid 0.249642 -0.249642)
							(end 0.1778 -0.2794)
						)
					)
					(width 0)
					(fill yes)
				)
			)
		)
		(pad "2" smd custom
			(at 0 0.4445 90)
			(size 0.1397 0.1397)
			(layers "F.Cu" "F.Mask" "F.Paste")
			(net "GND")
			(options
				(clearance outline)
				(anchor circle)
			)
			(primitives
				(gr_poly
					(pts
						(arc
							(start -0.1778 -0.2794)
							(mid -0.249642 -0.249642)
							(end -0.2794 -0.1778)
						)
						(arc
							(start -0.2794 0.1778)
							(mid -0.249642 0.249642)
							(end -0.1778 0.2794)
						)
						(arc
							(start 0.1778 0.2794)
							(mid 0.249642 0.249642)
							(end 0.2794 0.1778)
						)
						(arc
							(start 0.2794 -0.1778)
							(mid 0.249642 -0.249642)
							(end 0.1778 -0.2794)
						)
					)
					(width 0)
					(fill yes)
				)
			)
		)
	)
	(footprint ""
		(layer "F.Cu")
		(at 399.923 -148.082)
		(property "Reference" "Q96"
			(at 0 0 0)
			(layer "F.SilkS")
			(hide yes)
			(effects
				(font
					(size 1.27 1.27)
				)
			)
		)
		(property "Value" "AO4407AL-GP"
			(at -3.707384 -1.5367 0)
			(unlocked yes)
			(layer "F.Fab")
			(hide yes)
			(effects
				(font
					(size 1.016 1.016)
					(thickness 0.1524)
				)
			)
		)
		(property "Device Type" "SOIC8H69"
			(at -3.707384 -3.0607 0)
			(unlocked yes)
			(layer "F.Fab")
			(hide yes)
			(effects
				(font
					(size 1.016 1.016)
					(thickness 0.1524)
				)
			)
		)
		(duplicate_pad_numbers_are_jumpers no)
		(fp_line
			(start -2.7432 -1.4224)
			(end -2.7432 1.4224)
			(stroke
				(width 0.1524)
				(type default)
			)
			(layer "F.SilkS")
		)
		(fp_line
			(start -2.7432 1.4224)
			(end -2.6416 1.4224)
			(stroke
				(width 0.1524)
				(type default)
			)
			(layer "F.SilkS")
		)
		(fp_line
			(start -2.7432 1.4224)
			(end 2.1336 1.4224)
			(stroke
				(width 0.1524)
				(type default)
			)
			(layer "F.SilkS")
		)
		(fp_line
			(start -2.7178 -0.508)
			(end -2.1844 -0.0508)
			(stroke
				(width 0.1524)
				(type default)
			)
			(layer "F.SilkS")
		)
		(fp_line
			(start -2.6289 3.4417)
			(end -2.6289 1.4732)
			(stroke
				(width 0.381)
				(type default)
			)
			(layer "F.SilkS")
		)
		(fp_line
			(start -2.1844 -0.0508)
			(end -2.7178 0.508)
			(stroke
				(width 0.1524)
				(type default)
			)
			(layer "F.SilkS")
		)
		(fp_line
			(start 2.1336 -1.4224)
			(end -2.7432 -1.4224)
			(stroke
				(width 0.1524)
				(type default)
			)
			(layer "F.SilkS")
		)
		(fp_line
			(start 2.1336 1.4224)
			(end 2.1336 -1.4224)
			(stroke
				(width 0.1524)
				(type default)
			)
			(layer "F.SilkS")
		)
		(fp_poly
			(pts
				(xy -2.2098 -1.4224) (xy -2.2098 1.4224) (xy 2.2098 1.4224) (xy 2.2098 -1.4224)
			)
			(stroke
				(width 0)
				(type default)
			)
			(fill yes)
			(layer "F.SilkS")
		)
		(fp_rect
			(start -2.450084 2.999994)
			(end 2.450084 -2.999994)
			(stroke
				(width 0)
				(type default)
			)
			(fill no)
			(layer "F.CrtYd")
		)
		(fp_poly
			(pts
				(xy -2.8194 3.6322) (xy -2.8194 -3.6322) (xy 2.8194 -3.6322) (xy 2.8194 1.18364) (xy 2.450084 1.18364)
				(xy 2.450084 -2.999994) (xy -2.450084 -2.999994) (xy -2.450084 2.999994) (xy 2.450084 2.999994)
				(xy 2.450084 1.18618) (xy 2.8194 1.18618) (xy 2.8194 3.6322)
			)
			(stroke
				(width 0)
				(type default)
			)
			(fill no)
			(layer "F.CrtYd")
		)
		(fp_rect
			(start -2.8194 3.6322)
			(end 2.8194 -3.6322)
			(stroke
				(width 0)
				(type default)
			)
			(fill no)
			(layer "F.Fab")
		)
		(pad "1" smd rect
			(at -1.905 2.54)
			(size 0.635 1.651)
			(layers "F.Cu" "F.Mask" "F.Paste")
			(net "P12V_B")
		)
		(pad "2" smd rect
			(at -0.635 2.54)
			(size 0.635 1.651)
			(layers "F.Cu" "F.Mask" "F.Paste")
			(net "P12V_B")
		)
		(pad "3" smd rect
			(at 0.635 2.54)
			(size 0.635 1.651)
			(layers "F.Cu" "F.Mask" "F.Paste")
			(net "P12V_B")
		)
		(pad "4" smd rect
			(at 1.905 2.54)
			(size 0.635 1.651)
			(layers "F.Cu" "F.Mask" "F.Paste")
			(net "SW_HDD_N20")
		)
		(pad "5" smd rect
			(at 1.905 -2.54)
			(size 0.635 1.651)
			(layers "F.Cu" "F.Mask" "F.Paste")
			(net "P12V_HDD20")
		)
		(pad "6" smd rect
			(at 0.635 -2.54)
			(size 0.635 1.651)
			(layers "F.Cu" "F.Mask" "F.Paste")
			(net "P12V_HDD20")
		)
		(pad "7" smd rect
			(at -0.635 -2.54)
			(size 0.635 1.651)
			(layers "F.Cu" "F.Mask" "F.Paste")
			(net "P12V_HDD20")
		)
		(pad "8" smd rect
			(at -1.905 -2.54)
			(size 0.635 1.651)
			(layers "F.Cu" "F.Mask" "F.Paste")
			(net "P12V_HDD20")
		)
	)
	(footprint ""
		(layer "F.Cu")
		(at 474.6752 -6.8072 180)
		(property "Reference" "D35"
			(at 0 0 180)
			(layer "F.SilkS")
			(hide yes)
			(effects
				(font
					(size 1.27 1.27)
				)
			)
		)
		(property "Value" "RB551V30-GP"
			(at 0 -6.7818 180)
			(unlocked yes)
			(layer "F.Fab")
			(hide yes)
			(effects
				(font
					(size 1.016 1.016)
					(thickness 0.1524)
				)
			)
		)
		(property "Device Type" "SOD323AKH38"
			(at 0 -8.6868 180)
			(unlocked yes)
			(layer "F.Fab")
			(hide yes)
			(effects
				(font
					(size 1.016 1.016)
					(thickness 0.1524)
				)
			)
		)
		(duplicate_pad_numbers_are_jumpers no)
		(fp_line
			(start 0.889 2.159)
			(end -0.889 2.159)
			(stroke
				(width 0.1524)
				(type default)
			)
			(layer "F.SilkS")
		)
		(fp_line
			(start 0.889 -1.9304)
			(end 0.889 2.159)
			(stroke
				(width 0.1524)
				(type default)
			)
			(layer "F.SilkS")
		)
		(fp_line
			(start 0.762 2.0574)
			(end -0.762 2.0574)
			(stroke
				(width 0.508)
				(type default)
			)
			(layer "F.SilkS")
		)
		(fp_line
			(start -0.889 2.159)
			(end -0.889 -1.9304)
			(stroke
				(width 0.1524)
				(type default)
			)
			(layer "F.SilkS")
		)
		(fp_line
			(start -0.889 -1.9304)
			(end 0.889 -1.9304)
			(stroke
				(width 0.1524)
				(type default)
			)
			(layer "F.SilkS")
		)
		(fp_rect
			(start -1.016 2.3114)
			(end 1.016 -2.0066)
			(stroke
				(width 0)
				(type default)
			)
			(fill no)
			(layer "F.CrtYd")
		)
		(fp_poly
			(pts
				(xy -1.016 -2.0066) (xy 1.016 -2.0066) (xy 1.016 2.3114) (xy -1.016 2.3114)
			)
			(stroke
				(width 0)
				(type default)
			)
			(fill no)
			(layer "F.Fab")
		)
		(pad "A" smd rect
			(at 0 -1.143 180)
			(size 0.5588 1.016)
			(layers "F.Cu" "F.Mask" "F.Paste")
			(net "SW_HDD_R35")
		)
		(pad "K" smd rect
			(at 0 1.143 180)
			(size 0.5588 1.016)
			(layers "F.Cu" "F.Mask" "F.Paste")
			(net "SW_HDD_N35")
		)
	)
	(footprint ""
		(layer "F.Cu")
		(at 392.938 -160.401 180)
		(property "Reference" "C296"
			(at 0 0 180)
			(layer "F.SilkS")
			(hide yes)
			(effects
				(font
					(size 1.27 1.27)
				)
			)
		)
		(property "Value" "SC1U25V3KX-GP"
			(at 0 -2.8194 180)
			(unlocked yes)
			(layer "F.Fab")
			(hide yes)
			(effects
				(font
					(size 1.016 1.016)
					(thickness 0.1524)
				)
			)
		)
		(property "Device Type" "C603H36"
			(at 0 -4.3434 180)
			(unlocked yes)
			(layer "F.Fab")
			(hide yes)
			(effects
				(font
					(size 1.016 1.016)
					(thickness 0.1524)
				)
			)
		)
		(duplicate_pad_numbers_are_jumpers no)
		(fp_line
			(start 0.508 0)
			(end -0.508 0)
			(stroke
				(width 0.2032)
				(type default)
			)
			(layer "F.SilkS")
		)
		(fp_rect
			(start -0.5842 1.3335)
			(end 0.5842 -1.3335)
			(stroke
				(width 0)
				(type default)
			)
			(fill no)
			(layer "F.CrtYd")
		)
		(fp_rect
			(start -0.5842 1.3335)
			(end 0.5842 -1.3335)
			(stroke
				(width 0)
				(type default)
			)
			(fill no)
			(layer "F.Fab")
		)
		(pad "1" smd custom
			(at 0 -0.762 180)
			(size 0.2159 0.2159)
			(layers "F.Cu" "F.Mask" "F.Paste")
			(net "P12V_HDD20")
			(options
				(clearance outline)
				(anchor circle)
			)
			(primitives
				(gr_poly
					(pts
						(arc
							(start -0.3302 -0.4318)
							(mid -0.402042 -0.402042)
							(end -0.4318 -0.3302)
						)
						(arc
							(start -0.4318 0.3302)
							(mid -0.402042 0.402042)
							(end -0.3302 0.4318)
						)
						(arc
							(start 0.3302 0.4318)
							(mid 0.402042 0.402042)
							(end 0.4318 0.3302)
						)
						(arc
							(start 0.4318 -0.3302)
							(mid 0.402042 -0.402042)
							(end 0.3302 -0.4318)
						)
					)
					(width 0)
					(fill yes)
				)
			)
		)
		(pad "2" smd custom
			(at 0 0.762 180)
			(size 0.2159 0.2159)
			(layers "F.Cu" "F.Mask" "F.Paste")
			(net "GND")
			(options
				(clearance outline)
				(anchor circle)
			)
			(primitives
				(gr_poly
					(pts
						(arc
							(start -0.3302 -0.4318)
							(mid -0.402042 -0.402042)
							(end -0.4318 -0.3302)
						)
						(arc
							(start -0.4318 0.3302)
							(mid -0.402042 0.402042)
							(end -0.3302 0.4318)
						)
						(arc
							(start 0.3302 0.4318)
							(mid 0.402042 0.402042)
							(end 0.4318 0.3302)
						)
						(arc
							(start 0.4318 -0.3302)
							(mid 0.402042 -0.402042)
							(end 0.3302 -0.4318)
						)
					)
					(width 0)
					(fill yes)
				)
			)
		)
	)
	(footprint ""
		(layer "F.Cu")
		(at 146.304 -146.939 -90)
		(property "Reference" "C239"
			(at 0 0 270)
			(layer "F.SilkS")
			(hide yes)
			(effects
				(font
					(size 1.27 1.27)
				)
			)
		)
		(property "Value" "SC10U16V6KX-2GP"
			(at -0.0762 -5.1308 270)
			(unlocked yes)
			(layer "F.Fab")
			(hide yes)
			(effects
				(font
					(size 1.016 1.016)
					(thickness 0.1524)
				)
			)
		)
		(property "Device Type" "C1206H71"
			(at -0.127 -6.6548 270)
			(unlocked yes)
			(layer "F.Fab")
			(hide yes)
			(effects
				(font
					(size 1.016 1.016)
					(thickness 0.1524)
				)
			)
		)
		(duplicate_pad_numbers_are_jumpers no)
		(fp_line
			(start -1.016 2.2352)
			(end -1.016 0.8382)
			(stroke
				(width 0.1524)
				(type default)
			)
			(layer "F.SilkS")
		)
		(fp_line
			(start 1.016 2.2352)
			(end -1.016 2.2352)
			(stroke
				(width 0.1524)
				(type default)
			)
			(layer "F.SilkS")
		)
		(fp_line
			(start 1.016 0.8382)
			(end 1.016 2.2352)
			(stroke
				(width 0.1524)
				(type default)
			)
			(layer "F.SilkS")
		)
		(fp_line
			(start -1.016 -0.8382)
			(end -1.016 -2.2352)
			(stroke
				(width 0.1524)
				(type default)
			)
			(layer "F.SilkS")
		)
		(fp_line
			(start -1.016 -2.2352)
			(end 1.016 -2.2352)
			(stroke
				(width 0.1524)
				(type default)
			)
			(layer "F.SilkS")
		)
		(fp_line
			(start 1.016 -2.2352)
			(end 1.016 -0.8382)
			(stroke
				(width 0.1524)
				(type default)
			)
			(layer "F.SilkS")
		)
		(fp_rect
			(start -1.0922 2.3114)
			(end 1.0922 -2.3114)
			(stroke
				(width 0)
				(type default)
			)
			(fill no)
			(layer "F.CrtYd")
		)
		(fp_poly
			(pts
				(xy 1.0922 -2.3114) (xy 1.0922 2.3114) (xy -1.0922 2.3114) (xy -1.0922 -2.3114)
			)
			(stroke
				(width 0)
				(type default)
			)
			(fill no)
			(layer "F.Fab")
		)
		(pad "1" smd rect
			(at 0 -1.397 270)
			(size 1.651 1.27)
			(layers "F.Cu" "F.Mask" "F.Paste")
			(net "P5V_HDD16")
		)
		(pad "2" smd rect
			(at 0 1.397 270)
			(size 1.651 1.27)
			(layers "F.Cu" "F.Mask" "F.Paste")
			(net "GND")
		)
	)
	(footprint ""
		(layer "F.Cu")
		(at 444.159386 -121.312178 -90)
		(property "Reference" "R1155"
			(at 0 0 270)
			(layer "F.SilkS")
			(hide yes)
			(effects
				(font
					(size 1.27 1.27)
				)
			)
		)
		(property "Value" "0R2J-2-GP"
			(at 0.064008 -3.993896 270)
			(unlocked yes)
			(layer "F.Fab")
			(hide yes)
			(effects
				(font
					(size 1.016 1.016)
					(thickness 0.1524)
				)
			)
		)
		(property "Device Type" "R402H16"
			(at 0.064008 -5.517896 270)
			(unlocked yes)
			(layer "F.Fab")
			(hide yes)
			(effects
				(font
					(size 1.016 1.016)
					(thickness 0.1524)
				)
			)
		)
		(duplicate_pad_numbers_are_jumpers no)
		(fp_line
			(start -0.508 -0.9398)
			(end -0.508 0.9398)
			(stroke
				(width 0.1524)
				(type default)
			)
			(layer "F.SilkS")
		)
		(fp_line
			(start 0.508 -0.9398)
			(end -0.508 -0.9398)
			(stroke
				(width 0.1524)
				(type default)
			)
			(layer "F.SilkS")
		)
		(fp_rect
			(start -0.508 0.9398)
			(end 0.508 -0.9398)
			(stroke
				(width 0)
				(type default)
			)
			(fill no)
			(layer "F.CrtYd")
		)
		(fp_rect
			(start -0.508 0.9398)
			(end 0.508 -0.9398)
			(stroke
				(width 0)
				(type default)
			)
			(fill no)
			(layer "F.Fab")
		)
		(pad "1" smd custom
			(at 0 -0.4445 270)
			(size 0.1397 0.1397)
			(layers "F.Cu" "F.Mask" "F.Paste")
			(net "P12V_B_PGOOD")
			(options
				(clearance outline)
				(anchor circle)
			)
			(primitives
				(gr_poly
					(pts
						(arc
							(start -0.1778 -0.2794)
							(mid -0.249642 -0.249642)
							(end -0.2794 -0.1778)
						)
						(arc
							(start -0.2794 0.1778)
							(mid -0.249642 0.249642)
							(end -0.1778 0.2794)
						)
						(arc
							(start 0.1778 0.2794)
							(mid 0.249642 0.249642)
							(end 0.2794 0.1778)
						)
						(arc
							(start 0.2794 -0.1778)
							(mid 0.249642 -0.249642)
							(end 0.1778 -0.2794)
						)
					)
					(width 0)
					(fill yes)
				)
			)
		)
		(pad "2" smd custom
			(at 0 0.4445 270)
			(size 0.1397 0.1397)
			(layers "F.Cu" "F.Mask" "F.Paste")
			(net "P5V_B_4_EN_R")
			(options
				(clearance outline)
				(anchor circle)
			)
			(primitives
				(gr_poly
					(pts
						(arc
							(start -0.1778 -0.2794)
							(mid -0.249642 -0.249642)
							(end -0.2794 -0.1778)
						)
						(arc
							(start -0.2794 0.1778)
							(mid -0.249642 0.249642)
							(end -0.1778 0.2794)
						)
						(arc
							(start 0.1778 0.2794)
							(mid 0.249642 0.249642)
							(end 0.2794 0.1778)
						)
						(arc
							(start 0.2794 -0.1778)
							(mid 0.249642 -0.249642)
							(end 0.1778 -0.2794)
						)
					)
					(width 0)
					(fill yes)
				)
			)
		)
	)
	(footprint ""
		(layer "F.Cu")
		(at 263.1059 -380.216156 -90)
		(property "Reference" "R1069"
			(at 0 0 270)
			(layer "F.SilkS")
			(hide yes)
			(effects
				(font
					(size 1.27 1.27)
				)
			)
		)
		(property "Value" "1KR2J-1-GP"
			(at 0.064008 -3.993896 270)
			(unlocked yes)
			(layer "F.Fab")
			(hide yes)
			(effects
				(font
					(size 1.016 1.016)
					(thickness 0.1524)
				)
			)
		)
		(property "Device Type" "R402H16"
			(at 0.064008 -5.517896 270)
			(unlocked yes)
			(layer "F.Fab")
			(hide yes)
			(effects
				(font
					(size 1.016 1.016)
					(thickness 0.1524)
				)
			)
		)
		(duplicate_pad_numbers_are_jumpers no)
		(fp_line
			(start -0.508 -0.9398)
			(end -0.508 0.9398)
			(stroke
				(width 0.1524)
				(type default)
			)
			(layer "F.SilkS")
		)
		(fp_line
			(start 0.508 -0.9398)
			(end -0.508 -0.9398)
			(stroke
				(width 0.1524)
				(type default)
			)
			(layer "F.SilkS")
		)
		(fp_rect
			(start -0.508 0.9398)
			(end 0.508 -0.9398)
			(stroke
				(width 0)
				(type default)
			)
			(fill no)
			(layer "F.CrtYd")
		)
		(fp_rect
			(start -0.508 0.9398)
			(end 0.508 -0.9398)
			(stroke
				(width 0)
				(type default)
			)
			(fill no)
			(layer "F.Fab")
		)
		(pad "1" smd custom
			(at 0 -0.4445 270)
			(size 0.1397 0.1397)
			(layers "F.Cu" "F.Mask" "F.Paste")
			(net "DRAWER_OUT_NET")
			(options
				(clearance outline)
				(anchor circle)
			)
			(primitives
				(gr_poly
					(pts
						(arc
							(start -0.1778 -0.2794)
							(mid -0.249642 -0.249642)
							(end -0.2794 -0.1778)
						)
						(arc
							(start -0.2794 0.1778)
							(mid -0.249642 0.249642)
							(end -0.1778 0.2794)
						)
						(arc
							(start 0.1778 0.2794)
							(mid 0.249642 0.249642)
							(end 0.2794 0.1778)
						)
						(arc
							(start 0.2794 -0.1778)
							(mid 0.249642 -0.249642)
							(end 0.1778 -0.2794)
						)
					)
					(width 0)
					(fill yes)
				)
			)
		)
		(pad "2" smd custom
			(at 0 0.4445 270)
			(size 0.1397 0.1397)
			(layers "F.Cu" "F.Mask" "F.Paste")
			(net "GND")
			(options
				(clearance outline)
				(anchor circle)
			)
			(primitives
				(gr_poly
					(pts
						(arc
							(start -0.1778 -0.2794)
							(mid -0.249642 -0.249642)
							(end -0.2794 -0.1778)
						)
						(arc
							(start -0.2794 0.1778)
							(mid -0.249642 0.249642)
							(end -0.1778 0.2794)
						)
						(arc
							(start 0.1778 0.2794)
							(mid 0.249642 0.249642)
							(end 0.2794 0.1778)
						)
						(arc
							(start 0.2794 -0.1778)
							(mid 0.249642 -0.249642)
							(end 0.1778 -0.2794)
						)
					)
					(width 0)
					(fill yes)
				)
			)
		)
	)
	(footprint ""
		(layer "F.Cu")
		(at 395.224 -246.253 -90)
		(property "Reference" "Q31"
			(at 0 0 270)
			(layer "F.SilkS")
			(hide yes)
			(effects
				(font
					(size 1.27 1.27)
				)
			)
		)
		(property "Value" "2N7002KDW-GP"
			(at -2.3622 -8.2042 270)
			(unlocked yes)
			(layer "F.Fab")
			(hide yes)
			(effects
				(font
					(size 1.016 1.016)
					(thickness 0.1524)
				)
			)
		)
		(property "Device Type" "SOT-363H44"
			(at -2.3622 -10.1092 270)
			(unlocked yes)
			(layer "F.Fab")
			(hide yes)
			(effects
				(font
					(size 1.016 1.016)
					(thickness 0.1524)
				)
			)
		)
		(duplicate_pad_numbers_are_jumpers no)
		(fp_line
			(start -1.4478 1.7018)
			(end 1.4478 1.7018)
			(stroke
				(width 0.1524)
				(type default)
			)
			(layer "F.SilkS")
		)
		(fp_line
			(start 1.4478 1.7018)
			(end 1.4478 -1.7018)
			(stroke
				(width 0.1524)
				(type default)
			)
			(layer "F.SilkS")
		)
		(fp_line
			(start -1.27 1.524)
			(end -1.27 0.6604)
			(stroke
				(width 0.4826)
				(type default)
			)
			(layer "F.SilkS")
		)
		(fp_line
			(start -1.4478 -1.7018)
			(end -1.4478 1.7018)
			(stroke
				(width 0.1524)
				(type default)
			)
			(layer "F.SilkS")
		)
		(fp_line
			(start 1.4478 -1.7018)
			(end -1.4478 -1.7018)
			(stroke
				(width 0.1524)
				(type default)
			)
			(layer "F.SilkS")
		)
		(fp_poly
			(pts
				(xy -1.524 -1.778) (xy 1.524 -1.778) (xy 1.524 1.778) (xy -1.524 1.778)
			)
			(stroke
				(width 0)
				(type default)
			)
			(fill no)
			(layer "F.CrtYd")
		)
		(fp_poly
			(pts
				(xy -1.524 -1.778) (xy 1.524 -1.778) (xy 1.524 1.778) (xy -1.524 1.778)
			)
			(stroke
				(width 0)
				(type default)
			)
			(fill no)
			(layer "F.Fab")
		)
		(pad "1" smd rect
			(at -0.65024 0.9398 270)
			(size 0.4064 1.016)
			(layers "F.Cu" "F.Mask" "F.Paste")
			(net "GND")
		)
		(pad "2" smd rect
			(at 0 0.9398 270)
			(size 0.4064 1.016)
			(layers "F.Cu" "F.Mask" "F.Paste")
			(net "SW_PWR_R_HDD8")
		)
		(pad "3" smd rect
			(at 0.65024 0.9398 270)
			(size 0.4064 1.016)
			(layers "F.Cu" "F.Mask" "F.Paste")
			(net "SW_HDD_P8")
		)
		(pad "4" smd rect
			(at 0.65024 -0.9398 270)
			(size 0.4064 1.016)
			(layers "F.Cu" "F.Mask" "F.Paste")
			(net "GND")
		)
		(pad "5" smd rect
			(at 0 -0.9398 270)
			(size 0.4064 1.016)
			(layers "F.Cu" "F.Mask" "F.Paste")
			(net "SW_HDD_G8")
		)
		(pad "6" smd rect
			(at -0.65024 -0.9398 270)
			(size 0.4064 1.016)
			(layers "F.Cu" "F.Mask" "F.Paste")
			(net "SW_HDD_R8")
		)
	)
	(footprint ""
		(layer "F.Cu")
		(at 79.883 -24.13 -90)
		(property "Reference" "C376"
			(at 0 0 270)
			(layer "F.SilkS")
			(hide yes)
			(effects
				(font
					(size 1.27 1.27)
				)
			)
		)
		(property "Value" "SCD033U25V2KX-GP"
			(at 1.1811 -2.7051 270)
			(unlocked yes)
			(layer "F.Fab")
			(hide yes)
			(effects
				(font
					(size 1.016 1.016)
					(thickness 0.1524)
				)
			)
		)
		(property "Device Type" "C402H22"
			(at 1.1811 -4.2291 270)
			(unlocked yes)
			(layer "F.Fab")
			(hide yes)
			(effects
				(font
					(size 1.016 1.016)
					(thickness 0.1524)
				)
			)
		)
		(duplicate_pad_numbers_are_jumpers no)
		(fp_rect
			(start -0.4318 0.9525)
			(end 0.4318 -0.9525)
			(stroke
				(width 0)
				(type default)
			)
			(fill no)
			(layer "F.CrtYd")
		)
		(fp_rect
			(start -0.4318 0.9525)
			(end 0.4318 -0.9525)
			(stroke
				(width 0)
				(type default)
			)
			(fill no)
			(layer "F.Fab")
		)
		(pad "1" smd custom
			(at 0 -0.4445 270)
			(size 0.1524 0.1524)
			(layers "F.Cu" "F.Mask" "F.Paste")
			(net "SW_HDD_P26")
			(options
				(clearance outline)
				(anchor circle)
			)
			(primitives
				(gr_poly
					(pts
						(arc
							(start 0.3048 -0.2032)
							(mid 0.275042 -0.275042)
							(end 0.2032 -0.3048)
						)
						(arc
							(start -0.2032 -0.3048)
							(mid -0.275042 -0.275042)
							(end -0.3048 -0.2032)
						)
						(arc
							(start -0.3048 0.2032)
							(mid -0.275042 0.275042)
							(end -0.2032 0.3048)
						)
						(arc
							(start 0.2032 0.3048)
							(mid 0.275042 0.275042)
							(end 0.3048 0.2032)
						)
					)
					(width 0)
					(fill yes)
				)
			)
		)
		(pad "2" smd custom
			(at 0 0.4445 270)
			(size 0.1524 0.1524)
			(layers "F.Cu" "F.Mask" "F.Paste")
			(net "GND")
			(options
				(clearance outline)
				(anchor circle)
			)
			(primitives
				(gr_poly
					(pts
						(arc
							(start 0.3048 -0.2032)
							(mid 0.275042 -0.275042)
							(end 0.2032 -0.3048)
						)
						(arc
							(start -0.2032 -0.3048)
							(mid -0.275042 -0.275042)
							(end -0.3048 -0.2032)
						)
						(arc
							(start -0.3048 0.2032)
							(mid -0.275042 0.275042)
							(end -0.2032 0.3048)
						)
						(arc
							(start 0.2032 0.3048)
							(mid 0.275042 0.275042)
							(end 0.3048 0.2032)
						)
					)
					(width 0)
					(fill yes)
				)
			)
		)
	)
	(footprint ""
		(layer "F.Cu")
		(at 175.26 -369.189 180)
		(property "Reference" "U21"
			(at 0 0 180)
			(layer "F.SilkS")
			(hide yes)
			(effects
				(font
					(size 1.27 1.27)
				)
			)
		)
		(property "Value" "ADM1278-2ACPZ-RL-1-GP"
			(at -4.7625 -7.4422 180)
			(unlocked yes)
			(layer "F.Fab")
			(hide yes)
			(effects
				(font
					(size 1.016 1.016)
					(thickness 0.1524)
				)
			)
		)
		(property "Device Type" "QFN32-G3D45-UH32"
			(at -4.7625 -8.9662 180)
			(unlocked yes)
			(layer "F.Fab")
			(hide yes)
			(effects
				(font
					(size 1.016 1.016)
					(thickness 0.1524)
				)
			)
		)
		(duplicate_pad_numbers_are_jumpers no)
		(fp_line
			(start 4.0513 -0.749808)
			(end 3.2893 -0.749808)
			(stroke
				(width 0.1524)
				(type default)
			)
			(layer "F.SilkS")
		)
		(fp_line
			(start 3.7973 1.749552)
			(end 3.2893 1.749552)
			(stroke
				(width 0.1524)
				(type default)
			)
			(layer "F.SilkS")
		)
		(fp_line
			(start 3.5179 3.5179)
			(end 2.2479 3.5179)
			(stroke
				(width 0.1524)
				(type default)
			)
			(layer "F.SilkS")
		)
		(fp_line
			(start 3.5179 2.2479)
			(end 3.5179 3.5179)
			(stroke
				(width 0.1524)
				(type default)
			)
			(layer "F.SilkS")
		)
		(fp_line
			(start -0.250698 4.0513)
			(end -0.250698 3.2893)
			(stroke
				(width 0.1524)
				(type default)
			)
			(layer "F.SilkS")
		)
		(fp_line
			(start -0.250698 -3.7973)
			(end -0.250698 -3.2893)
			(stroke
				(width 0.1524)
				(type default)
			)
			(layer "F.SilkS")
		)
		(fp_line
			(start -3.5179 3.5179)
			(end -2.2479 3.5179)
			(stroke
				(width 0.1524)
				(type default)
			)
			(layer "F.SilkS")
		)
		(fp_line
			(start -3.5179 2.2479)
			(end -3.5179 3.5179)
			(stroke
				(width 0.1524)
				(type default)
			)
			(layer "F.SilkS")
		)
		(fp_line
			(start -3.5179 -2.2479)
			(end -3.5179 -3.5179)
			(stroke
				(width 0.1524)
				(type default)
			)
			(layer "F.SilkS")
		)
		(fp_line
			(start -3.5179 -3.5179)
			(end -2.2479 -3.5179)
			(stroke
				(width 0.1524)
				(type default)
			)
			(layer "F.SilkS")
		)
		(fp_line
			(start -3.7973 1.24968)
			(end -3.2893 1.24968)
			(stroke
				(width 0.1524)
				(type default)
			)
			(layer "F.SilkS")
		)
		(fp_line
			(start -4.0513 -1.24968)
			(end -3.2893 -1.24968)
			(stroke
				(width 0.1524)
				(type default)
			)
			(layer "F.SilkS")
		)
		(fp_poly
			(pts
				(xy 2.2479 -3.5179) (xy 3.5179 -2.2479) (xy 3.5179 -3.5179)
			)
			(stroke
				(width 0)
				(type default)
			)
			(fill yes)
			(layer "F.SilkS")
		)
		(fp_rect
			(start -2.5019 2.5019)
			(end 2.5019 -2.5019)
			(stroke
				(width 0)
				(type default)
			)
			(fill no)
			(layer "F.CrtYd")
		)
		(fp_poly
			(pts
				(xy -3.5179 3.5179) (xy -3.5179 -3.5179) (xy 3.5179 -3.5179) (xy 3.5179 3.5179) (xy -2.49682 3.5179)
				(xy -2.49682 2.5019) (xy 2.5019 2.5019) (xy 2.5019 -2.5019) (xy -2.5019 -2.5019) (xy -2.5019 3.5179)
			)
			(stroke
				(width 0)
				(type default)
			)
			(fill no)
			(layer "F.CrtYd")
		)
		(fp_rect
			(start -3.5179 3.5179)
			(end 3.5179 -3.5179)
			(stroke
				(width 0)
				(type default)
			)
			(fill no)
			(layer "F.Fab")
		)
		(pad "1" smd rect
			(at 1.75006 -2.5527 180)
			(size 0.3048 0.9144)
			(layers "F.Cu" "F.Mask" "F.Paste")
			(net "MB0_PSET_R")
		)
		(pad "2" smd rect
			(at 1.249934 -2.4765 180)
			(size 0.3048 1.0668)
			(layers "F.Cu" "F.Mask" "F.Paste")
			(net "MB0_VCAP_R")
		)
		(pad "3" smd rect
			(at 0.750062 -2.4765 180)
			(size 0.3048 1.0668)
			(layers "F.Cu" "F.Mask" "F.Paste")
			(net "MB0_ISET_R")
		)
		(pad "4" smd rect
			(at 0.249936 -2.4765 180)
			(size 0.3048 1.0668)
			(layers "F.Cu" "F.Mask" "F.Paste")
			(net "MB0_ISTART_R")
		)
		(pad "5" smd rect
			(at -0.249936 -2.4765 180)
			(size 0.3048 1.0668)
			(layers "F.Cu" "F.Mask" "F.Paste")
			(net "MB0_TIME_R")
		)
		(pad "6" smd rect
			(at -0.750062 -2.4765 180)
			(size 0.3048 1.0668)
			(layers "F.Cu" "F.Mask" "F.Paste")
			(net "Net_978")
		)
		(pad "7" smd rect
			(at -1.249934 -2.4765 180)
			(size 0.3048 1.0668)
			(layers "F.Cu" "F.Mask" "F.Paste")
			(net "MB0_CM_ADR1_R")
		)
		(pad "8" smd rect
			(at -1.75006 -2.5527 180)
			(size 0.3048 0.9144)
			(layers "F.Cu" "F.Mask" "F.Paste")
			(net "MB0_CM_ADR2_R")
		)
		(pad "9" smd rect
			(at -2.5527 -1.75006 180)
			(size 0.9144 0.3048)
			(layers "F.Cu" "F.Mask" "F.Paste")
			(net "MB0_SPISS_PD")
		)
		(pad "10" smd rect
			(at -2.4765 -1.249934 180)
			(size 1.0668 0.3048)
			(layers "F.Cu" "F.Mask" "F.Paste")
			(net "Net_982")
		)
		(pad "11" smd rect
			(at -2.4765 -0.750062 180)
			(size 1.0668 0.3048)
			(layers "F.Cu" "F.Mask" "F.Paste")
			(net "Net_981")
		)
		(pad "12" smd rect
			(at -2.4765 -0.249936 180)
			(size 1.0668 0.3048)
			(layers "F.Cu" "F.Mask" "F.Paste")
			(net "MB0_HS_ENABLE")
		)
		(pad "13" smd rect
			(at -2.4765 0.249936 180)
			(size 1.0668 0.3048)
			(layers "F.Cu" "F.Mask" "F.Paste")
			(net "Net_980")
		)
		(pad "14" smd rect
			(at -2.4765 0.750062 180)
			(size 1.0668 0.3048)
			(layers "F.Cu" "F.Mask" "F.Paste")
			(net "Net_979")
		)
		(pad "15" smd rect
			(at -2.4765 1.249934 180)
			(size 1.0668 0.3048)
			(layers "F.Cu" "F.Mask" "F.Paste")
			(net "MB0_SDA_R")
		)
		(pad "16" smd rect
			(at -2.5527 1.75006 180)
			(size 0.9144 0.3048)
			(layers "F.Cu" "F.Mask" "F.Paste")
			(net "MB0_SCL_R")
		)
		(pad "17" smd rect
			(at -1.75006 2.5527 180)
			(size 0.3048 0.9144)
			(layers "F.Cu" "F.Mask" "F.Paste")
			(net "MB0_RETRY_R")
		)
		(pad "18" smd rect
			(at -1.249934 2.4765 180)
			(size 0.3048 1.0668)
			(layers "F.Cu" "F.Mask" "F.Paste")
			(net "P12V_IN_PGOOD")
		)
		(pad "19" smd rect
			(at -0.750062 2.4765 180)
			(size 0.3048 1.0668)
			(layers "F.Cu" "F.Mask" "F.Paste")
			(net "Net_983")
		)
		(pad "20" smd rect
			(at -0.249936 2.4765 180)
			(size 0.3048 1.0668)
			(layers "F.Cu" "F.Mask" "F.Paste")
			(net "MB0_CM_VOUT_R")
		)
		(pad "21" smd rect
			(at 0.249936 2.4765 180)
			(size 0.3048 1.0668)
			(layers "F.Cu" "F.Mask" "F.Paste")
			(net "MB0_P12V_PWGIN_R")
		)
		(pad "22" smd rect
			(at 0.750062 2.4765 180)
			(size 0.3048 1.0668)
			(layers "F.Cu" "F.Mask" "F.Paste")
			(net "AGND_CURRENT_MON")
		)
		(pad "23" smd rect
			(at 1.249934 2.4765 180)
			(size 0.3048 1.0668)
			(layers "F.Cu" "F.Mask" "F.Paste")
			(net "GND")
		)
		(pad "24" smd rect
			(at 1.75006 2.5527 180)
			(size 0.3048 0.9144)
			(layers "F.Cu" "F.Mask" "F.Paste")
			(net "MB0_CM_GATE")
		)
		(pad "25" smd rect
			(at 2.5527 1.75006 180)
			(size 0.9144 0.3048)
			(layers "F.Cu" "F.Mask" "F.Paste")
			(net "MB0_TEMP")
		)
		(pad "26" smd rect
			(at 2.4765 1.249934 180)
			(size 1.0668 0.3048)
			(layers "F.Cu" "F.Mask" "F.Paste")
			(net "MB0_CM_SENSE_N")
		)
		(pad "27" smd rect
			(at 2.4765 0.750062 180)
			(size 1.0668 0.3048)
			(layers "F.Cu" "F.Mask" "F.Paste")
			(net "MB0_HS_SENSE_N")
		)
		(pad "28" smd rect
			(at 2.4765 0.249936 180)
			(size 1.0668 0.3048)
			(layers "F.Cu" "F.Mask" "F.Paste")
			(net "MB0_HS_SENSE_P")
		)
		(pad "29" smd rect
			(at 2.4765 -0.249936 180)
			(size 1.0668 0.3048)
			(layers "F.Cu" "F.Mask" "F.Paste")
			(net "MB0_CM_SENSE_P")
		)
		(pad "30" smd rect
			(at 2.4765 -0.750062 180)
			(size 1.0668 0.3048)
			(layers "F.Cu" "F.Mask" "F.Paste")
			(net "MB0_P12V_HS")
		)
		(pad "31" smd rect
			(at 2.4765 -1.249934 180)
			(size 1.0668 0.3048)
			(layers "F.Cu" "F.Mask" "F.Paste")
			(net "MB0_CM_UV_R")
		)
		(pad "32" smd rect
			(at 2.5527 -1.75006 180)
			(size 0.9144 0.3048)
			(layers "F.Cu" "F.Mask" "F.Paste")
			(net "MB0_CM_OV_R")
		)
		(pad "33" smd rect
			(at 0 0 180)
			(size 3.4544 3.4544)
			(layers "F.Cu" "F.Mask" "F.Paste")
			(net "AGND_CURRENT_MON")
		)
	)
	(footprint ""
		(layer "F.Cu")
		(at 66.313812 -154.70505)
		(property "Reference" "TP86"
			(at 0 0 0)
			(layer "F.SilkS")
			(hide yes)
			(effects
				(font
					(size 1.27 1.27)
				)
			)
		)
		(property "Value" "*"
			(at -0.0508 -1.6764 0)
			(unlocked yes)
			(layer "F.Fab")
			(hide yes)
			(effects
				(font
					(size 1.016 1.016)
					(thickness 0.1524)
				)
			)
		)
		(property "Device Type" "TPAD32"
			(at -0.0508 -3.2004 0)
			(unlocked yes)
			(layer "F.Fab")
			(hide yes)
			(effects
				(font
					(size 1.016 1.016)
					(thickness 0.1524)
				)
			)
		)
		(duplicate_pad_numbers_are_jumpers no)
		(fp_poly
			(pts
				(arc
					(start 0.4064 0)
					(mid -0.4064 0)
					(end 0.4064 0)
				)
			)
			(stroke
				(width 0)
				(type default)
			)
			(fill no)
			(layer "F.CrtYd")
		)
		(fp_poly
			(pts
				(arc
					(start 0.7112 0)
					(mid -0.7112 0)
					(end 0.7112 0)
				)
			)
			(stroke
				(width 0)
				(type default)
			)
			(fill no)
			(layer "F.Fab")
		)
		(pad "1" smd circle
			(at 0 0)
			(size 0.8128 0.8128)
			(layers "F.Cu" "F.Mask" "F.Paste")
			(net "ACT_HDD_13")
		)
	)
	(footprint ""
		(layer "F.Cu")
		(at 52.64277 -110.565946 -90)
		(property "Reference" "C644"
			(at 0 0 270)
			(layer "F.SilkS")
			(hide yes)
			(effects
				(font
					(size 1.27 1.27)
				)
			)
		)
		(property "Value" "SC2200P50V2KX-2GP"
			(at 1.1811 -2.7051 270)
			(unlocked yes)
			(layer "F.Fab")
			(hide yes)
			(effects
				(font
					(size 1.016 1.016)
					(thickness 0.1524)
				)
			)
		)
		(property "Device Type" "C402H22"
			(at 1.1811 -4.2291 270)
			(unlocked yes)
			(layer "F.Fab")
			(hide yes)
			(effects
				(font
					(size 1.016 1.016)
					(thickness 0.1524)
				)
			)
		)
		(duplicate_pad_numbers_are_jumpers no)
		(fp_rect
			(start -0.4318 0.9525)
			(end 0.4318 -0.9525)
			(stroke
				(width 0)
				(type default)
			)
			(fill no)
			(layer "F.CrtYd")
		)
		(fp_rect
			(start -0.4318 0.9525)
			(end 0.4318 -0.9525)
			(stroke
				(width 0)
				(type default)
			)
			(fill no)
			(layer "F.Fab")
		)
		(pad "1" smd custom
			(at 0 -0.4445 270)
			(size 0.1524 0.1524)
			(layers "F.Cu" "F.Mask" "F.Paste")
			(net "P5V_B_2_LL")
			(options
				(clearance outline)
				(anchor circle)
			)
			(primitives
				(gr_poly
					(pts
						(arc
							(start 0.3048 -0.2032)
							(mid 0.275042 -0.275042)
							(end 0.2032 -0.3048)
						)
						(arc
							(start -0.2032 -0.3048)
							(mid -0.275042 -0.275042)
							(end -0.3048 -0.2032)
						)
						(arc
							(start -0.3048 0.2032)
							(mid -0.275042 0.275042)
							(end -0.2032 0.3048)
						)
						(arc
							(start 0.2032 0.3048)
							(mid 0.275042 0.275042)
							(end 0.3048 0.2032)
						)
					)
					(width 0)
					(fill yes)
				)
			)
		)
		(pad "2" smd custom
			(at 0 0.4445 270)
			(size 0.1524 0.1524)
			(layers "F.Cu" "F.Mask" "F.Paste")
			(net "P5V_B_2_SNB")
			(options
				(clearance outline)
				(anchor circle)
			)
			(primitives
				(gr_poly
					(pts
						(arc
							(start 0.3048 -0.2032)
							(mid 0.275042 -0.275042)
							(end 0.2032 -0.3048)
						)
						(arc
							(start -0.2032 -0.3048)
							(mid -0.275042 -0.275042)
							(end -0.3048 -0.2032)
						)
						(arc
							(start -0.3048 0.2032)
							(mid -0.275042 0.275042)
							(end -0.2032 0.3048)
						)
						(arc
							(start 0.2032 0.3048)
							(mid 0.275042 0.275042)
							(end 0.3048 0.2032)
						)
					)
					(width 0)
					(fill yes)
				)
			)
		)
	)
	(footprint ""
		(layer "F.Cu")
		(at 353.184714 -245.219474 -90)
		(property "Reference" "C119"
			(at 0 0 270)
			(layer "F.SilkS")
			(hide yes)
			(effects
				(font
					(size 1.27 1.27)
				)
			)
		)
		(property "Value" "SCD01U16V1KX-GP"
			(at -2.8321 -1.7399 270)
			(unlocked yes)
			(layer "F.Fab")
			(hide yes)
			(effects
				(font
					(size 1.016 1.016)
					(thickness 0.1524)
				)
			)
		)
		(property "Device Type" "C0201H13"
			(at -2.8321 -3.2639 270)
			(unlocked yes)
			(layer "F.Fab")
			(hide yes)
			(effects
				(font
					(size 1.016 1.016)
					(thickness 0.1524)
				)
			)
		)
		(duplicate_pad_numbers_are_jumpers no)
		(fp_rect
			(start -0.2794 0.6477)
			(end 0.2794 -0.6477)
			(stroke
				(width 0)
				(type default)
			)
			(fill no)
			(layer "F.CrtYd")
		)
		(fp_rect
			(start -0.2794 0.6477)
			(end 0.2794 -0.6477)
			(stroke
				(width 0)
				(type default)
			)
			(fill no)
			(layer "F.Fab")
		)
		(pad "1" smd custom
			(at 0 -0.2794 270)
			(size 0.0762 0.0762)
			(layers "F.Cu" "F.Mask" "F.Paste")
			(net "SAS_HDD_RX_N7")
			(options
				(clearance outline)
				(anchor circle)
			)
			(primitives
				(gr_poly
					(pts
						(arc
							(start 0.1524 -0.127)
							(mid 0.137521 -0.162921)
							(end 0.1016 -0.1778)
						)
						(arc
							(start -0.1016 -0.1778)
							(mid -0.137521 -0.162921)
							(end -0.1524 -0.127)
						)
						(arc
							(start -0.1524 0.127)
							(mid -0.137521 0.162921)
							(end -0.1016 0.1778)
						)
						(arc
							(start 0.1016 0.1778)
							(mid 0.137521 0.162921)
							(end 0.1524 0.127)
						)
					)
					(width 0)
					(fill yes)
				)
			)
		)
		(pad "2" smd custom
			(at 0 0.2794 270)
			(size 0.0762 0.0762)
			(layers "F.Cu" "F.Mask" "F.Paste")
			(net "PHY_SCC_B_TO_DRV_B_7_DN")
			(options
				(clearance outline)
				(anchor circle)
			)
			(primitives
				(gr_poly
					(pts
						(arc
							(start 0.1524 -0.127)
							(mid 0.137521 -0.162921)
							(end 0.1016 -0.1778)
						)
						(arc
							(start -0.1016 -0.1778)
							(mid -0.137521 -0.162921)
							(end -0.1524 -0.127)
						)
						(arc
							(start -0.1524 0.127)
							(mid -0.137521 0.162921)
							(end -0.1016 0.1778)
						)
						(arc
							(start 0.1016 0.1778)
							(mid 0.137521 0.162921)
							(end 0.1524 0.127)
						)
					)
					(width 0)
					(fill yes)
				)
			)
		)
	)
	(footprint ""
		(layer "F.Cu")
		(at 479.298 -45.339 180)
		(property "Reference" "C491"
			(at 0 0 180)
			(layer "F.SilkS")
			(hide yes)
			(effects
				(font
					(size 1.27 1.27)
				)
			)
		)
		(property "Value" "SC1U25V3KX-GP"
			(at 0 -2.8194 180)
			(unlocked yes)
			(layer "F.Fab")
			(hide yes)
			(effects
				(font
					(size 1.016 1.016)
					(thickness 0.1524)
				)
			)
		)
		(property "Device Type" "C603H36"
			(at 0 -4.3434 180)
			(unlocked yes)
			(layer "F.Fab")
			(hide yes)
			(effects
				(font
					(size 1.016 1.016)
					(thickness 0.1524)
				)
			)
		)
		(duplicate_pad_numbers_are_jumpers no)
		(fp_line
			(start 0.508 0)
			(end -0.508 0)
			(stroke
				(width 0.2032)
				(type default)
			)
			(layer "F.SilkS")
		)
		(fp_rect
			(start -0.5842 1.3335)
			(end 0.5842 -1.3335)
			(stroke
				(width 0)
				(type default)
			)
			(fill no)
			(layer "F.CrtYd")
		)
		(fp_rect
			(start -0.5842 1.3335)
			(end 0.5842 -1.3335)
			(stroke
				(width 0)
				(type default)
			)
			(fill no)
			(layer "F.Fab")
		)
		(pad "1" smd custom
			(at 0 -0.762 180)
			(size 0.2159 0.2159)
			(layers "F.Cu" "F.Mask" "F.Paste")
			(net "P12V_HDD35")
			(options
				(clearance outline)
				(anchor circle)
			)
			(primitives
				(gr_poly
					(pts
						(arc
							(start -0.3302 -0.4318)
							(mid -0.402042 -0.402042)
							(end -0.4318 -0.3302)
						)
						(arc
							(start -0.4318 0.3302)
							(mid -0.402042 0.402042)
							(end -0.3302 0.4318)
						)
						(arc
							(start 0.3302 0.4318)
							(mid 0.402042 0.402042)
							(end 0.4318 0.3302)
						)
						(arc
							(start 0.4318 -0.3302)
							(mid 0.402042 -0.402042)
							(end 0.3302 -0.4318)
						)
					)
					(width 0)
					(fill yes)
				)
			)
		)
		(pad "2" smd custom
			(at 0 0.762 180)
			(size 0.2159 0.2159)
			(layers "F.Cu" "F.Mask" "F.Paste")
			(net "GND")
			(options
				(clearance outline)
				(anchor circle)
			)
			(primitives
				(gr_poly
					(pts
						(arc
							(start -0.3302 -0.4318)
							(mid -0.402042 -0.402042)
							(end -0.4318 -0.3302)
						)
						(arc
							(start -0.4318 0.3302)
							(mid -0.402042 0.402042)
							(end -0.3302 0.4318)
						)
						(arc
							(start 0.3302 0.4318)
							(mid 0.402042 0.402042)
							(end 0.4318 0.3302)
						)
						(arc
							(start 0.4318 -0.3302)
							(mid 0.402042 -0.402042)
							(end 0.3302 -0.4318)
						)
					)
					(width 0)
					(fill yes)
				)
			)
		)
	)
	(footprint ""
		(layer "F.Cu")
		(at 465.3534 -99.3902)
		(property "Reference" "R458"
			(at 0 0 0)
			(layer "F.SilkS")
			(hide yes)
			(effects
				(font
					(size 1.27 1.27)
				)
			)
		)
		(property "Value" "91R3F-1-GP"
			(at -0.0254 -2.5146 0)
			(unlocked yes)
			(layer "F.Fab")
			(hide yes)
			(effects
				(font
					(size 1.016 1.016)
					(thickness 0.1524)
				)
			)
		)
		(property "Device Type" "R603H22"
			(at -0.0254 -4.0386 0)
			(unlocked yes)
			(layer "F.Fab")
			(hide yes)
			(effects
				(font
					(size 1.016 1.016)
					(thickness 0.1524)
				)
			)
		)
		(duplicate_pad_numbers_are_jumpers no)
		(fp_line
			(start -0.4826 0)
			(end -0.2032 0)
			(stroke
				(width 0.2032)
				(type default)
			)
			(layer "F.SilkS")
		)
		(fp_line
			(start 0.2032 0)
			(end 0.4826 0)
			(stroke
				(width 0.2032)
				(type default)
			)
			(layer "F.SilkS")
		)
		(fp_rect
			(start -0.5842 1.3335)
			(end 0.5842 -1.3335)
			(stroke
				(width 0)
				(type default)
			)
			(fill no)
			(layer "F.CrtYd")
		)
		(fp_rect
			(start -0.5842 1.3335)
			(end 0.5842 -1.3335)
			(stroke
				(width 0)
				(type default)
			)
			(fill no)
			(layer "F.Fab")
		)
		(pad "1" smd custom
			(at 0 -0.762)
			(size 0.2159 0.2159)
			(layers "F.Cu" "F.Mask" "F.Paste")
			(net "P5V_B_4")
			(options
				(clearance outline)
				(anchor circle)
			)
			(primitives
				(gr_poly
					(pts
						(arc
							(start -0.3302 -0.4318)
							(mid -0.402042 -0.402042)
							(end -0.4318 -0.3302)
						)
						(arc
							(start -0.4318 0.3302)
							(mid -0.402042 0.402042)
							(end -0.3302 0.4318)
						)
						(arc
							(start 0.3302 0.4318)
							(mid 0.402042 0.402042)
							(end 0.4318 0.3302)
						)
						(arc
							(start 0.4318 -0.3302)
							(mid 0.402042 -0.402042)
							(end 0.3302 -0.4318)
						)
					)
					(width 0)
					(fill yes)
				)
			)
		)
		(pad "2" smd custom
			(at 0 0.762)
			(size 0.2159 0.2159)
			(layers "F.Cu" "F.Mask" "F.Paste")
			(net "DRV_ACT_23")
			(options
				(clearance outline)
				(anchor circle)
			)
			(primitives
				(gr_poly
					(pts
						(arc
							(start -0.3302 -0.4318)
							(mid -0.402042 -0.402042)
							(end -0.4318 -0.3302)
						)
						(arc
							(start -0.4318 0.3302)
							(mid -0.402042 0.402042)
							(end -0.3302 0.4318)
						)
						(arc
							(start 0.3302 0.4318)
							(mid 0.402042 0.402042)
							(end 0.4318 0.3302)
						)
						(arc
							(start 0.4318 -0.3302)
							(mid 0.402042 -0.402042)
							(end 0.3302 -0.4318)
						)
					)
					(width 0)
					(fill yes)
				)
			)
		)
	)
	(footprint ""
		(layer "F.Cu")
		(at 249.69978 -211.19846)
		(property "Reference" "R114"
			(at 0 0 0)
			(layer "F.SilkS")
			(hide yes)
			(effects
				(font
					(size 1.27 1.27)
				)
			)
		)
		(property "Value" "10KR2F-2-GP"
			(at 0.064008 -3.993896 0)
			(unlocked yes)
			(layer "F.Fab")
			(hide yes)
			(effects
				(font
					(size 1.016 1.016)
					(thickness 0.1524)
				)
			)
		)
		(property "Device Type" "R402H16"
			(at 0.064008 -5.517896 0)
			(unlocked yes)
			(layer "F.Fab")
			(hide yes)
			(effects
				(font
					(size 1.016 1.016)
					(thickness 0.1524)
				)
			)
		)
		(duplicate_pad_numbers_are_jumpers no)
		(fp_line
			(start -0.508 -0.9398)
			(end -0.508 0.9398)
			(stroke
				(width 0.1524)
				(type default)
			)
			(layer "F.SilkS")
		)
		(fp_line
			(start 0.508 -0.9398)
			(end -0.508 -0.9398)
			(stroke
				(width 0.1524)
				(type default)
			)
			(layer "F.SilkS")
		)
		(fp_rect
			(start -0.508 0.9398)
			(end 0.508 -0.9398)
			(stroke
				(width 0)
				(type default)
			)
			(fill no)
			(layer "F.CrtYd")
		)
		(fp_rect
			(start -0.508 0.9398)
			(end 0.508 -0.9398)
			(stroke
				(width 0)
				(type default)
			)
			(fill no)
			(layer "F.Fab")
		)
		(pad "1" smd custom
			(at 0 -0.4445)
			(size 0.1397 0.1397)
			(layers "F.Cu" "F.Mask" "F.Paste")
			(net "EEPROM_WP")
			(options
				(clearance outline)
				(anchor circle)
			)
			(primitives
				(gr_poly
					(pts
						(arc
							(start -0.1778 -0.2794)
							(mid -0.249642 -0.249642)
							(end -0.2794 -0.1778)
						)
						(arc
							(start -0.2794 0.1778)
							(mid -0.249642 0.249642)
							(end -0.1778 0.2794)
						)
						(arc
							(start 0.1778 0.2794)
							(mid 0.249642 0.249642)
							(end 0.2794 0.1778)
						)
						(arc
							(start 0.2794 -0.1778)
							(mid 0.249642 -0.249642)
							(end 0.1778 -0.2794)
						)
					)
					(width 0)
					(fill yes)
				)
			)
		)
		(pad "2" smd custom
			(at 0 0.4445)
			(size 0.1397 0.1397)
			(layers "F.Cu" "F.Mask" "F.Paste")
			(net "GND")
			(options
				(clearance outline)
				(anchor circle)
			)
			(primitives
				(gr_poly
					(pts
						(arc
							(start -0.1778 -0.2794)
							(mid -0.249642 -0.249642)
							(end -0.2794 -0.1778)
						)
						(arc
							(start -0.2794 0.1778)
							(mid -0.249642 0.249642)
							(end -0.1778 0.2794)
						)
						(arc
							(start 0.1778 0.2794)
							(mid 0.249642 0.249642)
							(end 0.2794 0.1778)
						)
						(arc
							(start 0.2794 -0.1778)
							(mid 0.249642 -0.249642)
							(end 0.1778 -0.2794)
						)
					)
					(width 0)
					(fill yes)
				)
			)
		)
	)
	(footprint ""
		(layer "F.Cu")
		(at 465.140802 -231.52735)
		(property "Reference" "TP204"
			(at 0 0 0)
			(layer "F.SilkS")
			(hide yes)
			(effects
				(font
					(size 1.27 1.27)
				)
			)
		)
		(property "Value" "*"
			(at -0.0508 -1.6764 0)
			(unlocked yes)
			(layer "F.Fab")
			(hide yes)
			(effects
				(font
					(size 1.016 1.016)
					(thickness 0.1524)
				)
			)
		)
		(property "Device Type" "TPAD32"
			(at -0.0508 -3.2004 0)
			(unlocked yes)
			(layer "F.Fab")
			(hide yes)
			(effects
				(font
					(size 1.016 1.016)
					(thickness 0.1524)
				)
			)
		)
		(duplicate_pad_numbers_are_jumpers no)
		(fp_poly
			(pts
				(arc
					(start 0.4064 0)
					(mid -0.4064 0)
					(end 0.4064 0)
				)
			)
			(stroke
				(width 0)
				(type default)
			)
			(fill no)
			(layer "F.CrtYd")
		)
		(fp_poly
			(pts
				(arc
					(start 0.7112 0)
					(mid -0.7112 0)
					(end 0.7112 0)
				)
			)
			(stroke
				(width 0)
				(type default)
			)
			(fill no)
			(layer "F.Fab")
		)
		(pad "1" smd circle
			(at 0 0)
			(size 0.8128 0.8128)
			(layers "F.Cu" "F.Mask" "F.Paste")
			(net "P5V_B_3_PGOOD")
		)
	)
	(footprint ""
		(layer "F.Cu")
		(at 258.474972 -372.32971)
		(property "Reference" "R1037"
			(at 0 0 0)
			(layer "F.SilkS")
			(hide yes)
			(effects
				(font
					(size 1.27 1.27)
				)
			)
		)
		(property "Value" "10KR2F-2-GP"
			(at 0.064008 -3.993896 0)
			(unlocked yes)
			(layer "F.Fab")
			(hide yes)
			(effects
				(font
					(size 1.016 1.016)
					(thickness 0.1524)
				)
			)
		)
		(property "Device Type" "R402H16"
			(at 0.064008 -5.517896 0)
			(unlocked yes)
			(layer "F.Fab")
			(hide yes)
			(effects
				(font
					(size 1.016 1.016)
					(thickness 0.1524)
				)
			)
		)
		(duplicate_pad_numbers_are_jumpers no)
		(fp_line
			(start -0.508 -0.9398)
			(end -0.508 0.9398)
			(stroke
				(width 0.1524)
				(type default)
			)
			(layer "F.SilkS")
		)
		(fp_line
			(start 0.508 -0.9398)
			(end -0.508 -0.9398)
			(stroke
				(width 0.1524)
				(type default)
			)
			(layer "F.SilkS")
		)
		(fp_rect
			(start -0.508 0.9398)
			(end 0.508 -0.9398)
			(stroke
				(width 0)
				(type default)
			)
			(fill no)
			(layer "F.CrtYd")
		)
		(fp_rect
			(start -0.508 0.9398)
			(end 0.508 -0.9398)
			(stroke
				(width 0)
				(type default)
			)
			(fill no)
			(layer "F.Fab")
		)
		(pad "1" smd custom
			(at 0 -0.4445)
			(size 0.1397 0.1397)
			(layers "F.Cu" "F.Mask" "F.Paste")
			(net "P12V_B")
			(options
				(clearance outline)
				(anchor circle)
			)
			(primitives
				(gr_poly
					(pts
						(arc
							(start -0.1778 -0.2794)
							(mid -0.249642 -0.249642)
							(end -0.2794 -0.1778)
						)
						(arc
							(start -0.2794 0.1778)
							(mid -0.249642 0.249642)
							(end -0.1778 0.2794)
						)
						(arc
							(start 0.1778 0.2794)
							(mid 0.249642 0.249642)
							(end 0.2794 0.1778)
						)
						(arc
							(start 0.2794 -0.1778)
							(mid 0.249642 -0.249642)
							(end 0.1778 -0.2794)
						)
					)
					(width 0)
					(fill yes)
				)
			)
		)
		(pad "2" smd custom
			(at 0 0.4445)
			(size 0.1397 0.1397)
			(layers "F.Cu" "F.Mask" "F.Paste")
			(net "P12V_B_PGOOD")
			(options
				(clearance outline)
				(anchor circle)
			)
			(primitives
				(gr_poly
					(pts
						(arc
							(start -0.1778 -0.2794)
							(mid -0.249642 -0.249642)
							(end -0.2794 -0.1778)
						)
						(arc
							(start -0.2794 0.1778)
							(mid -0.249642 0.249642)
							(end -0.1778 0.2794)
						)
						(arc
							(start 0.1778 0.2794)
							(mid 0.249642 0.249642)
							(end 0.2794 0.1778)
						)
						(arc
							(start 0.2794 -0.1778)
							(mid 0.249642 -0.249642)
							(end 0.1778 -0.2794)
						)
					)
					(width 0)
					(fill yes)
				)
			)
		)
	)
	(footprint ""
		(layer "F.Cu")
		(at 32.508952 -133.75005 -90)
		(property "Reference" "VIA26"
			(at 0 0 270)
			(layer "F.SilkS")
			(hide yes)
			(effects
				(font
					(size 1.27 1.27)
				)
			)
		)
		(property "Value" "100OHM-8L-2D36MM-L16-GP"
			(at -3.4036 -0.4572 270)
			(unlocked yes)
			(layer "F.Fab")
			(hide yes)
			(effects
				(font
					(size 1.016 1.016)
					(thickness 0.1524)
				)
			)
		)
		(property "Device Type" "VIA-PCIE-4P-427097"
			(at -3.4036 -1.9812 270)
			(unlocked yes)
			(layer "F.Fab")
			(hide yes)
			(effects
				(font
					(size 1.016 1.016)
					(thickness 0.1524)
				)
			)
		)
		(duplicate_pad_numbers_are_jumpers no)
		(fp_rect
			(start -2.1336 0.4826)
			(end 2.1336 -0.4826)
			(stroke
				(width 0)
				(type default)
			)
			(fill no)
			(layer "F.CrtYd")
		)
		(fp_rect
			(start -2.1336 0.4826)
			(end 2.1336 -0.4826)
			(stroke
				(width 0)
				(type default)
			)
			(fill no)
			(layer "F.Fab")
		)
		(pad "1" thru_hole circle
			(at -1.651 0 270)
			(size 0.508 0.508)
			(drill 0.254)
			(layers "*.Cu" "*.Mask")
			(remove_unused_layers no)
			(net "GND")
			(clearance 0.2286)
			(thermal_gap 0.2286)
		)
		(pad "2" thru_hole circle
			(at -0.635 0 270)
			(size 0.508 0.508)
			(drill 0.254)
			(layers "*.Cu" "*.Mask")
			(remove_unused_layers no)
			(net "PHY_DRV_B_TO_SCC_B_12_DP")
			(clearance 0.2286)
			(thermal_gap 0.2286)
		)
		(pad "3" thru_hole circle
			(at 0.635 0 270)
			(size 0.508 0.508)
			(drill 0.254)
			(layers "*.Cu" "*.Mask")
			(remove_unused_layers no)
			(net "PHY_DRV_B_TO_SCC_B_12_DN")
			(clearance 0.2286)
			(thermal_gap 0.2286)
		)
		(pad "4" thru_hole circle
			(at 1.651 0 270)
			(size 0.508 0.508)
			(drill 0.254)
			(layers "*.Cu" "*.Mask")
			(remove_unused_layers no)
			(net "GND")
			(clearance 0.2286)
			(thermal_gap 0.2286)
		)
	)
	(footprint ""
		(layer "F.Cu")
		(at 96.324928 -293.799768)
		(property "Reference" ""
			(at 0 0 0)
			(layer "F.SilkS")
			(hide yes)
			(effects
				(font
					(size 1.27 1.27)
				)
			)
		)
		(property "Value" "*"
			(at -8.398764 -8.057642 0)
			(unlocked yes)
			(layer "F.Fab")
			(hide yes)
			(effects
				(font
					(size 1.016 1.016)
					(thickness 0.1524)
				)
			)
		)
		(duplicate_pad_numbers_are_jumpers no)
		(fp_poly
			(pts
				(arc
					(start 7.3152 0)
					(mid 0 7.3152)
					(end -7.3152 0)
				)
				(arc
					(start -7.3152 -5.9944)
					(mid 0 -13.3096)
					(end 7.3152 -5.9944)
				)
			)
			(stroke
				(width 0)
				(type default)
			)
			(fill no)
			(layer "B.CrtYd")
		)
		(fp_poly
			(pts
				(arc
					(start 7.3152 0)
					(mid 0 7.3152)
					(end -7.3152 0)
				)
				(arc
					(start -7.3152 -5.9944)
					(mid 0 -13.3096)
					(end 7.3152 -5.9944)
				)
			)
			(stroke
				(width 0)
				(type default)
			)
			(fill no)
			(layer "F.CrtYd")
		)
		(fp_poly
			(pts
				(arc
					(start 7.3152 0)
					(mid 0 7.3152)
					(end -7.3152 0)
				)
				(arc
					(start -7.3152 -5.9944)
					(mid 0 -13.3096)
					(end 7.3152 -5.9944)
				)
			)
			(stroke
				(width 0)
				(type default)
			)
			(fill no)
			(layer "B.Fab")
		)
		(fp_poly
			(pts
				(arc
					(start 7.3152 0)
					(mid 0 7.3152)
					(end -7.3152 0)
				)
				(arc
					(start -7.3152 -5.9944)
					(mid 0 -13.3096)
					(end 7.3152 -5.9944)
				)
			)
			(stroke
				(width 0)
				(type default)
			)
			(fill no)
			(layer "F.Fab")
		)
		(pad "1" thru_hole oval
			(at 0 0)
			(size 14.0208 20.0152)
			(drill 0.0254
				(offset 0 -2.9972)
			)
			(layers "*.Cu" "*.Mask")
			(remove_unused_layers no)
			(net "Net_38")
			(clearance -1.002284)
			(thermal_gap 0.1524)
			(padstack
				(mode front_inner_back)
				(layer "Inner"
					(shape custom)
					(size 2.928012 2.928012)
					(options
						(anchor circle)
					)
					(primitives
						(gr_poly
							(pts
								(arc
									(start 4.571746 -2.084324)
									(mid 0.000333 7.430372)
									(end -4.571492 -2.084324)
								)
								(arc
									(start -4.571492 -2.084324)
									(mid -3.570296 -3.611977)
									(end -2.875026 -5.30098)
								)
								(arc
									(start -2.875026 -5.30098)
									(mid 0.000217 -7.43089)
									(end 2.87528 -5.30098)
								)
								(arc
									(start 2.87528 -5.30098)
									(mid 3.570511 -3.611956)
									(end 4.571746 -2.084324)
								)
							)
							(width 0)
							(fill yes)
						)
					)
					(clearance 0.1524)
				)
				(layer "B.Cu"
					(shape oval)
					(size 14.0208 20.0152)
					(offset 0 -2.9972)
					(clearance -1.002284)
				)
			)
		)
		(zone
			(layers "F.Cu" "B.Cu" "In1.Cu" "In2.Cu" "In3.Cu" "In4.Cu" "In5.Cu" "In6.Cu")
			(hatch none 0.5)
			(connect_pads
				(clearance 0)
			)
			(min_thickness 0.25)
			(keepout
				(tracks not_allowed)
				(vias allowed)
				(pads allowed)
				(copperpour not_allowed)
				(footprints allowed)
			)
			(placement
				(enabled no)
				(sheetname "")
			)
			(fill
				(thermal_gap 0.5)
				(thermal_bridge_width 0.5)
				(island_removal_mode 0)
			)
			(polygon
				(pts
					(arc
						(start 89.314528 -299.794168)
						(mid 96.324928 -306.804568)
						(end 103.335328 -299.794168)
					)
					(arc
						(start 103.335328 -293.799768)
						(mid 96.324928 -286.789368)
						(end 89.314528 -293.799768)
					)
				)
			)
		)
	)
	(footprint ""
		(layer "F.Cu")
		(at 95.563436 -245.219474 90)
		(property "Reference" "C54"
			(at 0 0 90)
			(layer "F.SilkS")
			(hide yes)
			(effects
				(font
					(size 1.27 1.27)
				)
			)
		)
		(property "Value" "SCD01U16V1KX-GP"
			(at -2.8321 -1.7399 90)
			(unlocked yes)
			(layer "F.Fab")
			(hide yes)
			(effects
				(font
					(size 1.016 1.016)
					(thickness 0.1524)
				)
			)
		)
		(property "Device Type" "C0201H13"
			(at -2.8321 -3.2639 90)
			(unlocked yes)
			(layer "F.Fab")
			(hide yes)
			(effects
				(font
					(size 1.016 1.016)
					(thickness 0.1524)
				)
			)
		)
		(duplicate_pad_numbers_are_jumpers no)
		(fp_rect
			(start -0.2794 0.6477)
			(end 0.2794 -0.6477)
			(stroke
				(width 0)
				(type default)
			)
			(fill no)
			(layer "F.CrtYd")
		)
		(fp_rect
			(start -0.2794 0.6477)
			(end 0.2794 -0.6477)
			(stroke
				(width 0)
				(type default)
			)
			(fill no)
			(layer "F.Fab")
		)
		(pad "1" smd custom
			(at 0 -0.2794 90)
			(size 0.0762 0.0762)
			(layers "F.Cu" "F.Mask" "F.Paste")
			(net "SAS_HDD_RX_N2")
			(options
				(clearance outline)
				(anchor circle)
			)
			(primitives
				(gr_poly
					(pts
						(arc
							(start 0.1524 -0.127)
							(mid 0.137521 -0.162921)
							(end 0.1016 -0.1778)
						)
						(arc
							(start -0.1016 -0.1778)
							(mid -0.137521 -0.162921)
							(end -0.1524 -0.127)
						)
						(arc
							(start -0.1524 0.127)
							(mid -0.137521 0.162921)
							(end -0.1016 0.1778)
						)
						(arc
							(start 0.1016 0.1778)
							(mid 0.137521 0.162921)
							(end 0.1524 0.127)
						)
					)
					(width 0)
					(fill yes)
				)
			)
		)
		(pad "2" smd custom
			(at 0 0.2794 90)
			(size 0.0762 0.0762)
			(layers "F.Cu" "F.Mask" "F.Paste")
			(net "PHY_SCC_B_TO_DRV_B_2_DN")
			(options
				(clearance outline)
				(anchor circle)
			)
			(primitives
				(gr_poly
					(pts
						(arc
							(start 0.1524 -0.127)
							(mid 0.137521 -0.162921)
							(end 0.1016 -0.1778)
						)
						(arc
							(start -0.1016 -0.1778)
							(mid -0.137521 -0.162921)
							(end -0.1524 -0.127)
						)
						(arc
							(start -0.1524 0.127)
							(mid -0.137521 0.162921)
							(end -0.1016 0.1778)
						)
						(arc
							(start 0.1016 0.1778)
							(mid 0.137521 0.162921)
							(end 0.1524 0.127)
						)
					)
					(width 0)
					(fill yes)
				)
			)
		)
	)
	(footprint ""
		(layer "F.Cu")
		(at 16.764 -23.114 90)
		(property "Reference" "R629"
			(at 0 0 90)
			(layer "F.SilkS")
			(hide yes)
			(effects
				(font
					(size 1.27 1.27)
				)
			)
		)
		(property "Value" "4K7R2J-2-GP"
			(at 0.064008 -3.993896 90)
			(unlocked yes)
			(layer "F.Fab")
			(hide yes)
			(effects
				(font
					(size 1.016 1.016)
					(thickness 0.1524)
				)
			)
		)
		(property "Device Type" "R402H16"
			(at 0.064008 -5.517896 90)
			(unlocked yes)
			(layer "F.Fab")
			(hide yes)
			(effects
				(font
					(size 1.016 1.016)
					(thickness 0.1524)
				)
			)
		)
		(duplicate_pad_numbers_are_jumpers no)
		(fp_line
			(start 0.508 -0.9398)
			(end -0.508 -0.9398)
			(stroke
				(width 0.1524)
				(type default)
			)
			(layer "F.SilkS")
		)
		(fp_line
			(start -0.508 -0.9398)
			(end -0.508 0.9398)
			(stroke
				(width 0.1524)
				(type default)
			)
			(layer "F.SilkS")
		)
		(fp_rect
			(start -0.508 0.9398)
			(end 0.508 -0.9398)
			(stroke
				(width 0)
				(type default)
			)
			(fill no)
			(layer "F.CrtYd")
		)
		(fp_rect
			(start -0.508 0.9398)
			(end 0.508 -0.9398)
			(stroke
				(width 0)
				(type default)
			)
			(fill no)
			(layer "F.Fab")
		)
		(pad "1" smd custom
			(at 0 -0.4445 90)
			(size 0.1397 0.1397)
			(layers "F.Cu" "F.Mask" "F.Paste")
			(net "P12V_B")
			(options
				(clearance outline)
				(anchor circle)
			)
			(primitives
				(gr_poly
					(pts
						(arc
							(start -0.1778 -0.2794)
							(mid -0.249642 -0.249642)
							(end -0.2794 -0.1778)
						)
						(arc
							(start -0.2794 0.1778)
							(mid -0.249642 0.249642)
							(end -0.1778 0.2794)
						)
						(arc
							(start 0.1778 0.2794)
							(mid 0.249642 0.249642)
							(end 0.2794 0.1778)
						)
						(arc
							(start 0.2794 -0.1778)
							(mid 0.249642 -0.249642)
							(end 0.1778 -0.2794)
						)
					)
					(width 0)
					(fill yes)
				)
			)
		)
		(pad "2" smd custom
			(at 0 0.4445 90)
			(size 0.1397 0.1397)
			(layers "F.Cu" "F.Mask" "F.Paste")
			(net "SW_HDD_P24")
			(options
				(clearance outline)
				(anchor circle)
			)
			(primitives
				(gr_poly
					(pts
						(arc
							(start -0.1778 -0.2794)
							(mid -0.249642 -0.249642)
							(end -0.2794 -0.1778)
						)
						(arc
							(start -0.2794 0.1778)
							(mid -0.249642 0.249642)
							(end -0.1778 0.2794)
						)
						(arc
							(start 0.1778 0.2794)
							(mid 0.249642 0.249642)
							(end 0.2794 0.1778)
						)
						(arc
							(start 0.2794 -0.1778)
							(mid 0.249642 -0.249642)
							(end 0.1778 -0.2794)
						)
					)
					(width 0)
					(fill yes)
				)
			)
		)
	)
	(footprint ""
		(layer "F.Cu")
		(at 331.089 -10.16)
		(property "Reference" "R773"
			(at 0 0 0)
			(layer "F.SilkS")
			(hide yes)
			(effects
				(font
					(size 1.27 1.27)
				)
			)
		)
		(property "Value" "4K7R2F-GP"
			(at 0.064008 -3.993896 0)
			(unlocked yes)
			(layer "F.Fab")
			(hide yes)
			(effects
				(font
					(size 1.016 1.016)
					(thickness 0.1524)
				)
			)
		)
		(property "Device Type" "R402H16"
			(at 0.064008 -5.517896 0)
			(unlocked yes)
			(layer "F.Fab")
			(hide yes)
			(effects
				(font
					(size 1.016 1.016)
					(thickness 0.1524)
				)
			)
		)
		(duplicate_pad_numbers_are_jumpers no)
		(fp_line
			(start -0.508 -0.9398)
			(end -0.508 0.9398)
			(stroke
				(width 0.1524)
				(type default)
			)
			(layer "F.SilkS")
		)
		(fp_line
			(start 0.508 -0.9398)
			(end -0.508 -0.9398)
			(stroke
				(width 0.1524)
				(type default)
			)
			(layer "F.SilkS")
		)
		(fp_rect
			(start -0.508 0.9398)
			(end 0.508 -0.9398)
			(stroke
				(width 0)
				(type default)
			)
			(fill no)
			(layer "F.CrtYd")
		)
		(fp_rect
			(start -0.508 0.9398)
			(end 0.508 -0.9398)
			(stroke
				(width 0)
				(type default)
			)
			(fill no)
			(layer "F.Fab")
		)
		(pad "1" smd custom
			(at 0 -0.4445)
			(size 0.1397 0.1397)
			(layers "F.Cu" "F.Mask" "F.Paste")
			(net "SW_PWR_R_HDD30")
			(options
				(clearance outline)
				(anchor circle)
			)
			(primitives
				(gr_poly
					(pts
						(arc
							(start -0.1778 -0.2794)
							(mid -0.249642 -0.249642)
							(end -0.2794 -0.1778)
						)
						(arc
							(start -0.2794 0.1778)
							(mid -0.249642 0.249642)
							(end -0.1778 0.2794)
						)
						(arc
							(start 0.1778 0.2794)
							(mid 0.249642 0.249642)
							(end 0.2794 0.1778)
						)
						(arc
							(start 0.2794 -0.1778)
							(mid 0.249642 -0.249642)
							(end 0.1778 -0.2794)
						)
					)
					(width 0)
					(fill yes)
				)
			)
		)
		(pad "2" smd custom
			(at 0 0.4445)
			(size 0.1397 0.1397)
			(layers "F.Cu" "F.Mask" "F.Paste")
			(net "GND")
			(options
				(clearance outline)
				(anchor circle)
			)
			(primitives
				(gr_poly
					(pts
						(arc
							(start -0.1778 -0.2794)
							(mid -0.249642 -0.249642)
							(end -0.2794 -0.1778)
						)
						(arc
							(start -0.2794 0.1778)
							(mid -0.249642 0.249642)
							(end -0.1778 0.2794)
						)
						(arc
							(start 0.1778 0.2794)
							(mid 0.249642 0.249642)
							(end 0.2794 0.1778)
						)
						(arc
							(start 0.2794 -0.1778)
							(mid 0.249642 -0.249642)
							(end 0.1778 -0.2794)
						)
					)
					(width 0)
					(fill yes)
				)
			)
		)
	)
	(footprint ""
		(layer "F.Cu")
		(at 222.123 -203.962 -90)
		(property "Reference" "R51"
			(at 0 0 270)
			(layer "F.SilkS")
			(hide yes)
			(effects
				(font
					(size 1.27 1.27)
				)
			)
		)
		(property "Value" "4K7R2F-GP"
			(at 0.064008 -3.993896 270)
			(unlocked yes)
			(layer "F.Fab")
			(hide yes)
			(effects
				(font
					(size 1.016 1.016)
					(thickness 0.1524)
				)
			)
		)
		(property "Device Type" "R402H16"
			(at 0.064008 -5.517896 270)
			(unlocked yes)
			(layer "F.Fab")
			(hide yes)
			(effects
				(font
					(size 1.016 1.016)
					(thickness 0.1524)
				)
			)
		)
		(duplicate_pad_numbers_are_jumpers no)
		(fp_line
			(start -0.508 -0.9398)
			(end -0.508 0.9398)
			(stroke
				(width 0.1524)
				(type default)
			)
			(layer "F.SilkS")
		)
		(fp_line
			(start 0.508 -0.9398)
			(end -0.508 -0.9398)
			(stroke
				(width 0.1524)
				(type default)
			)
			(layer "F.SilkS")
		)
		(fp_rect
			(start -0.508 0.9398)
			(end 0.508 -0.9398)
			(stroke
				(width 0)
				(type default)
			)
			(fill no)
			(layer "F.CrtYd")
		)
		(fp_rect
			(start -0.508 0.9398)
			(end 0.508 -0.9398)
			(stroke
				(width 0)
				(type default)
			)
			(fill no)
			(layer "F.Fab")
		)
		(pad "1" smd custom
			(at 0 -0.4445 270)
			(size 0.1397 0.1397)
			(layers "F.Cu" "F.Mask" "F.Paste")
			(net "P3V3_STBY_B")
			(options
				(clearance outline)
				(anchor circle)
			)
			(primitives
				(gr_poly
					(pts
						(arc
							(start -0.1778 -0.2794)
							(mid -0.249642 -0.249642)
							(end -0.2794 -0.1778)
						)
						(arc
							(start -0.2794 0.1778)
							(mid -0.249642 0.249642)
							(end -0.1778 0.2794)
						)
						(arc
							(start 0.1778 0.2794)
							(mid 0.249642 0.249642)
							(end 0.2794 0.1778)
						)
						(arc
							(start 0.2794 -0.1778)
							(mid 0.249642 -0.249642)
							(end 0.1778 -0.2794)
						)
					)
					(width 0)
					(fill yes)
				)
			)
		)
		(pad "2" smd custom
			(at 0 0.4445 270)
			(size 0.1397 0.1397)
			(layers "F.Cu" "F.Mask" "F.Paste")
			(net "IO_EXP5_A1")
			(options
				(clearance outline)
				(anchor circle)
			)
			(primitives
				(gr_poly
					(pts
						(arc
							(start -0.1778 -0.2794)
							(mid -0.249642 -0.249642)
							(end -0.2794 -0.1778)
						)
						(arc
							(start -0.2794 0.1778)
							(mid -0.249642 0.249642)
							(end -0.1778 0.2794)
						)
						(arc
							(start 0.1778 0.2794)
							(mid 0.249642 0.249642)
							(end 0.2794 0.1778)
						)
						(arc
							(start 0.2794 -0.1778)
							(mid 0.249642 -0.249642)
							(end 0.1778 -0.2794)
						)
					)
					(width 0)
					(fill yes)
				)
			)
		)
	)
	(footprint ""
		(layer "F.Cu")
		(at 464.82 -257.81 -90)
		(property "Reference" "R329"
			(at 0 0 270)
			(layer "F.SilkS")
			(hide yes)
			(effects
				(font
					(size 1.27 1.27)
				)
			)
		)
		(property "Value" "300KR2F-GP"
			(at 0.064008 -3.993896 270)
			(unlocked yes)
			(layer "F.Fab")
			(hide yes)
			(effects
				(font
					(size 1.016 1.016)
					(thickness 0.1524)
				)
			)
		)
		(property "Device Type" "R402H16"
			(at 0.064008 -5.517896 270)
			(unlocked yes)
			(layer "F.Fab")
			(hide yes)
			(effects
				(font
					(size 1.016 1.016)
					(thickness 0.1524)
				)
			)
		)
		(duplicate_pad_numbers_are_jumpers no)
		(fp_line
			(start -0.508 -0.9398)
			(end -0.508 0.9398)
			(stroke
				(width 0.1524)
				(type default)
			)
			(layer "F.SilkS")
		)
		(fp_line
			(start 0.508 -0.9398)
			(end -0.508 -0.9398)
			(stroke
				(width 0.1524)
				(type default)
			)
			(layer "F.SilkS")
		)
		(fp_rect
			(start -0.508 0.9398)
			(end 0.508 -0.9398)
			(stroke
				(width 0)
				(type default)
			)
			(fill no)
			(layer "F.CrtYd")
		)
		(fp_rect
			(start -0.508 0.9398)
			(end 0.508 -0.9398)
			(stroke
				(width 0)
				(type default)
			)
			(fill no)
			(layer "F.Fab")
		)
		(pad "1" smd custom
			(at 0 -0.4445 270)
			(size 0.1397 0.1397)
			(layers "F.Cu" "F.Mask" "F.Paste")
			(net "SW_HDD_N10")
			(options
				(clearance outline)
				(anchor circle)
			)
			(primitives
				(gr_poly
					(pts
						(arc
							(start -0.1778 -0.2794)
							(mid -0.249642 -0.249642)
							(end -0.2794 -0.1778)
						)
						(arc
							(start -0.2794 0.1778)
							(mid -0.249642 0.249642)
							(end -0.1778 0.2794)
						)
						(arc
							(start 0.1778 0.2794)
							(mid 0.249642 0.249642)
							(end 0.2794 0.1778)
						)
						(arc
							(start 0.2794 -0.1778)
							(mid 0.249642 -0.249642)
							(end 0.1778 -0.2794)
						)
					)
					(width 0)
					(fill yes)
				)
			)
		)
		(pad "2" smd custom
			(at 0 0.4445 270)
			(size 0.1397 0.1397)
			(layers "F.Cu" "F.Mask" "F.Paste")
			(net "P12V_B")
			(options
				(clearance outline)
				(anchor circle)
			)
			(primitives
				(gr_poly
					(pts
						(arc
							(start -0.1778 -0.2794)
							(mid -0.249642 -0.249642)
							(end -0.2794 -0.1778)
						)
						(arc
							(start -0.2794 0.1778)
							(mid -0.249642 0.249642)
							(end -0.1778 0.2794)
						)
						(arc
							(start 0.1778 0.2794)
							(mid 0.249642 0.249642)
							(end 0.2794 0.1778)
						)
						(arc
							(start 0.2794 -0.1778)
							(mid 0.249642 -0.249642)
							(end 0.1778 -0.2794)
						)
					)
					(width 0)
					(fill yes)
				)
			)
		)
	)
	(footprint ""
		(layer "F.Cu")
		(at 206.756 -348.361 90)
		(property "Reference" "R1018"
			(at 0 0 90)
			(layer "F.SilkS")
			(hide yes)
			(effects
				(font
					(size 1.27 1.27)
				)
			)
		)
		(property "Value" "10R5F-1-GP"
			(at 0 -8.9535 90)
			(unlocked yes)
			(layer "F.Fab")
			(hide yes)
			(effects
				(font
					(size 1.27 1.016)
					(thickness 0.1524)
				)
			)
		)
		(property "Device Type" "R805H24"
			(at 0 -10.6299 90)
			(unlocked yes)
			(layer "F.Fab")
			(hide yes)
			(effects
				(font
					(size 1.27 1.016)
					(thickness 0.1524)
				)
			)
		)
		(duplicate_pad_numbers_are_jumpers no)
		(fp_line
			(start 0.889 -1.7018)
			(end -0.889 -1.7018)
			(stroke
				(width 0.1524)
				(type default)
			)
			(layer "F.SilkS")
		)
		(fp_line
			(start 0.889 -1.7018)
			(end 0.889 -0.381)
			(stroke
				(width 0.1524)
				(type default)
			)
			(layer "F.SilkS")
		)
		(fp_line
			(start -0.889 -1.7018)
			(end -0.889 0.2794)
			(stroke
				(width 0.1524)
				(type default)
			)
			(layer "F.SilkS")
		)
		(fp_line
			(start -0.889 0.0762)
			(end -0.889 1.7018)
			(stroke
				(width 0.1524)
				(type default)
			)
			(layer "F.SilkS")
		)
		(fp_line
			(start 0.889 1.7018)
			(end 0.889 -0.508)
			(stroke
				(width 0.1524)
				(type default)
			)
			(layer "F.SilkS")
		)
		(fp_line
			(start -0.889 1.7018)
			(end 0.889 1.7018)
			(stroke
				(width 0.1524)
				(type default)
			)
			(layer "F.SilkS")
		)
		(fp_poly
			(pts
				(xy 0.9652 -1.778) (xy 0.9652 1.778) (xy -0.9652 1.778) (xy -0.9652 -1.778)
			)
			(stroke
				(width 0)
				(type default)
			)
			(fill no)
			(layer "F.CrtYd")
		)
		(fp_rect
			(start -0.9652 1.778)
			(end 0.9652 -1.778)
			(stroke
				(width 0)
				(type default)
			)
			(fill no)
			(layer "F.Fab")
		)
		(pad "1" smd rect
			(at 0 -0.9652 90)
			(size 1.397 1.143)
			(layers "F.Cu" "F.Mask" "F.Paste")
			(net "MB0_12V_CTRL_GATE4")
		)
		(pad "2" smd rect
			(at 0 0.9652 90)
			(size 1.397 1.143)
			(layers "F.Cu" "F.Mask" "F.Paste")
			(net "MB0_CM_GATE_R")
		)
	)
	(footprint ""
		(layer "F.Cu")
		(at 24.257 -45.466 180)
		(property "Reference" "C348"
			(at 0 0 180)
			(layer "F.SilkS")
			(hide yes)
			(effects
				(font
					(size 1.27 1.27)
				)
			)
		)
		(property "Value" "SC1U25V3KX-GP"
			(at 0 -2.8194 180)
			(unlocked yes)
			(layer "F.Fab")
			(hide yes)
			(effects
				(font
					(size 1.016 1.016)
					(thickness 0.1524)
				)
			)
		)
		(property "Device Type" "C603H36"
			(at 0 -4.3434 180)
			(unlocked yes)
			(layer "F.Fab")
			(hide yes)
			(effects
				(font
					(size 1.016 1.016)
					(thickness 0.1524)
				)
			)
		)
		(duplicate_pad_numbers_are_jumpers no)
		(fp_line
			(start 0.508 0)
			(end -0.508 0)
			(stroke
				(width 0.2032)
				(type default)
			)
			(layer "F.SilkS")
		)
		(fp_rect
			(start -0.5842 1.3335)
			(end 0.5842 -1.3335)
			(stroke
				(width 0)
				(type default)
			)
			(fill no)
			(layer "F.CrtYd")
		)
		(fp_rect
			(start -0.5842 1.3335)
			(end 0.5842 -1.3335)
			(stroke
				(width 0)
				(type default)
			)
			(fill no)
			(layer "F.Fab")
		)
		(pad "1" smd custom
			(at 0 -0.762 180)
			(size 0.2159 0.2159)
			(layers "F.Cu" "F.Mask" "F.Paste")
			(net "P12V_HDD24")
			(options
				(clearance outline)
				(anchor circle)
			)
			(primitives
				(gr_poly
					(pts
						(arc
							(start -0.3302 -0.4318)
							(mid -0.402042 -0.402042)
							(end -0.4318 -0.3302)
						)
						(arc
							(start -0.4318 0.3302)
							(mid -0.402042 0.402042)
							(end -0.3302 0.4318)
						)
						(arc
							(start 0.3302 0.4318)
							(mid 0.402042 0.402042)
							(end 0.4318 0.3302)
						)
						(arc
							(start 0.4318 -0.3302)
							(mid 0.402042 -0.402042)
							(end 0.3302 -0.4318)
						)
					)
					(width 0)
					(fill yes)
				)
			)
		)
		(pad "2" smd custom
			(at 0 0.762 180)
			(size 0.2159 0.2159)
			(layers "F.Cu" "F.Mask" "F.Paste")
			(net "GND")
			(options
				(clearance outline)
				(anchor circle)
			)
			(primitives
				(gr_poly
					(pts
						(arc
							(start -0.3302 -0.4318)
							(mid -0.402042 -0.402042)
							(end -0.4318 -0.3302)
						)
						(arc
							(start -0.4318 0.3302)
							(mid -0.402042 0.402042)
							(end -0.3302 0.4318)
						)
						(arc
							(start 0.3302 0.4318)
							(mid 0.402042 0.402042)
							(end 0.4318 0.3302)
						)
						(arc
							(start 0.4318 -0.3302)
							(mid 0.402042 -0.402042)
							(end 0.3302 -0.4318)
						)
					)
					(width 0)
					(fill yes)
				)
			)
		)
	)
	(footprint ""
		(layer "F.Cu")
		(at 237.236 -219.964 180)
		(property "Reference" "Q17"
			(at 0 0 180)
			(layer "F.SilkS")
			(hide yes)
			(effects
				(font
					(size 1.27 1.27)
				)
			)
		)
		(property "Value" "SSM3K324R-GP"
			(at 0.127 -8.9662 180)
			(unlocked yes)
			(layer "F.Fab")
			(hide yes)
			(effects
				(font
					(size 1.016 1.016)
					(thickness 0.1524)
				)
			)
		)
		(property "Device Type" "SOT23DGS2D4H35"
			(at 0.127 -10.4902 180)
			(unlocked yes)
			(layer "F.Fab")
			(hide yes)
			(effects
				(font
					(size 1.016 1.016)
					(thickness 0.1524)
				)
			)
		)
		(duplicate_pad_numbers_are_jumpers no)
		(fp_line
			(start 1.651 1.778)
			(end 1.651 -1.778)
			(stroke
				(width 0.1524)
				(type default)
			)
			(layer "F.SilkS")
		)
		(fp_line
			(start 1.651 -1.778)
			(end -1.651 -1.778)
			(stroke
				(width 0.1524)
				(type default)
			)
			(layer "F.SilkS")
		)
		(fp_line
			(start -1.651 1.778)
			(end 1.651 1.778)
			(stroke
				(width 0.1524)
				(type default)
			)
			(layer "F.SilkS")
		)
		(fp_line
			(start -1.651 -1.778)
			(end -1.651 1.778)
			(stroke
				(width 0.1524)
				(type default)
			)
			(layer "F.SilkS")
		)
		(fp_poly
			(pts
				(xy -1.778 1.8796) (xy -1.778 -1.8796) (xy 1.778 -1.8796) (xy 1.778 1.8796)
			)
			(stroke
				(width 0)
				(type default)
			)
			(fill no)
			(layer "F.CrtYd")
		)
		(fp_poly
			(pts
				(xy -1.778 1.8796) (xy -1.778 -1.8796) (xy 1.778 -1.8796) (xy 1.778 1.8796)
			)
			(stroke
				(width 0)
				(type default)
			)
			(fill no)
			(layer "F.Fab")
		)
		(pad "D" smd custom
			(at 0 -0.9525 180)
			(size 0.1905 0.1905)
			(layers "F.Cu" "F.Mask" "F.Paste")
			(net "P3V3_STBY_B")
			(options
				(clearance outline)
				(anchor circle)
			)
			(primitives
				(gr_poly
					(pts
						(arc
							(start -0.1778 0.5715)
							(mid -0.321484 0.511984)
							(end -0.381 0.3683)
						)
						(arc
							(start -0.381 -0.3683)
							(mid -0.321484 -0.511984)
							(end -0.1778 -0.5715)
						)
						(arc
							(start 0.1778 -0.5715)
							(mid 0.321484 -0.511984)
							(end 0.381 -0.3683)
						)
						(arc
							(start 0.381 0.3683)
							(mid 0.321484 0.511984)
							(end 0.1778 0.5715)
						)
					)
					(width 0)
					(fill yes)
				)
			)
		)
		(pad "G" smd custom
			(at -0.98425 0.9525 180)
			(size 0.1905 0.1905)
			(layers "F.Cu" "F.Mask" "F.Paste")
			(net "SCC_FULL_PWR_EN_5V")
			(options
				(clearance outline)
				(anchor circle)
			)
			(primitives
				(gr_poly
					(pts
						(arc
							(start -0.1778 0.5715)
							(mid -0.321484 0.511984)
							(end -0.381 0.3683)
						)
						(arc
							(start -0.381 -0.3683)
							(mid -0.321484 -0.511984)
							(end -0.1778 -0.5715)
						)
						(arc
							(start 0.1778 -0.5715)
							(mid 0.321484 -0.511984)
							(end 0.381 -0.3683)
						)
						(arc
							(start 0.381 0.3683)
							(mid 0.321484 0.511984)
							(end 0.1778 0.5715)
						)
					)
					(width 0)
					(fill yes)
				)
			)
		)
		(pad "S" smd custom
			(at 0.98425 0.9525 180)
			(size 0.1905 0.1905)
			(layers "F.Cu" "F.Mask" "F.Paste")
			(net "GPIO_VCC_U8")
			(options
				(clearance outline)
				(anchor circle)
			)
			(primitives
				(gr_poly
					(pts
						(arc
							(start -0.1778 0.5715)
							(mid -0.321484 0.511984)
							(end -0.381 0.3683)
						)
						(arc
							(start -0.381 -0.3683)
							(mid -0.321484 -0.511984)
							(end -0.1778 -0.5715)
						)
						(arc
							(start 0.1778 -0.5715)
							(mid 0.321484 -0.511984)
							(end 0.381 -0.3683)
						)
						(arc
							(start 0.381 0.3683)
							(mid 0.321484 0.511984)
							(end 0.1778 0.5715)
						)
					)
					(width 0)
					(fill yes)
				)
			)
		)
	)
	(footprint ""
		(layer "F.Cu")
		(at 479.384614 -245.219474 -90)
		(property "Reference" "C171"
			(at 0 0 270)
			(layer "F.SilkS")
			(hide yes)
			(effects
				(font
					(size 1.27 1.27)
				)
			)
		)
		(property "Value" "SCD01U16V1KX-GP"
			(at -2.8321 -1.7399 270)
			(unlocked yes)
			(layer "F.Fab")
			(hide yes)
			(effects
				(font
					(size 1.016 1.016)
					(thickness 0.1524)
				)
			)
		)
		(property "Device Type" "C0201H13"
			(at -2.8321 -3.2639 270)
			(unlocked yes)
			(layer "F.Fab")
			(hide yes)
			(effects
				(font
					(size 1.016 1.016)
					(thickness 0.1524)
				)
			)
		)
		(duplicate_pad_numbers_are_jumpers no)
		(fp_rect
			(start -0.2794 0.6477)
			(end 0.2794 -0.6477)
			(stroke
				(width 0)
				(type default)
			)
			(fill no)
			(layer "F.CrtYd")
		)
		(fp_rect
			(start -0.2794 0.6477)
			(end 0.2794 -0.6477)
			(stroke
				(width 0)
				(type default)
			)
			(fill no)
			(layer "F.Fab")
		)
		(pad "1" smd custom
			(at 0 -0.2794 270)
			(size 0.0762 0.0762)
			(layers "F.Cu" "F.Mask" "F.Paste")
			(net "SAS_HDD_RX_N11")
			(options
				(clearance outline)
				(anchor circle)
			)
			(primitives
				(gr_poly
					(pts
						(arc
							(start 0.1524 -0.127)
							(mid 0.137521 -0.162921)
							(end 0.1016 -0.1778)
						)
						(arc
							(start -0.1016 -0.1778)
							(mid -0.137521 -0.162921)
							(end -0.1524 -0.127)
						)
						(arc
							(start -0.1524 0.127)
							(mid -0.137521 0.162921)
							(end -0.1016 0.1778)
						)
						(arc
							(start 0.1016 0.1778)
							(mid 0.137521 0.162921)
							(end 0.1524 0.127)
						)
					)
					(width 0)
					(fill yes)
				)
			)
		)
		(pad "2" smd custom
			(at 0 0.2794 270)
			(size 0.0762 0.0762)
			(layers "F.Cu" "F.Mask" "F.Paste")
			(net "PHY_SCC_B_TO_DRV_B_11_DN")
			(options
				(clearance outline)
				(anchor circle)
			)
			(primitives
				(gr_poly
					(pts
						(arc
							(start 0.1524 -0.127)
							(mid 0.137521 -0.162921)
							(end 0.1016 -0.1778)
						)
						(arc
							(start -0.1016 -0.1778)
							(mid -0.137521 -0.162921)
							(end -0.1524 -0.127)
						)
						(arc
							(start -0.1524 0.127)
							(mid -0.137521 0.162921)
							(end -0.1016 0.1778)
						)
						(arc
							(start 0.1016 0.1778)
							(mid 0.137521 0.162921)
							(end 0.1524 0.127)
						)
					)
					(width 0)
					(fill yes)
				)
			)
		)
	)
	(footprint ""
		(layer "F.Cu")
		(at 353.184714 -130.21945 -90)
		(property "Reference" "C275"
			(at 0 0 270)
			(layer "F.SilkS")
			(hide yes)
			(effects
				(font
					(size 1.27 1.27)
				)
			)
		)
		(property "Value" "SCD01U16V1KX-GP"
			(at -2.8321 -1.7399 270)
			(unlocked yes)
			(layer "F.Fab")
			(hide yes)
			(effects
				(font
					(size 1.016 1.016)
					(thickness 0.1524)
				)
			)
		)
		(property "Device Type" "C0201H13"
			(at -2.8321 -3.2639 270)
			(unlocked yes)
			(layer "F.Fab")
			(hide yes)
			(effects
				(font
					(size 1.016 1.016)
					(thickness 0.1524)
				)
			)
		)
		(duplicate_pad_numbers_are_jumpers no)
		(fp_rect
			(start -0.2794 0.6477)
			(end 0.2794 -0.6477)
			(stroke
				(width 0)
				(type default)
			)
			(fill no)
			(layer "F.CrtYd")
		)
		(fp_rect
			(start -0.2794 0.6477)
			(end 0.2794 -0.6477)
			(stroke
				(width 0)
				(type default)
			)
			(fill no)
			(layer "F.Fab")
		)
		(pad "1" smd custom
			(at 0 -0.2794 270)
			(size 0.0762 0.0762)
			(layers "F.Cu" "F.Mask" "F.Paste")
			(net "SAS_HDD_RX_N19")
			(options
				(clearance outline)
				(anchor circle)
			)
			(primitives
				(gr_poly
					(pts
						(arc
							(start 0.1524 -0.127)
							(mid 0.137521 -0.162921)
							(end 0.1016 -0.1778)
						)
						(arc
							(start -0.1016 -0.1778)
							(mid -0.137521 -0.162921)
							(end -0.1524 -0.127)
						)
						(arc
							(start -0.1524 0.127)
							(mid -0.137521 0.162921)
							(end -0.1016 0.1778)
						)
						(arc
							(start 0.1016 0.1778)
							(mid 0.137521 0.162921)
							(end 0.1524 0.127)
						)
					)
					(width 0)
					(fill yes)
				)
			)
		)
		(pad "2" smd custom
			(at 0 0.2794 270)
			(size 0.0762 0.0762)
			(layers "F.Cu" "F.Mask" "F.Paste")
			(net "PHY_SCC_B_TO_DRV_B_19_DN")
			(options
				(clearance outline)
				(anchor circle)
			)
			(primitives
				(gr_poly
					(pts
						(arc
							(start 0.1524 -0.127)
							(mid 0.137521 -0.162921)
							(end 0.1016 -0.1778)
						)
						(arc
							(start -0.1016 -0.1778)
							(mid -0.137521 -0.162921)
							(end -0.1524 -0.127)
						)
						(arc
							(start -0.1524 0.127)
							(mid -0.137521 0.162921)
							(end -0.1016 0.1778)
						)
						(arc
							(start 0.1016 0.1778)
							(mid 0.137521 0.162921)
							(end 0.1524 0.127)
						)
					)
					(width 0)
					(fill yes)
				)
			)
		)
	)
	(footprint ""
		(layer "F.Cu")
		(at 21.480018 -99.401884)
		(property "Reference" "R387"
			(at 0 0 0)
			(layer "F.SilkS")
			(hide yes)
			(effects
				(font
					(size 1.27 1.27)
				)
			)
		)
		(property "Value" "91R3F-1-GP"
			(at -0.0254 -2.5146 0)
			(unlocked yes)
			(layer "F.Fab")
			(hide yes)
			(effects
				(font
					(size 1.016 1.016)
					(thickness 0.1524)
				)
			)
		)
		(property "Device Type" "R603H22"
			(at -0.0254 -4.0386 0)
			(unlocked yes)
			(layer "F.Fab")
			(hide yes)
			(effects
				(font
					(size 1.016 1.016)
					(thickness 0.1524)
				)
			)
		)
		(duplicate_pad_numbers_are_jumpers no)
		(fp_line
			(start -0.4826 0)
			(end -0.2032 0)
			(stroke
				(width 0.2032)
				(type default)
			)
			(layer "F.SilkS")
		)
		(fp_line
			(start 0.2032 0)
			(end 0.4826 0)
			(stroke
				(width 0.2032)
				(type default)
			)
			(layer "F.SilkS")
		)
		(fp_rect
			(start -0.5842 1.3335)
			(end 0.5842 -1.3335)
			(stroke
				(width 0)
				(type default)
			)
			(fill no)
			(layer "F.CrtYd")
		)
		(fp_rect
			(start -0.5842 1.3335)
			(end 0.5842 -1.3335)
			(stroke
				(width 0)
				(type default)
			)
			(fill no)
			(layer "F.Fab")
		)
		(pad "1" smd custom
			(at 0 -0.762)
			(size 0.2159 0.2159)
			(layers "F.Cu" "F.Mask" "F.Paste")
			(net "P5V_B_1")
			(options
				(clearance outline)
				(anchor circle)
			)
			(primitives
				(gr_poly
					(pts
						(arc
							(start -0.3302 -0.4318)
							(mid -0.402042 -0.402042)
							(end -0.4318 -0.3302)
						)
						(arc
							(start -0.4318 0.3302)
							(mid -0.402042 0.402042)
							(end -0.3302 0.4318)
						)
						(arc
							(start 0.3302 0.4318)
							(mid 0.402042 0.402042)
							(end 0.4318 0.3302)
						)
						(arc
							(start 0.4318 -0.3302)
							(mid 0.402042 -0.402042)
							(end 0.3302 -0.4318)
						)
					)
					(width 0)
					(fill yes)
				)
			)
		)
		(pad "2" smd custom
			(at 0 0.762)
			(size 0.2159 0.2159)
			(layers "F.Cu" "F.Mask" "F.Paste")
			(net "DRV_ACT_12")
			(options
				(clearance outline)
				(anchor circle)
			)
			(primitives
				(gr_poly
					(pts
						(arc
							(start -0.3302 -0.4318)
							(mid -0.402042 -0.402042)
							(end -0.4318 -0.3302)
						)
						(arc
							(start -0.4318 0.3302)
							(mid -0.402042 0.402042)
							(end -0.3302 0.4318)
						)
						(arc
							(start 0.3302 0.4318)
							(mid 0.402042 0.402042)
							(end 0.4318 0.3302)
						)
						(arc
							(start 0.4318 -0.3302)
							(mid 0.402042 -0.402042)
							(end 0.3302 -0.4318)
						)
					)
					(width 0)
					(fill yes)
				)
			)
		)
	)
	(footprint ""
		(layer "F.Cu")
		(at 65.83553 -129.99085 90)
		(property "Reference" "VIA27"
			(at 0 0 90)
			(layer "F.SilkS")
			(hide yes)
			(effects
				(font
					(size 1.27 1.27)
				)
			)
		)
		(property "Value" "100OHM-8L-2D36MM-L18-GP"
			(at 3.8989 0.5715 90)
			(unlocked yes)
			(layer "F.Fab")
			(hide yes)
			(effects
				(font
					(size 1.016 1.016)
					(thickness 0.1524)
				)
			)
		)
		(property "Device Type" "VIA-PCIE-4P-414097"
			(at 3.8989 -0.9525 90)
			(unlocked yes)
			(layer "F.Fab")
			(hide yes)
			(effects
				(font
					(size 1.016 1.016)
					(thickness 0.1524)
				)
			)
		)
		(duplicate_pad_numbers_are_jumpers no)
		(fp_rect
			(start -2.0701 0.4826)
			(end 2.0701 -0.4826)
			(stroke
				(width 0)
				(type default)
			)
			(fill no)
			(layer "F.CrtYd")
		)
		(fp_rect
			(start -2.0701 0.4826)
			(end 2.0701 -0.4826)
			(stroke
				(width 0)
				(type default)
			)
			(fill no)
			(layer "F.Fab")
		)
		(pad "1" thru_hole circle
			(at -1.5875 0 90)
			(size 0.508 0.508)
			(drill 0.254)
			(layers "*.Cu" "*.Mask")
			(remove_unused_layers no)
			(net "GND")
			(clearance 0.2286)
			(thermal_gap 0.2286)
		)
		(pad "2" thru_hole circle
			(at -0.5715 0 90)
			(size 0.508 0.508)
			(drill 0.254)
			(layers "*.Cu" "*.Mask")
			(remove_unused_layers no)
			(net "PHY_SCC_B_TO_DRV_B_13_DP")
			(clearance 0.2286)
			(thermal_gap 0.2286)
		)
		(pad "3" thru_hole circle
			(at 0.5715 0 90)
			(size 0.508 0.508)
			(drill 0.254)
			(layers "*.Cu" "*.Mask")
			(remove_unused_layers no)
			(net "PHY_SCC_B_TO_DRV_B_13_DN")
			(clearance 0.2286)
			(thermal_gap 0.2286)
		)
		(pad "4" thru_hole circle
			(at 1.5875 0 90)
			(size 0.508 0.508)
			(drill 0.254)
			(layers "*.Cu" "*.Mask")
			(remove_unused_layers no)
			(net "GND")
			(clearance 0.2286)
			(thermal_gap 0.2286)
		)
	)
	(footprint ""
		(layer "F.Cu")
		(at 146.685 -249.555 180)
		(property "Reference" "Q15"
			(at 0 0 180)
			(layer "F.SilkS")
			(hide yes)
			(effects
				(font
					(size 1.27 1.27)
				)
			)
		)
		(property "Value" "2N7002KDW-GP"
			(at -2.3622 -8.2042 180)
			(unlocked yes)
			(layer "F.Fab")
			(hide yes)
			(effects
				(font
					(size 1.016 1.016)
					(thickness 0.1524)
				)
			)
		)
		(property "Device Type" "SOT-363H44"
			(at -2.3622 -10.1092 180)
			(unlocked yes)
			(layer "F.Fab")
			(hide yes)
			(effects
				(font
					(size 1.016 1.016)
					(thickness 0.1524)
				)
			)
		)
		(duplicate_pad_numbers_are_jumpers no)
		(fp_line
			(start 1.4478 1.7018)
			(end 1.4478 -1.7018)
			(stroke
				(width 0.1524)
				(type default)
			)
			(layer "F.SilkS")
		)
		(fp_line
			(start 1.4478 -1.7018)
			(end -1.4478 -1.7018)
			(stroke
				(width 0.1524)
				(type default)
			)
			(layer "F.SilkS")
		)
		(fp_line
			(start -1.27 1.524)
			(end -1.27 0.6604)
			(stroke
				(width 0.4826)
				(type default)
			)
			(layer "F.SilkS")
		)
		(fp_line
			(start -1.4478 1.7018)
			(end 1.4478 1.7018)
			(stroke
				(width 0.1524)
				(type default)
			)
			(layer "F.SilkS")
		)
		(fp_line
			(start -1.4478 -1.7018)
			(end -1.4478 1.7018)
			(stroke
				(width 0.1524)
				(type default)
			)
			(layer "F.SilkS")
		)
		(fp_poly
			(pts
				(xy -1.524 -1.778) (xy 1.524 -1.778) (xy 1.524 1.778) (xy -1.524 1.778)
			)
			(stroke
				(width 0)
				(type default)
			)
			(fill no)
			(layer "F.CrtYd")
		)
		(fp_poly
			(pts
				(xy -1.524 -1.778) (xy 1.524 -1.778) (xy 1.524 1.778) (xy -1.524 1.778)
			)
			(stroke
				(width 0)
				(type default)
			)
			(fill no)
			(layer "F.Fab")
		)
		(pad "1" smd rect
			(at -0.65024 0.9398 180)
			(size 0.4064 1.016)
			(layers "F.Cu" "F.Mask" "F.Paste")
			(net "GND")
		)
		(pad "2" smd rect
			(at 0 0.9398 180)
			(size 0.4064 1.016)
			(layers "F.Cu" "F.Mask" "F.Paste")
			(net "SW_PWR_R_HDD4")
		)
		(pad "3" smd rect
			(at 0.65024 0.9398 180)
			(size 0.4064 1.016)
			(layers "F.Cu" "F.Mask" "F.Paste")
			(net "SW_HDD_P4")
		)
		(pad "4" smd rect
			(at 0.65024 -0.9398 180)
			(size 0.4064 1.016)
			(layers "F.Cu" "F.Mask" "F.Paste")
			(net "GND")
		)
		(pad "5" smd rect
			(at 0 -0.9398 180)
			(size 0.4064 1.016)
			(layers "F.Cu" "F.Mask" "F.Paste")
			(net "SW_HDD_G4")
		)
		(pad "6" smd rect
			(at -0.65024 -0.9398 180)
			(size 0.4064 1.016)
			(layers "F.Cu" "F.Mask" "F.Paste")
			(net "SW_HDD_R4")
		)
	)
	(footprint ""
		(layer "F.Cu")
		(at 394.589 -32.004 -90)
		(property "Reference" "R805"
			(at 0 0 270)
			(layer "F.SilkS")
			(hide yes)
			(effects
				(font
					(size 1.27 1.27)
				)
			)
		)
		(property "Value" "2R6F-GP"
			(at -0.0508 -4.8514 270)
			(unlocked yes)
			(layer "F.Fab")
			(hide yes)
			(effects
				(font
					(size 1.016 1.016)
					(thickness 0.1524)
				)
			)
		)
		(property "Device Type" "R1206H26"
			(at 0 -6.3754 270)
			(unlocked yes)
			(layer "F.Fab")
			(hide yes)
			(effects
				(font
					(size 1.016 1.016)
					(thickness 0.1524)
				)
			)
		)
		(duplicate_pad_numbers_are_jumpers no)
		(fp_line
			(start -1.016 2.2352)
			(end -1.016 -2.2352)
			(stroke
				(width 0.1524)
				(type default)
			)
			(layer "F.SilkS")
		)
		(fp_line
			(start 1.016 2.2352)
			(end -1.016 2.2352)
			(stroke
				(width 0.1524)
				(type default)
			)
			(layer "F.SilkS")
		)
		(fp_line
			(start -1.016 -2.2352)
			(end 1.016 -2.2352)
			(stroke
				(width 0.1524)
				(type default)
			)
			(layer "F.SilkS")
		)
		(fp_line
			(start 1.016 -2.2352)
			(end 1.016 2.2352)
			(stroke
				(width 0.1524)
				(type default)
			)
			(layer "F.SilkS")
		)
		(fp_rect
			(start -1.0922 2.3114)
			(end 1.0922 -2.3114)
			(stroke
				(width 0)
				(type default)
			)
			(fill no)
			(layer "F.CrtYd")
		)
		(fp_poly
			(pts
				(xy -1.0922 -2.3114) (xy 1.0922 -2.3114) (xy 1.0922 2.3114) (xy -1.0922 2.3114)
			)
			(stroke
				(width 0)
				(type default)
			)
			(fill no)
			(layer "F.Fab")
		)
		(pad "1" smd rect
			(at 0 -1.397 270)
			(size 1.651 1.27)
			(layers "F.Cu" "F.Mask" "F.Paste")
			(net "P5V_HDD32")
		)
		(pad "2" smd rect
			(at 0 1.397 270)
			(size 1.651 1.27)
			(layers "F.Cu" "F.Mask" "F.Paste")
			(net "5V_PRE_32")
		)
	)
	(footprint ""
		(layer "F.Cu")
		(at 111.506 -247.65 180)
		(property "Reference" "D3"
			(at 0 0 180)
			(layer "F.SilkS")
			(hide yes)
			(effects
				(font
					(size 1.27 1.27)
				)
			)
		)
		(property "Value" "RB551V30-GP"
			(at 0 -6.7818 180)
			(unlocked yes)
			(layer "F.Fab")
			(hide yes)
			(effects
				(font
					(size 1.016 1.016)
					(thickness 0.1524)
				)
			)
		)
		(property "Device Type" "SOD323AKH38"
			(at 0 -8.6868 180)
			(unlocked yes)
			(layer "F.Fab")
			(hide yes)
			(effects
				(font
					(size 1.016 1.016)
					(thickness 0.1524)
				)
			)
		)
		(duplicate_pad_numbers_are_jumpers no)
		(fp_line
			(start 0.889 2.159)
			(end -0.889 2.159)
			(stroke
				(width 0.1524)
				(type default)
			)
			(layer "F.SilkS")
		)
		(fp_line
			(start 0.889 -1.9304)
			(end 0.889 2.159)
			(stroke
				(width 0.1524)
				(type default)
			)
			(layer "F.SilkS")
		)
		(fp_line
			(start 0.762 2.0574)
			(end -0.762 2.0574)
			(stroke
				(width 0.508)
				(type default)
			)
			(layer "F.SilkS")
		)
		(fp_line
			(start -0.889 2.159)
			(end -0.889 -1.9304)
			(stroke
				(width 0.1524)
				(type default)
			)
			(layer "F.SilkS")
		)
		(fp_line
			(start -0.889 -1.9304)
			(end 0.889 -1.9304)
			(stroke
				(width 0.1524)
				(type default)
			)
			(layer "F.SilkS")
		)
		(fp_rect
			(start -1.016 2.3114)
			(end 1.016 -2.0066)
			(stroke
				(width 0)
				(type default)
			)
			(fill no)
			(layer "F.CrtYd")
		)
		(fp_poly
			(pts
				(xy -1.016 -2.0066) (xy 1.016 -2.0066) (xy 1.016 2.3114) (xy -1.016 2.3114)
			)
			(stroke
				(width 0)
				(type default)
			)
			(fill no)
			(layer "F.Fab")
		)
		(pad "A" smd rect
			(at 0 -1.143 180)
			(size 0.5588 1.016)
			(layers "F.Cu" "F.Mask" "F.Paste")
			(net "SW_HDD_R3")
		)
		(pad "K" smd rect
			(at 0 1.143 180)
			(size 0.5588 1.016)
			(layers "F.Cu" "F.Mask" "F.Paste")
			(net "SW_HDD_N3")
		)
	)
	(footprint ""
		(layer "F.Cu")
		(at 83.3374 -33.782 -90)
		(property "Reference" "C368"
			(at 0 0 270)
			(layer "F.SilkS")
			(hide yes)
			(effects
				(font
					(size 1.27 1.27)
				)
			)
		)
		(property "Value" "SC1U16V3KX-5GP"
			(at 0 -2.8194 270)
			(unlocked yes)
			(layer "F.Fab")
			(hide yes)
			(effects
				(font
					(size 1.016 1.016)
					(thickness 0.1524)
				)
			)
		)
		(property "Device Type" "C603H36"
			(at 0 -4.3434 270)
			(unlocked yes)
			(layer "F.Fab")
			(hide yes)
			(effects
				(font
					(size 1.016 1.016)
					(thickness 0.1524)
				)
			)
		)
		(duplicate_pad_numbers_are_jumpers no)
		(fp_line
			(start 0.508 0)
			(end -0.508 0)
			(stroke
				(width 0.2032)
				(type default)
			)
			(layer "F.SilkS")
		)
		(fp_rect
			(start -0.5842 1.3335)
			(end 0.5842 -1.3335)
			(stroke
				(width 0)
				(type default)
			)
			(fill no)
			(layer "F.CrtYd")
		)
		(fp_rect
			(start -0.5842 1.3335)
			(end 0.5842 -1.3335)
			(stroke
				(width 0)
				(type default)
			)
			(fill no)
			(layer "F.Fab")
		)
		(pad "1" smd custom
			(at 0 -0.762 270)
			(size 0.2159 0.2159)
			(layers "F.Cu" "F.Mask" "F.Paste")
			(net "P5V_HDD26")
			(options
				(clearance outline)
				(anchor circle)
			)
			(primitives
				(gr_poly
					(pts
						(arc
							(start -0.3302 -0.4318)
							(mid -0.402042 -0.402042)
							(end -0.4318 -0.3302)
						)
						(arc
							(start -0.4318 0.3302)
							(mid -0.402042 0.402042)
							(end -0.3302 0.4318)
						)
						(arc
							(start 0.3302 0.4318)
							(mid 0.402042 0.402042)
							(end 0.4318 0.3302)
						)
						(arc
							(start 0.4318 -0.3302)
							(mid 0.402042 -0.402042)
							(end 0.3302 -0.4318)
						)
					)
					(width 0)
					(fill yes)
				)
			)
		)
		(pad "2" smd custom
			(at 0 0.762 270)
			(size 0.2159 0.2159)
			(layers "F.Cu" "F.Mask" "F.Paste")
			(net "GND")
			(options
				(clearance outline)
				(anchor circle)
			)
			(primitives
				(gr_poly
					(pts
						(arc
							(start -0.3302 -0.4318)
							(mid -0.402042 -0.402042)
							(end -0.4318 -0.3302)
						)
						(arc
							(start -0.4318 0.3302)
							(mid -0.402042 0.402042)
							(end -0.3302 0.4318)
						)
						(arc
							(start 0.3302 0.4318)
							(mid 0.402042 0.402042)
							(end 0.4318 0.3302)
						)
						(arc
							(start 0.4318 -0.3302)
							(mid 0.402042 -0.402042)
							(end 0.3302 -0.4318)
						)
					)
					(width 0)
					(fill yes)
				)
			)
		)
	)
	(footprint ""
		(layer "F.Cu")
		(at 469.519 -129.286 180)
		(property "Reference" "R609"
			(at 0 0 180)
			(layer "F.SilkS")
			(hide yes)
			(effects
				(font
					(size 1.27 1.27)
				)
			)
		)
		(property "Value" "0R2J-2-GP"
			(at 0.064008 -3.993896 180)
			(unlocked yes)
			(layer "F.Fab")
			(hide yes)
			(effects
				(font
					(size 1.016 1.016)
					(thickness 0.1524)
				)
			)
		)
		(property "Device Type" "R402H16"
			(at 0.064008 -5.517896 180)
			(unlocked yes)
			(layer "F.Fab")
			(hide yes)
			(effects
				(font
					(size 1.016 1.016)
					(thickness 0.1524)
				)
			)
		)
		(duplicate_pad_numbers_are_jumpers no)
		(fp_line
			(start 0.508 -0.9398)
			(end -0.508 -0.9398)
			(stroke
				(width 0.1524)
				(type default)
			)
			(layer "F.SilkS")
		)
		(fp_line
			(start -0.508 -0.9398)
			(end -0.508 0.9398)
			(stroke
				(width 0.1524)
				(type default)
			)
			(layer "F.SilkS")
		)
		(fp_rect
			(start -0.508 0.9398)
			(end 0.508 -0.9398)
			(stroke
				(width 0)
				(type default)
			)
			(fill no)
			(layer "F.CrtYd")
		)
		(fp_rect
			(start -0.508 0.9398)
			(end 0.508 -0.9398)
			(stroke
				(width 0)
				(type default)
			)
			(fill no)
			(layer "F.Fab")
		)
		(pad "1" smd custom
			(at 0 -0.4445 180)
			(size 0.1397 0.1397)
			(layers "F.Cu" "F.Mask" "F.Paste")
			(net "DRIVE_B_23_PWR")
			(options
				(clearance outline)
				(anchor circle)
			)
			(primitives
				(gr_poly
					(pts
						(arc
							(start -0.1778 -0.2794)
							(mid -0.249642 -0.249642)
							(end -0.2794 -0.1778)
						)
						(arc
							(start -0.2794 0.1778)
							(mid -0.249642 0.249642)
							(end -0.1778 0.2794)
						)
						(arc
							(start 0.1778 0.2794)
							(mid 0.249642 0.249642)
							(end 0.2794 0.1778)
						)
						(arc
							(start 0.2794 -0.1778)
							(mid 0.249642 -0.249642)
							(end 0.1778 -0.2794)
						)
					)
					(width 0)
					(fill yes)
				)
			)
		)
		(pad "2" smd custom
			(at 0 0.4445 180)
			(size 0.1397 0.1397)
			(layers "F.Cu" "F.Mask" "F.Paste")
			(net "SW_PWR_R_HDD23")
			(options
				(clearance outline)
				(anchor circle)
			)
			(primitives
				(gr_poly
					(pts
						(arc
							(start -0.1778 -0.2794)
							(mid -0.249642 -0.249642)
							(end -0.2794 -0.1778)
						)
						(arc
							(start -0.2794 0.1778)
							(mid -0.249642 0.249642)
							(end -0.1778 0.2794)
						)
						(arc
							(start 0.1778 0.2794)
							(mid 0.249642 0.249642)
							(end 0.2794 0.1778)
						)
						(arc
							(start 0.2794 -0.1778)
							(mid 0.249642 -0.249642)
							(end 0.1778 -0.2794)
						)
					)
					(width 0)
					(fill yes)
				)
			)
		)
	)
	(footprint ""
		(layer "F.Cu")
		(at 52.578 -19.177 180)
		(property "Reference" "R657"
			(at 0 0 180)
			(layer "F.SilkS")
			(hide yes)
			(effects
				(font
					(size 1.27 1.27)
				)
			)
		)
		(property "Value" "4K7R2F-GP"
			(at 0.064008 -3.993896 180)
			(unlocked yes)
			(layer "F.Fab")
			(hide yes)
			(effects
				(font
					(size 1.016 1.016)
					(thickness 0.1524)
				)
			)
		)
		(property "Device Type" "R402H16"
			(at 0.064008 -5.517896 180)
			(unlocked yes)
			(layer "F.Fab")
			(hide yes)
			(effects
				(font
					(size 1.016 1.016)
					(thickness 0.1524)
				)
			)
		)
		(duplicate_pad_numbers_are_jumpers no)
		(fp_line
			(start 0.508 -0.9398)
			(end -0.508 -0.9398)
			(stroke
				(width 0.1524)
				(type default)
			)
			(layer "F.SilkS")
		)
		(fp_line
			(start -0.508 -0.9398)
			(end -0.508 0.9398)
			(stroke
				(width 0.1524)
				(type default)
			)
			(layer "F.SilkS")
		)
		(fp_rect
			(start -0.508 0.9398)
			(end 0.508 -0.9398)
			(stroke
				(width 0)
				(type default)
			)
			(fill no)
			(layer "F.CrtYd")
		)
		(fp_rect
			(start -0.508 0.9398)
			(end 0.508 -0.9398)
			(stroke
				(width 0)
				(type default)
			)
			(fill no)
			(layer "F.Fab")
		)
		(pad "1" smd custom
			(at 0 -0.4445 180)
			(size 0.1397 0.1397)
			(layers "F.Cu" "F.Mask" "F.Paste")
			(net "SW_PWR_R_HDD25")
			(options
				(clearance outline)
				(anchor circle)
			)
			(primitives
				(gr_poly
					(pts
						(arc
							(start -0.1778 -0.2794)
							(mid -0.249642 -0.249642)
							(end -0.2794 -0.1778)
						)
						(arc
							(start -0.2794 0.1778)
							(mid -0.249642 0.249642)
							(end -0.1778 0.2794)
						)
						(arc
							(start 0.1778 0.2794)
							(mid 0.249642 0.249642)
							(end 0.2794 0.1778)
						)
						(arc
							(start 0.2794 -0.1778)
							(mid 0.249642 -0.249642)
							(end 0.1778 -0.2794)
						)
					)
					(width 0)
					(fill yes)
				)
			)
		)
		(pad "2" smd custom
			(at 0 0.4445 180)
			(size 0.1397 0.1397)
			(layers "F.Cu" "F.Mask" "F.Paste")
			(net "GND")
			(options
				(clearance outline)
				(anchor circle)
			)
			(primitives
				(gr_poly
					(pts
						(arc
							(start -0.1778 -0.2794)
							(mid -0.249642 -0.249642)
							(end -0.2794 -0.1778)
						)
						(arc
							(start -0.2794 0.1778)
							(mid -0.249642 0.249642)
							(end -0.1778 0.2794)
						)
						(arc
							(start 0.1778 0.2794)
							(mid 0.249642 0.249642)
							(end 0.2794 0.1778)
						)
						(arc
							(start 0.2794 -0.1778)
							(mid 0.249642 -0.249642)
							(end 0.1778 -0.2794)
						)
					)
					(width 0)
					(fill yes)
				)
			)
		)
	)
	(footprint ""
		(layer "F.Cu")
		(at 220.853 -225.425 90)
		(property "Reference" "C4"
			(at 0 0 90)
			(layer "F.SilkS")
			(hide yes)
			(effects
				(font
					(size 1.27 1.27)
				)
			)
		)
		(property "Value" "SCD1U16V2KX-3GP"
			(at 1.1811 -2.7051 90)
			(unlocked yes)
			(layer "F.Fab")
			(hide yes)
			(effects
				(font
					(size 1.016 1.016)
					(thickness 0.1524)
				)
			)
		)
		(property "Device Type" "C402H22"
			(at 1.1811 -4.2291 90)
			(unlocked yes)
			(layer "F.Fab")
			(hide yes)
			(effects
				(font
					(size 1.016 1.016)
					(thickness 0.1524)
				)
			)
		)
		(duplicate_pad_numbers_are_jumpers no)
		(fp_rect
			(start -0.4318 0.9525)
			(end 0.4318 -0.9525)
			(stroke
				(width 0)
				(type default)
			)
			(fill no)
			(layer "F.CrtYd")
		)
		(fp_rect
			(start -0.4318 0.9525)
			(end 0.4318 -0.9525)
			(stroke
				(width 0)
				(type default)
			)
			(fill no)
			(layer "F.Fab")
		)
		(pad "1" smd custom
			(at 0 -0.4445 90)
			(size 0.1524 0.1524)
			(layers "F.Cu" "F.Mask" "F.Paste")
			(net "P3V3_STBY_B")
			(options
				(clearance outline)
				(anchor circle)
			)
			(primitives
				(gr_poly
					(pts
						(arc
							(start 0.3048 -0.2032)
							(mid 0.275042 -0.275042)
							(end 0.2032 -0.3048)
						)
						(arc
							(start -0.2032 -0.3048)
							(mid -0.275042 -0.275042)
							(end -0.3048 -0.2032)
						)
						(arc
							(start -0.3048 0.2032)
							(mid -0.275042 0.275042)
							(end -0.2032 0.3048)
						)
						(arc
							(start 0.2032 0.3048)
							(mid 0.275042 0.275042)
							(end 0.3048 0.2032)
						)
					)
					(width 0)
					(fill yes)
				)
			)
		)
		(pad "2" smd custom
			(at 0 0.4445 90)
			(size 0.1524 0.1524)
			(layers "F.Cu" "F.Mask" "F.Paste")
			(net "GND")
			(options
				(clearance outline)
				(anchor circle)
			)
			(primitives
				(gr_poly
					(pts
						(arc
							(start 0.3048 -0.2032)
							(mid 0.275042 -0.275042)
							(end 0.2032 -0.3048)
						)
						(arc
							(start -0.2032 -0.3048)
							(mid -0.275042 -0.275042)
							(end -0.3048 -0.2032)
						)
						(arc
							(start -0.3048 0.2032)
							(mid -0.275042 0.275042)
							(end -0.2032 0.3048)
						)
						(arc
							(start 0.2032 0.3048)
							(mid 0.275042 0.275042)
							(end 0.3048 0.2032)
						)
					)
					(width 0)
					(fill yes)
				)
			)
		)
	)
	(footprint ""
		(layer "F.Cu")
		(at 259.588 -213.995 -90)
		(property "Reference" "R123"
			(at 0 0 270)
			(layer "F.SilkS")
			(hide yes)
			(effects
				(font
					(size 1.27 1.27)
				)
			)
		)
		(property "Value" "4K7R2F-GP"
			(at 0.064008 -3.993896 270)
			(unlocked yes)
			(layer "F.Fab")
			(hide yes)
			(effects
				(font
					(size 1.016 1.016)
					(thickness 0.1524)
				)
			)
		)
		(property "Device Type" "R402H16"
			(at 0.064008 -5.517896 270)
			(unlocked yes)
			(layer "F.Fab")
			(hide yes)
			(effects
				(font
					(size 1.016 1.016)
					(thickness 0.1524)
				)
			)
		)
		(duplicate_pad_numbers_are_jumpers no)
		(fp_line
			(start -0.508 -0.9398)
			(end -0.508 0.9398)
			(stroke
				(width 0.1524)
				(type default)
			)
			(layer "F.SilkS")
		)
		(fp_line
			(start 0.508 -0.9398)
			(end -0.508 -0.9398)
			(stroke
				(width 0.1524)
				(type default)
			)
			(layer "F.SilkS")
		)
		(fp_rect
			(start -0.508 0.9398)
			(end 0.508 -0.9398)
			(stroke
				(width 0)
				(type default)
			)
			(fill no)
			(layer "F.CrtYd")
		)
		(fp_rect
			(start -0.508 0.9398)
			(end 0.508 -0.9398)
			(stroke
				(width 0)
				(type default)
			)
			(fill no)
			(layer "F.Fab")
		)
		(pad "1" smd custom
			(at 0 -0.4445 270)
			(size 0.1397 0.1397)
			(layers "F.Cu" "F.Mask" "F.Paste")
			(net "P3V3_STBY_B")
			(options
				(clearance outline)
				(anchor circle)
			)
			(primitives
				(gr_poly
					(pts
						(arc
							(start -0.1778 -0.2794)
							(mid -0.249642 -0.249642)
							(end -0.2794 -0.1778)
						)
						(arc
							(start -0.2794 0.1778)
							(mid -0.249642 0.249642)
							(end -0.1778 0.2794)
						)
						(arc
							(start 0.1778 0.2794)
							(mid 0.249642 0.249642)
							(end 0.2794 0.1778)
						)
						(arc
							(start 0.2794 -0.1778)
							(mid 0.249642 -0.249642)
							(end 0.1778 -0.2794)
						)
					)
					(width 0)
					(fill yes)
				)
			)
		)
		(pad "2" smd custom
			(at 0 0.4445 270)
			(size 0.1397 0.1397)
			(layers "F.Cu" "F.Mask" "F.Paste")
			(net "VOL_SEN_INT_N")
			(options
				(clearance outline)
				(anchor circle)
			)
			(primitives
				(gr_poly
					(pts
						(arc
							(start -0.1778 -0.2794)
							(mid -0.249642 -0.249642)
							(end -0.2794 -0.1778)
						)
						(arc
							(start -0.2794 0.1778)
							(mid -0.249642 0.249642)
							(end -0.1778 0.2794)
						)
						(arc
							(start 0.1778 0.2794)
							(mid 0.249642 0.249642)
							(end 0.2794 0.1778)
						)
						(arc
							(start 0.2794 -0.1778)
							(mid 0.249642 -0.249642)
							(end 0.1778 -0.2794)
						)
					)
					(width 0)
					(fill yes)
				)
			)
		)
	)
	(footprint ""
		(layer "F.Cu")
		(at 438.104026 -214.757 180)
		(property "Reference" "Q229"
			(at 0 0 180)
			(layer "F.SilkS")
			(hide yes)
			(effects
				(font
					(size 1.27 1.27)
				)
			)
		)
		(property "Value" "2N7002K-2-GP"
			(at 0.127 -8.9662 180)
			(unlocked yes)
			(layer "F.Fab")
			(hide yes)
			(effects
				(font
					(size 1.016 1.016)
					(thickness 0.1524)
				)
			)
		)
		(property "Device Type" "SOT23DGS2D4H44"
			(at 0.127 -10.4902 180)
			(unlocked yes)
			(layer "F.Fab")
			(hide yes)
			(effects
				(font
					(size 1.016 1.016)
					(thickness 0.1524)
				)
			)
		)
		(duplicate_pad_numbers_are_jumpers no)
		(fp_line
			(start 1.651 1.778)
			(end 1.651 -1.778)
			(stroke
				(width 0.1524)
				(type default)
			)
			(layer "F.SilkS")
		)
		(fp_line
			(start 1.651 -1.778)
			(end -1.651 -1.778)
			(stroke
				(width 0.1524)
				(type default)
			)
			(layer "F.SilkS")
		)
		(fp_line
			(start -1.651 1.778)
			(end 1.651 1.778)
			(stroke
				(width 0.1524)
				(type default)
			)
			(layer "F.SilkS")
		)
		(fp_line
			(start -1.651 -1.778)
			(end -1.651 1.778)
			(stroke
				(width 0.1524)
				(type default)
			)
			(layer "F.SilkS")
		)
		(fp_poly
			(pts
				(xy -1.778 1.8796) (xy -1.778 -1.8796) (xy 1.778 -1.8796) (xy 1.778 1.8796)
			)
			(stroke
				(width 0)
				(type default)
			)
			(fill no)
			(layer "F.CrtYd")
		)
		(fp_poly
			(pts
				(xy -1.778 1.8796) (xy -1.778 -1.8796) (xy 1.778 -1.8796) (xy 1.778 1.8796)
			)
			(stroke
				(width 0)
				(type default)
			)
			(fill no)
			(layer "F.Fab")
		)
		(pad "D" smd custom
			(at 0 -0.9525 180)
			(size 0.1905 0.1905)
			(layers "F.Cu" "F.Mask" "F.Paste")
			(net "FLT_HDD10_N")
			(options
				(clearance outline)
				(anchor circle)
			)
			(primitives
				(gr_poly
					(pts
						(arc
							(start -0.1778 0.5715)
							(mid -0.321484 0.511984)
							(end -0.381 0.3683)
						)
						(arc
							(start -0.381 -0.3683)
							(mid -0.321484 -0.511984)
							(end -0.1778 -0.5715)
						)
						(arc
							(start 0.1778 -0.5715)
							(mid 0.321484 -0.511984)
							(end 0.381 -0.3683)
						)
						(arc
							(start 0.381 0.3683)
							(mid 0.321484 0.511984)
							(end 0.1778 0.5715)
						)
					)
					(width 0)
					(fill yes)
				)
			)
		)
		(pad "G" smd custom
			(at -0.98425 0.9525 180)
			(size 0.1905 0.1905)
			(layers "F.Cu" "F.Mask" "F.Paste")
			(net "DRIVE_B_10_FLT_LED")
			(options
				(clearance outline)
				(anchor circle)
			)
			(primitives
				(gr_poly
					(pts
						(arc
							(start -0.1778 0.5715)
							(mid -0.321484 0.511984)
							(end -0.381 0.3683)
						)
						(arc
							(start -0.381 -0.3683)
							(mid -0.321484 -0.511984)
							(end -0.1778 -0.5715)
						)
						(arc
							(start 0.1778 -0.5715)
							(mid 0.321484 -0.511984)
							(end 0.381 -0.3683)
						)
						(arc
							(start 0.381 0.3683)
							(mid 0.321484 0.511984)
							(end 0.1778 0.5715)
						)
					)
					(width 0)
					(fill yes)
				)
			)
		)
		(pad "S" smd custom
			(at 0.98425 0.9525 180)
			(size 0.1905 0.1905)
			(layers "F.Cu" "F.Mask" "F.Paste")
			(net "GND")
			(options
				(clearance outline)
				(anchor circle)
			)
			(primitives
				(gr_poly
					(pts
						(arc
							(start -0.1778 0.5715)
							(mid -0.321484 0.511984)
							(end -0.381 0.3683)
						)
						(arc
							(start -0.381 -0.3683)
							(mid -0.321484 -0.511984)
							(end -0.1778 -0.5715)
						)
						(arc
							(start 0.1778 -0.5715)
							(mid 0.321484 -0.511984)
							(end 0.381 -0.3683)
						)
						(arc
							(start 0.381 0.3683)
							(mid 0.321484 0.511984)
							(end 0.1778 0.5715)
						)
					)
					(width 0)
					(fill yes)
				)
			)
		)
	)
	(footprint ""
		(layer "F.Cu")
		(at 209.92338 -235.18622)
		(property "Reference" "R40"
			(at 0 0 0)
			(layer "F.SilkS")
			(hide yes)
			(effects
				(font
					(size 1.27 1.27)
				)
			)
		)
		(property "Value" "0R2J-2-GP"
			(at 0.064008 -3.993896 0)
			(unlocked yes)
			(layer "F.Fab")
			(hide yes)
			(effects
				(font
					(size 1.016 1.016)
					(thickness 0.1524)
				)
			)
		)
		(property "Device Type" "R402H16"
			(at 0.064008 -5.517896 0)
			(unlocked yes)
			(layer "F.Fab")
			(hide yes)
			(effects
				(font
					(size 1.016 1.016)
					(thickness 0.1524)
				)
			)
		)
		(duplicate_pad_numbers_are_jumpers no)
		(fp_line
			(start -0.508 -0.9398)
			(end -0.508 0.9398)
			(stroke
				(width 0.1524)
				(type default)
			)
			(layer "F.SilkS")
		)
		(fp_line
			(start 0.508 -0.9398)
			(end -0.508 -0.9398)
			(stroke
				(width 0.1524)
				(type default)
			)
			(layer "F.SilkS")
		)
		(fp_rect
			(start -0.508 0.9398)
			(end 0.508 -0.9398)
			(stroke
				(width 0)
				(type default)
			)
			(fill no)
			(layer "F.CrtYd")
		)
		(fp_rect
			(start -0.508 0.9398)
			(end 0.508 -0.9398)
			(stroke
				(width 0)
				(type default)
			)
			(fill no)
			(layer "F.Fab")
		)
		(pad "1" smd custom
			(at 0 -0.4445)
			(size 0.1397 0.1397)
			(layers "F.Cu" "F.Mask" "F.Paste")
			(net "IO_EXP4_SCL")
			(options
				(clearance outline)
				(anchor circle)
			)
			(primitives
				(gr_poly
					(pts
						(arc
							(start -0.1778 -0.2794)
							(mid -0.249642 -0.249642)
							(end -0.2794 -0.1778)
						)
						(arc
							(start -0.2794 0.1778)
							(mid -0.249642 0.249642)
							(end -0.1778 0.2794)
						)
						(arc
							(start 0.1778 0.2794)
							(mid 0.249642 0.249642)
							(end 0.2794 0.1778)
						)
						(arc
							(start 0.2794 -0.1778)
							(mid 0.249642 -0.249642)
							(end 0.1778 -0.2794)
						)
					)
					(width 0)
					(fill yes)
				)
			)
		)
		(pad "2" smd custom
			(at 0 0.4445)
			(size 0.1397 0.1397)
			(layers "F.Cu" "F.Mask" "F.Paste")
			(net "I2C_DRIVE_B_INS_SCL")
			(options
				(clearance outline)
				(anchor circle)
			)
			(primitives
				(gr_poly
					(pts
						(arc
							(start -0.1778 -0.2794)
							(mid -0.249642 -0.249642)
							(end -0.2794 -0.1778)
						)
						(arc
							(start -0.2794 0.1778)
							(mid -0.249642 0.249642)
							(end -0.1778 0.2794)
						)
						(arc
							(start 0.1778 0.2794)
							(mid 0.249642 0.249642)
							(end 0.2794 0.1778)
						)
						(arc
							(start 0.2794 -0.1778)
							(mid 0.249642 -0.249642)
							(end 0.1778 -0.2794)
						)
					)
					(width 0)
					(fill yes)
				)
			)
		)
	)
	(footprint ""
		(layer "F.Cu")
		(at 77.5716 -99.7712 180)
		(property "Reference" "Q233"
			(at 0 0 180)
			(layer "F.SilkS")
			(hide yes)
			(effects
				(font
					(size 1.27 1.27)
				)
			)
		)
		(property "Value" "2N7002K-2-GP"
			(at 0.127 -8.9662 180)
			(unlocked yes)
			(layer "F.Fab")
			(hide yes)
			(effects
				(font
					(size 1.016 1.016)
					(thickness 0.1524)
				)
			)
		)
		(property "Device Type" "SOT23DGS2D4H44"
			(at 0.127 -10.4902 180)
			(unlocked yes)
			(layer "F.Fab")
			(hide yes)
			(effects
				(font
					(size 1.016 1.016)
					(thickness 0.1524)
				)
			)
		)
		(duplicate_pad_numbers_are_jumpers no)
		(fp_line
			(start 1.651 1.778)
			(end 1.651 -1.778)
			(stroke
				(width 0.1524)
				(type default)
			)
			(layer "F.SilkS")
		)
		(fp_line
			(start 1.651 -1.778)
			(end -1.651 -1.778)
			(stroke
				(width 0.1524)
				(type default)
			)
			(layer "F.SilkS")
		)
		(fp_line
			(start -1.651 1.778)
			(end 1.651 1.778)
			(stroke
				(width 0.1524)
				(type default)
			)
			(layer "F.SilkS")
		)
		(fp_line
			(start -1.651 -1.778)
			(end -1.651 1.778)
			(stroke
				(width 0.1524)
				(type default)
			)
			(layer "F.SilkS")
		)
		(fp_poly
			(pts
				(xy -1.778 1.8796) (xy -1.778 -1.8796) (xy 1.778 -1.8796) (xy 1.778 1.8796)
			)
			(stroke
				(width 0)
				(type default)
			)
			(fill no)
			(layer "F.CrtYd")
		)
		(fp_poly
			(pts
				(xy -1.778 1.8796) (xy -1.778 -1.8796) (xy 1.778 -1.8796) (xy 1.778 1.8796)
			)
			(stroke
				(width 0)
				(type default)
			)
			(fill no)
			(layer "F.Fab")
		)
		(pad "D" smd custom
			(at 0 -0.9525 180)
			(size 0.1905 0.1905)
			(layers "F.Cu" "F.Mask" "F.Paste")
			(net "FLT_HDD14_N")
			(options
				(clearance outline)
				(anchor circle)
			)
			(primitives
				(gr_poly
					(pts
						(arc
							(start -0.1778 0.5715)
							(mid -0.321484 0.511984)
							(end -0.381 0.3683)
						)
						(arc
							(start -0.381 -0.3683)
							(mid -0.321484 -0.511984)
							(end -0.1778 -0.5715)
						)
						(arc
							(start 0.1778 -0.5715)
							(mid 0.321484 -0.511984)
							(end 0.381 -0.3683)
						)
						(arc
							(start 0.381 0.3683)
							(mid 0.321484 0.511984)
							(end 0.1778 0.5715)
						)
					)
					(width 0)
					(fill yes)
				)
			)
		)
		(pad "G" smd custom
			(at -0.98425 0.9525 180)
			(size 0.1905 0.1905)
			(layers "F.Cu" "F.Mask" "F.Paste")
			(net "DRIVE_B_14_FLT_LED")
			(options
				(clearance outline)
				(anchor circle)
			)
			(primitives
				(gr_poly
					(pts
						(arc
							(start -0.1778 0.5715)
							(mid -0.321484 0.511984)
							(end -0.381 0.3683)
						)
						(arc
							(start -0.381 -0.3683)
							(mid -0.321484 -0.511984)
							(end -0.1778 -0.5715)
						)
						(arc
							(start 0.1778 -0.5715)
							(mid 0.321484 -0.511984)
							(end 0.381 -0.3683)
						)
						(arc
							(start 0.381 0.3683)
							(mid 0.321484 0.511984)
							(end 0.1778 0.5715)
						)
					)
					(width 0)
					(fill yes)
				)
			)
		)
		(pad "S" smd custom
			(at 0.98425 0.9525 180)
			(size 0.1905 0.1905)
			(layers "F.Cu" "F.Mask" "F.Paste")
			(net "GND")
			(options
				(clearance outline)
				(anchor circle)
			)
			(primitives
				(gr_poly
					(pts
						(arc
							(start -0.1778 0.5715)
							(mid -0.321484 0.511984)
							(end -0.381 0.3683)
						)
						(arc
							(start -0.381 -0.3683)
							(mid -0.321484 -0.511984)
							(end -0.1778 -0.5715)
						)
						(arc
							(start 0.1778 -0.5715)
							(mid 0.321484 -0.511984)
							(end 0.381 -0.3683)
						)
						(arc
							(start 0.381 0.3683)
							(mid 0.321484 0.511984)
							(end 0.1778 0.5715)
						)
					)
					(width 0)
					(fill yes)
				)
			)
		)
	)
	(footprint ""
		(layer "F.Cu")
		(at 251.941838 -227.34651 -90)
		(property "Reference" "R132"
			(at 0 0 270)
			(layer "F.SilkS")
			(hide yes)
			(effects
				(font
					(size 1.27 1.27)
				)
			)
		)
		(property "Value" "10KR2F-2-GP"
			(at 0.064008 -3.993896 270)
			(unlocked yes)
			(layer "F.Fab")
			(hide yes)
			(effects
				(font
					(size 1.016 1.016)
					(thickness 0.1524)
				)
			)
		)
		(property "Device Type" "R402H16"
			(at 0.064008 -5.517896 270)
			(unlocked yes)
			(layer "F.Fab")
			(hide yes)
			(effects
				(font
					(size 1.016 1.016)
					(thickness 0.1524)
				)
			)
		)
		(duplicate_pad_numbers_are_jumpers no)
		(fp_line
			(start -0.508 -0.9398)
			(end -0.508 0.9398)
			(stroke
				(width 0.1524)
				(type default)
			)
			(layer "F.SilkS")
		)
		(fp_line
			(start 0.508 -0.9398)
			(end -0.508 -0.9398)
			(stroke
				(width 0.1524)
				(type default)
			)
			(layer "F.SilkS")
		)
		(fp_rect
			(start -0.508 0.9398)
			(end 0.508 -0.9398)
			(stroke
				(width 0)
				(type default)
			)
			(fill no)
			(layer "F.CrtYd")
		)
		(fp_rect
			(start -0.508 0.9398)
			(end 0.508 -0.9398)
			(stroke
				(width 0)
				(type default)
			)
			(fill no)
			(layer "F.Fab")
		)
		(pad "1" smd custom
			(at 0 -0.4445 270)
			(size 0.1397 0.1397)
			(layers "F.Cu" "F.Mask" "F.Paste")
			(net "P3V3_SENSE")
			(options
				(clearance outline)
				(anchor circle)
			)
			(primitives
				(gr_poly
					(pts
						(arc
							(start -0.1778 -0.2794)
							(mid -0.249642 -0.249642)
							(end -0.2794 -0.1778)
						)
						(arc
							(start -0.2794 0.1778)
							(mid -0.249642 0.249642)
							(end -0.1778 0.2794)
						)
						(arc
							(start 0.1778 0.2794)
							(mid 0.249642 0.249642)
							(end 0.2794 0.1778)
						)
						(arc
							(start 0.2794 -0.1778)
							(mid 0.249642 -0.249642)
							(end 0.1778 -0.2794)
						)
					)
					(width 0)
					(fill yes)
				)
			)
		)
		(pad "2" smd custom
			(at 0 0.4445 270)
			(size 0.1397 0.1397)
			(layers "F.Cu" "F.Mask" "F.Paste")
			(net "GND")
			(options
				(clearance outline)
				(anchor circle)
			)
			(primitives
				(gr_poly
					(pts
						(arc
							(start -0.1778 -0.2794)
							(mid -0.249642 -0.249642)
							(end -0.2794 -0.1778)
						)
						(arc
							(start -0.2794 0.1778)
							(mid -0.249642 0.249642)
							(end -0.1778 0.2794)
						)
						(arc
							(start 0.1778 0.2794)
							(mid 0.249642 0.249642)
							(end 0.2794 0.1778)
						)
						(arc
							(start 0.2794 -0.1778)
							(mid 0.249642 -0.249642)
							(end 0.1778 -0.2794)
						)
					)
					(width 0)
					(fill yes)
				)
			)
		)
	)
	(footprint ""
		(layer "F.Cu")
		(at 144.526 -214.249)
		(property "Reference" "R269"
			(at 0 0 0)
			(layer "F.SilkS")
			(hide yes)
			(effects
				(font
					(size 1.27 1.27)
				)
			)
		)
		(property "Value" "91R3F-1-GP"
			(at -0.0254 -2.5146 0)
			(unlocked yes)
			(layer "F.Fab")
			(hide yes)
			(effects
				(font
					(size 1.016 1.016)
					(thickness 0.1524)
				)
			)
		)
		(property "Device Type" "R603H22"
			(at -0.0254 -4.0386 0)
			(unlocked yes)
			(layer "F.Fab")
			(hide yes)
			(effects
				(font
					(size 1.016 1.016)
					(thickness 0.1524)
				)
			)
		)
		(duplicate_pad_numbers_are_jumpers no)
		(fp_line
			(start -0.4826 0)
			(end -0.2032 0)
			(stroke
				(width 0.2032)
				(type default)
			)
			(layer "F.SilkS")
		)
		(fp_line
			(start 0.2032 0)
			(end 0.4826 0)
			(stroke
				(width 0.2032)
				(type default)
			)
			(layer "F.SilkS")
		)
		(fp_rect
			(start -0.5842 1.3335)
			(end 0.5842 -1.3335)
			(stroke
				(width 0)
				(type default)
			)
			(fill no)
			(layer "F.CrtYd")
		)
		(fp_rect
			(start -0.5842 1.3335)
			(end 0.5842 -1.3335)
			(stroke
				(width 0)
				(type default)
			)
			(fill no)
			(layer "F.Fab")
		)
		(pad "1" smd custom
			(at 0 -0.762)
			(size 0.2159 0.2159)
			(layers "F.Cu" "F.Mask" "F.Paste")
			(net "P5V_B_1")
			(options
				(clearance outline)
				(anchor circle)
			)
			(primitives
				(gr_poly
					(pts
						(arc
							(start -0.3302 -0.4318)
							(mid -0.402042 -0.402042)
							(end -0.4318 -0.3302)
						)
						(arc
							(start -0.4318 0.3302)
							(mid -0.402042 0.402042)
							(end -0.3302 0.4318)
						)
						(arc
							(start 0.3302 0.4318)
							(mid 0.402042 0.402042)
							(end 0.4318 0.3302)
						)
						(arc
							(start 0.4318 -0.3302)
							(mid 0.402042 -0.402042)
							(end 0.3302 -0.4318)
						)
					)
					(width 0)
					(fill yes)
				)
			)
		)
		(pad "2" smd custom
			(at 0 0.762)
			(size 0.2159 0.2159)
			(layers "F.Cu" "F.Mask" "F.Paste")
			(net "DRV_ACT_4")
			(options
				(clearance outline)
				(anchor circle)
			)
			(primitives
				(gr_poly
					(pts
						(arc
							(start -0.3302 -0.4318)
							(mid -0.402042 -0.402042)
							(end -0.4318 -0.3302)
						)
						(arc
							(start -0.4318 0.3302)
							(mid -0.402042 0.402042)
							(end -0.3302 0.4318)
						)
						(arc
							(start 0.3302 0.4318)
							(mid 0.402042 0.402042)
							(end 0.4318 0.3302)
						)
						(arc
							(start 0.4318 -0.3302)
							(mid 0.402042 -0.402042)
							(end 0.3302 -0.4318)
						)
					)
					(width 0)
					(fill yes)
				)
			)
		)
	)
	(footprint ""
		(layer "F.Cu")
		(at 57.18937 -364.243366 90)
		(property "Reference" "C521"
			(at 0 0 90)
			(layer "F.SilkS")
			(hide yes)
			(effects
				(font
					(size 1.27 1.27)
				)
			)
		)
		(property "Value" "SCD1U25V2KX-2-GP"
			(at 1.1811 -2.7051 90)
			(unlocked yes)
			(layer "F.Fab")
			(hide yes)
			(effects
				(font
					(size 1.016 1.016)
					(thickness 0.1524)
				)
			)
		)
		(property "Device Type" "C402H22"
			(at 1.1811 -4.2291 90)
			(unlocked yes)
			(layer "F.Fab")
			(hide yes)
			(effects
				(font
					(size 1.016 1.016)
					(thickness 0.1524)
				)
			)
		)
		(duplicate_pad_numbers_are_jumpers no)
		(fp_rect
			(start -0.4318 0.9525)
			(end 0.4318 -0.9525)
			(stroke
				(width 0)
				(type default)
			)
			(fill no)
			(layer "F.CrtYd")
		)
		(fp_rect
			(start -0.4318 0.9525)
			(end 0.4318 -0.9525)
			(stroke
				(width 0)
				(type default)
			)
			(fill no)
			(layer "F.Fab")
		)
		(pad "1" smd custom
			(at 0 -0.4445 90)
			(size 0.1524 0.1524)
			(layers "F.Cu" "F.Mask" "F.Paste")
			(net "P12V_FAN0")
			(options
				(clearance outline)
				(anchor circle)
			)
			(primitives
				(gr_poly
					(pts
						(arc
							(start 0.3048 -0.2032)
							(mid 0.275042 -0.275042)
							(end 0.2032 -0.3048)
						)
						(arc
							(start -0.2032 -0.3048)
							(mid -0.275042 -0.275042)
							(end -0.3048 -0.2032)
						)
						(arc
							(start -0.3048 0.2032)
							(mid -0.275042 0.275042)
							(end -0.2032 0.3048)
						)
						(arc
							(start 0.2032 0.3048)
							(mid 0.275042 0.275042)
							(end 0.3048 0.2032)
						)
					)
					(width 0)
					(fill yes)
				)
			)
		)
		(pad "2" smd custom
			(at 0 0.4445 90)
			(size 0.1524 0.1524)
			(layers "F.Cu" "F.Mask" "F.Paste")
			(net "GND")
			(options
				(clearance outline)
				(anchor circle)
			)
			(primitives
				(gr_poly
					(pts
						(arc
							(start 0.3048 -0.2032)
							(mid 0.275042 -0.275042)
							(end 0.2032 -0.3048)
						)
						(arc
							(start -0.2032 -0.3048)
							(mid -0.275042 -0.275042)
							(end -0.3048 -0.2032)
						)
						(arc
							(start -0.3048 0.2032)
							(mid -0.275042 0.275042)
							(end -0.2032 0.3048)
						)
						(arc
							(start 0.2032 0.3048)
							(mid 0.275042 0.275042)
							(end 0.3048 0.2032)
						)
					)
					(width 0)
					(fill yes)
				)
			)
		)
	)
	(footprint ""
		(layer "F.Cu")
		(at 128.93548 -14.990826 90)
		(property "Reference" "VIA55"
			(at 0 0 90)
			(layer "F.SilkS")
			(hide yes)
			(effects
				(font
					(size 1.27 1.27)
				)
			)
		)
		(property "Value" "100OHM-8L-2D36MM-L18-GP"
			(at 3.8989 0.5715 90)
			(unlocked yes)
			(layer "F.Fab")
			(hide yes)
			(effects
				(font
					(size 1.016 1.016)
					(thickness 0.1524)
				)
			)
		)
		(property "Device Type" "VIA-PCIE-4P-414097"
			(at 3.8989 -0.9525 90)
			(unlocked yes)
			(layer "F.Fab")
			(hide yes)
			(effects
				(font
					(size 1.016 1.016)
					(thickness 0.1524)
				)
			)
		)
		(duplicate_pad_numbers_are_jumpers no)
		(fp_rect
			(start -2.0701 0.4826)
			(end 2.0701 -0.4826)
			(stroke
				(width 0)
				(type default)
			)
			(fill no)
			(layer "F.CrtYd")
		)
		(fp_rect
			(start -2.0701 0.4826)
			(end 2.0701 -0.4826)
			(stroke
				(width 0)
				(type default)
			)
			(fill no)
			(layer "F.Fab")
		)
		(pad "1" thru_hole circle
			(at -1.5875 0 90)
			(size 0.508 0.508)
			(drill 0.254)
			(layers "*.Cu" "*.Mask")
			(remove_unused_layers no)
			(net "GND")
			(clearance 0.2286)
			(thermal_gap 0.2286)
		)
		(pad "2" thru_hole circle
			(at -0.5715 0 90)
			(size 0.508 0.508)
			(drill 0.254)
			(layers "*.Cu" "*.Mask")
			(remove_unused_layers no)
			(net "PHY_SCC_B_TO_DRV_B_27_DP")
			(clearance 0.2286)
			(thermal_gap 0.2286)
		)
		(pad "3" thru_hole circle
			(at 0.5715 0 90)
			(size 0.508 0.508)
			(drill 0.254)
			(layers "*.Cu" "*.Mask")
			(remove_unused_layers no)
			(net "PHY_SCC_B_TO_DRV_B_27_DN")
			(clearance 0.2286)
			(thermal_gap 0.2286)
		)
		(pad "4" thru_hole circle
			(at 1.5875 0 90)
			(size 0.508 0.508)
			(drill 0.254)
			(layers "*.Cu" "*.Mask")
			(remove_unused_layers no)
			(net "GND")
			(clearance 0.2286)
			(thermal_gap 0.2286)
		)
	)
	(footprint ""
		(layer "F.Cu")
		(at 363.601 -16.256 -90)
		(property "Reference" "Q161"
			(at 0 0 270)
			(layer "F.SilkS")
			(hide yes)
			(effects
				(font
					(size 1.27 1.27)
				)
			)
		)
		(property "Value" "2N7002KDW-GP"
			(at -2.3622 -8.2042 270)
			(unlocked yes)
			(layer "F.Fab")
			(hide yes)
			(effects
				(font
					(size 1.016 1.016)
					(thickness 0.1524)
				)
			)
		)
		(property "Device Type" "SOT-363H44"
			(at -2.3622 -10.1092 270)
			(unlocked yes)
			(layer "F.Fab")
			(hide yes)
			(effects
				(font
					(size 1.016 1.016)
					(thickness 0.1524)
				)
			)
		)
		(duplicate_pad_numbers_are_jumpers no)
		(fp_line
			(start -1.4478 1.7018)
			(end 1.4478 1.7018)
			(stroke
				(width 0.1524)
				(type default)
			)
			(layer "F.SilkS")
		)
		(fp_line
			(start 1.4478 1.7018)
			(end 1.4478 -1.7018)
			(stroke
				(width 0.1524)
				(type default)
			)
			(layer "F.SilkS")
		)
		(fp_line
			(start -1.27 1.524)
			(end -1.27 0.6604)
			(stroke
				(width 0.4826)
				(type default)
			)
			(layer "F.SilkS")
		)
		(fp_line
			(start -1.4478 -1.7018)
			(end -1.4478 1.7018)
			(stroke
				(width 0.1524)
				(type default)
			)
			(layer "F.SilkS")
		)
		(fp_line
			(start 1.4478 -1.7018)
			(end -1.4478 -1.7018)
			(stroke
				(width 0.1524)
				(type default)
			)
			(layer "F.SilkS")
		)
		(fp_poly
			(pts
				(xy -1.524 -1.778) (xy 1.524 -1.778) (xy 1.524 1.778) (xy -1.524 1.778)
			)
			(stroke
				(width 0)
				(type default)
			)
			(fill no)
			(layer "F.CrtYd")
		)
		(fp_poly
			(pts
				(xy -1.524 -1.778) (xy 1.524 -1.778) (xy 1.524 1.778) (xy -1.524 1.778)
			)
			(stroke
				(width 0)
				(type default)
			)
			(fill no)
			(layer "F.Fab")
		)
		(pad "1" smd rect
			(at -0.65024 0.9398 270)
			(size 0.4064 1.016)
			(layers "F.Cu" "F.Mask" "F.Paste")
			(net "GND")
		)
		(pad "2" smd rect
			(at 0 0.9398 270)
			(size 0.4064 1.016)
			(layers "F.Cu" "F.Mask" "F.Paste")
			(net "SW_PWR_R_HDD31")
		)
		(pad "3" smd rect
			(at 0.65024 0.9398 270)
			(size 0.4064 1.016)
			(layers "F.Cu" "F.Mask" "F.Paste")
			(net "SW_HDD_P31")
		)
		(pad "4" smd rect
			(at 0.65024 -0.9398 270)
			(size 0.4064 1.016)
			(layers "F.Cu" "F.Mask" "F.Paste")
			(net "GND")
		)
		(pad "5" smd rect
			(at 0 -0.9398 270)
			(size 0.4064 1.016)
			(layers "F.Cu" "F.Mask" "F.Paste")
			(net "SW_HDD_G31")
		)
		(pad "6" smd rect
			(at -0.65024 -0.9398 270)
			(size 0.4064 1.016)
			(layers "F.Cu" "F.Mask" "F.Paste")
			(net "SW_HDD_R31")
		)
	)
	(footprint ""
		(layer "F.Cu")
		(at 457.7842 -134.6454 90)
		(property "Reference" "R583"
			(at 0 0 90)
			(layer "F.SilkS")
			(hide yes)
			(effects
				(font
					(size 1.27 1.27)
				)
			)
		)
		(property "Value" "4K7R2J-2-GP"
			(at 0.064008 -3.993896 90)
			(unlocked yes)
			(layer "F.Fab")
			(hide yes)
			(effects
				(font
					(size 1.016 1.016)
					(thickness 0.1524)
				)
			)
		)
		(property "Device Type" "R402H16"
			(at 0.064008 -5.517896 90)
			(unlocked yes)
			(layer "F.Fab")
			(hide yes)
			(effects
				(font
					(size 1.016 1.016)
					(thickness 0.1524)
				)
			)
		)
		(duplicate_pad_numbers_are_jumpers no)
		(fp_line
			(start 0.508 -0.9398)
			(end -0.508 -0.9398)
			(stroke
				(width 0.1524)
				(type default)
			)
			(layer "F.SilkS")
		)
		(fp_line
			(start -0.508 -0.9398)
			(end -0.508 0.9398)
			(stroke
				(width 0.1524)
				(type default)
			)
			(layer "F.SilkS")
		)
		(fp_rect
			(start -0.508 0.9398)
			(end 0.508 -0.9398)
			(stroke
				(width 0)
				(type default)
			)
			(fill no)
			(layer "F.CrtYd")
		)
		(fp_rect
			(start -0.508 0.9398)
			(end 0.508 -0.9398)
			(stroke
				(width 0)
				(type default)
			)
			(fill no)
			(layer "F.Fab")
		)
		(pad "1" smd custom
			(at 0 -0.4445 90)
			(size 0.1397 0.1397)
			(layers "F.Cu" "F.Mask" "F.Paste")
			(net "P12V_B")
			(options
				(clearance outline)
				(anchor circle)
			)
			(primitives
				(gr_poly
					(pts
						(arc
							(start -0.1778 -0.2794)
							(mid -0.249642 -0.249642)
							(end -0.2794 -0.1778)
						)
						(arc
							(start -0.2794 0.1778)
							(mid -0.249642 0.249642)
							(end -0.1778 0.2794)
						)
						(arc
							(start 0.1778 0.2794)
							(mid 0.249642 0.249642)
							(end 0.2794 0.1778)
						)
						(arc
							(start 0.2794 -0.1778)
							(mid 0.249642 -0.249642)
							(end 0.1778 -0.2794)
						)
					)
					(width 0)
					(fill yes)
				)
			)
		)
		(pad "2" smd custom
			(at 0 0.4445 90)
			(size 0.1397 0.1397)
			(layers "F.Cu" "F.Mask" "F.Paste")
			(net "SW_HDD_P22")
			(options
				(clearance outline)
				(anchor circle)
			)
			(primitives
				(gr_poly
					(pts
						(arc
							(start -0.1778 -0.2794)
							(mid -0.249642 -0.249642)
							(end -0.2794 -0.1778)
						)
						(arc
							(start -0.2794 0.1778)
							(mid -0.249642 0.249642)
							(end -0.1778 0.2794)
						)
						(arc
							(start 0.1778 0.2794)
							(mid 0.249642 0.249642)
							(end 0.2794 0.1778)
						)
						(arc
							(start 0.2794 -0.1778)
							(mid 0.249642 -0.249642)
							(end 0.1778 -0.2794)
						)
					)
					(width 0)
					(fill yes)
				)
			)
		)
	)
	(footprint ""
		(layer "F.Cu")
		(at 44.225718 -110.86338 90)
		(property "Reference" "C640"
			(at 0 0 90)
			(layer "F.SilkS")
			(hide yes)
			(effects
				(font
					(size 1.27 1.27)
				)
			)
		)
		(property "Value" "SC10U16V5KX-7-GP-U"
			(at -0.0762 -6.1214 90)
			(unlocked yes)
			(layer "F.Fab")
			(hide yes)
			(effects
				(font
					(size 1.016 1.016)
					(thickness 0.1524)
				)
			)
		)
		(property "Device Type" "C805H58"
			(at -0.0762 -8.1534 90)
			(unlocked yes)
			(layer "F.Fab")
			(hide yes)
			(effects
				(font
					(size 1.016 1.016)
					(thickness 0.1524)
				)
			)
		)
		(duplicate_pad_numbers_are_jumpers no)
		(fp_line
			(start 0.635 0)
			(end -0.635 0)
			(stroke
				(width 0.508)
				(type default)
			)
			(layer "F.SilkS")
		)
		(fp_rect
			(start -0.9652 1.778)
			(end 0.9652 -1.778)
			(stroke
				(width 0)
				(type default)
			)
			(fill no)
			(layer "F.CrtYd")
		)
		(fp_poly
			(pts
				(xy -0.9652 -1.778) (xy 0.9652 -1.778) (xy 0.9652 1.778) (xy -0.9652 1.778)
			)
			(stroke
				(width 0)
				(type default)
			)
			(fill no)
			(layer "F.Fab")
		)
		(pad "1" smd rect
			(at 0 -0.9652 90)
			(size 1.397 1.143)
			(layers "F.Cu" "F.Mask" "F.Paste")
			(net "P12V_B_2_VIN_U32")
		)
		(pad "2" smd rect
			(at 0 0.9652 90)
			(size 1.397 1.143)
			(layers "F.Cu" "F.Mask" "F.Paste")
			(net "GND")
		)
	)
	(footprint ""
		(layer "F.Cu")
		(at 464.6168 -5.3086 -90)
		(property "Reference" "R139"
			(at 0 0 270)
			(layer "F.SilkS")
			(hide yes)
			(effects
				(font
					(size 1.27 1.27)
				)
			)
		)
		(property "Value" "4K7R2F-GP"
			(at 0.064008 -3.993896 270)
			(unlocked yes)
			(layer "F.Fab")
			(hide yes)
			(effects
				(font
					(size 1.016 1.016)
					(thickness 0.1524)
				)
			)
		)
		(property "Device Type" "R402H16"
			(at 0.064008 -5.517896 270)
			(unlocked yes)
			(layer "F.Fab")
			(hide yes)
			(effects
				(font
					(size 1.016 1.016)
					(thickness 0.1524)
				)
			)
		)
		(duplicate_pad_numbers_are_jumpers no)
		(fp_line
			(start -0.508 -0.9398)
			(end -0.508 0.9398)
			(stroke
				(width 0.1524)
				(type default)
			)
			(layer "F.SilkS")
		)
		(fp_line
			(start 0.508 -0.9398)
			(end -0.508 -0.9398)
			(stroke
				(width 0.1524)
				(type default)
			)
			(layer "F.SilkS")
		)
		(fp_rect
			(start -0.508 0.9398)
			(end 0.508 -0.9398)
			(stroke
				(width 0)
				(type default)
			)
			(fill no)
			(layer "F.CrtYd")
		)
		(fp_rect
			(start -0.508 0.9398)
			(end 0.508 -0.9398)
			(stroke
				(width 0)
				(type default)
			)
			(fill no)
			(layer "F.Fab")
		)
		(pad "1" smd custom
			(at 0 -0.4445 270)
			(size 0.1397 0.1397)
			(layers "F.Cu" "F.Mask" "F.Paste")
			(net "TEMP2_A2")
			(options
				(clearance outline)
				(anchor circle)
			)
			(primitives
				(gr_poly
					(pts
						(arc
							(start -0.1778 -0.2794)
							(mid -0.249642 -0.249642)
							(end -0.2794 -0.1778)
						)
						(arc
							(start -0.2794 0.1778)
							(mid -0.249642 0.249642)
							(end -0.1778 0.2794)
						)
						(arc
							(start 0.1778 0.2794)
							(mid 0.249642 0.249642)
							(end 0.2794 0.1778)
						)
						(arc
							(start 0.2794 -0.1778)
							(mid 0.249642 -0.249642)
							(end 0.1778 -0.2794)
						)
					)
					(width 0)
					(fill yes)
				)
			)
		)
		(pad "2" smd custom
			(at 0 0.4445 270)
			(size 0.1397 0.1397)
			(layers "F.Cu" "F.Mask" "F.Paste")
			(net "GND")
			(options
				(clearance outline)
				(anchor circle)
			)
			(primitives
				(gr_poly
					(pts
						(arc
							(start -0.1778 -0.2794)
							(mid -0.249642 -0.249642)
							(end -0.2794 -0.1778)
						)
						(arc
							(start -0.2794 0.1778)
							(mid -0.249642 0.249642)
							(end -0.1778 0.2794)
						)
						(arc
							(start 0.1778 0.2794)
							(mid 0.249642 0.249642)
							(end 0.2794 0.1778)
						)
						(arc
							(start 0.2794 -0.1778)
							(mid 0.249642 -0.249642)
							(end 0.1778 -0.2794)
						)
					)
					(width 0)
					(fill yes)
				)
			)
		)
	)
	(footprint ""
		(layer "F.Cu")
		(at 445.167004 -363.22 90)
		(property "Reference" "C537"
			(at 0 0 90)
			(layer "F.SilkS")
			(hide yes)
			(effects
				(font
					(size 1.27 1.27)
				)
			)
		)
		(property "Value" "SC1U25V3KX-GP"
			(at 0 -2.8194 90)
			(unlocked yes)
			(layer "F.Fab")
			(hide yes)
			(effects
				(font
					(size 1.016 1.016)
					(thickness 0.1524)
				)
			)
		)
		(property "Device Type" "C603H36"
			(at 0 -4.3434 90)
			(unlocked yes)
			(layer "F.Fab")
			(hide yes)
			(effects
				(font
					(size 1.016 1.016)
					(thickness 0.1524)
				)
			)
		)
		(duplicate_pad_numbers_are_jumpers no)
		(fp_line
			(start 0.508 0)
			(end -0.508 0)
			(stroke
				(width 0.2032)
				(type default)
			)
			(layer "F.SilkS")
		)
		(fp_rect
			(start -0.5842 1.3335)
			(end 0.5842 -1.3335)
			(stroke
				(width 0)
				(type default)
			)
			(fill no)
			(layer "F.CrtYd")
		)
		(fp_rect
			(start -0.5842 1.3335)
			(end 0.5842 -1.3335)
			(stroke
				(width 0)
				(type default)
			)
			(fill no)
			(layer "F.Fab")
		)
		(pad "1" smd custom
			(at 0 -0.762 90)
			(size 0.2159 0.2159)
			(layers "F.Cu" "F.Mask" "F.Paste")
			(net "P12V_FAN3")
			(options
				(clearance outline)
				(anchor circle)
			)
			(primitives
				(gr_poly
					(pts
						(arc
							(start -0.3302 -0.4318)
							(mid -0.402042 -0.402042)
							(end -0.4318 -0.3302)
						)
						(arc
							(start -0.4318 0.3302)
							(mid -0.402042 0.402042)
							(end -0.3302 0.4318)
						)
						(arc
							(start 0.3302 0.4318)
							(mid 0.402042 0.402042)
							(end 0.4318 0.3302)
						)
						(arc
							(start 0.4318 -0.3302)
							(mid 0.402042 -0.402042)
							(end 0.3302 -0.4318)
						)
					)
					(width 0)
					(fill yes)
				)
			)
		)
		(pad "2" smd custom
			(at 0 0.762 90)
			(size 0.2159 0.2159)
			(layers "F.Cu" "F.Mask" "F.Paste")
			(net "GND")
			(options
				(clearance outline)
				(anchor circle)
			)
			(primitives
				(gr_poly
					(pts
						(arc
							(start -0.3302 -0.4318)
							(mid -0.402042 -0.402042)
							(end -0.4318 -0.3302)
						)
						(arc
							(start -0.4318 0.3302)
							(mid -0.402042 0.402042)
							(end -0.3302 0.4318)
						)
						(arc
							(start 0.3302 0.4318)
							(mid 0.402042 0.402042)
							(end 0.4318 0.3302)
						)
						(arc
							(start 0.4318 -0.3302)
							(mid 0.402042 -0.402042)
							(end 0.3302 -0.4318)
						)
					)
					(width 0)
					(fill yes)
				)
			)
		)
	)
	(footprint ""
		(layer "F.Cu")
		(at 20.066 -32.004 -90)
		(property "Reference" "C343"
			(at 0 0 270)
			(layer "F.SilkS")
			(hide yes)
			(effects
				(font
					(size 1.27 1.27)
				)
			)
		)
		(property "Value" "SC10U16V6KX-2GP"
			(at -0.0762 -5.1308 270)
			(unlocked yes)
			(layer "F.Fab")
			(hide yes)
			(effects
				(font
					(size 1.016 1.016)
					(thickness 0.1524)
				)
			)
		)
		(property "Device Type" "C1206H71"
			(at -0.127 -6.6548 270)
			(unlocked yes)
			(layer "F.Fab")
			(hide yes)
			(effects
				(font
					(size 1.016 1.016)
					(thickness 0.1524)
				)
			)
		)
		(duplicate_pad_numbers_are_jumpers no)
		(fp_line
			(start -1.016 2.2352)
			(end -1.016 0.8382)
			(stroke
				(width 0.1524)
				(type default)
			)
			(layer "F.SilkS")
		)
		(fp_line
			(start 1.016 2.2352)
			(end -1.016 2.2352)
			(stroke
				(width 0.1524)
				(type default)
			)
			(layer "F.SilkS")
		)
		(fp_line
			(start 1.016 0.8382)
			(end 1.016 2.2352)
			(stroke
				(width 0.1524)
				(type default)
			)
			(layer "F.SilkS")
		)
		(fp_line
			(start -1.016 -0.8382)
			(end -1.016 -2.2352)
			(stroke
				(width 0.1524)
				(type default)
			)
			(layer "F.SilkS")
		)
		(fp_line
			(start -1.016 -2.2352)
			(end 1.016 -2.2352)
			(stroke
				(width 0.1524)
				(type default)
			)
			(layer "F.SilkS")
		)
		(fp_line
			(start 1.016 -2.2352)
			(end 1.016 -0.8382)
			(stroke
				(width 0.1524)
				(type default)
			)
			(layer "F.SilkS")
		)
		(fp_rect
			(start -1.0922 2.3114)
			(end 1.0922 -2.3114)
			(stroke
				(width 0)
				(type default)
			)
			(fill no)
			(layer "F.CrtYd")
		)
		(fp_poly
			(pts
				(xy 1.0922 -2.3114) (xy 1.0922 2.3114) (xy -1.0922 2.3114) (xy -1.0922 -2.3114)
			)
			(stroke
				(width 0)
				(type default)
			)
			(fill no)
			(layer "F.Fab")
		)
		(pad "1" smd rect
			(at 0 -1.397 270)
			(size 1.651 1.27)
			(layers "F.Cu" "F.Mask" "F.Paste")
			(net "P5V_HDD24")
		)
		(pad "2" smd rect
			(at 0 1.397 270)
			(size 1.651 1.27)
			(layers "F.Cu" "F.Mask" "F.Paste")
			(net "GND")
		)
	)
	(footprint ""
		(layer "F.Cu")
		(at 146.685 -19.558 180)
		(property "Reference" "Q143"
			(at 0 0 180)
			(layer "F.SilkS")
			(hide yes)
			(effects
				(font
					(size 1.27 1.27)
				)
			)
		)
		(property "Value" "2N7002KDW-GP"
			(at -2.3622 -8.2042 180)
			(unlocked yes)
			(layer "F.Fab")
			(hide yes)
			(effects
				(font
					(size 1.016 1.016)
					(thickness 0.1524)
				)
			)
		)
		(property "Device Type" "SOT-363H44"
			(at -2.3622 -10.1092 180)
			(unlocked yes)
			(layer "F.Fab")
			(hide yes)
			(effects
				(font
					(size 1.016 1.016)
					(thickness 0.1524)
				)
			)
		)
		(duplicate_pad_numbers_are_jumpers no)
		(fp_line
			(start 1.4478 1.7018)
			(end 1.4478 -1.7018)
			(stroke
				(width 0.1524)
				(type default)
			)
			(layer "F.SilkS")
		)
		(fp_line
			(start 1.4478 -1.7018)
			(end -1.4478 -1.7018)
			(stroke
				(width 0.1524)
				(type default)
			)
			(layer "F.SilkS")
		)
		(fp_line
			(start -1.27 1.524)
			(end -1.27 0.6604)
			(stroke
				(width 0.4826)
				(type default)
			)
			(layer "F.SilkS")
		)
		(fp_line
			(start -1.4478 1.7018)
			(end 1.4478 1.7018)
			(stroke
				(width 0.1524)
				(type default)
			)
			(layer "F.SilkS")
		)
		(fp_line
			(start -1.4478 -1.7018)
			(end -1.4478 1.7018)
			(stroke
				(width 0.1524)
				(type default)
			)
			(layer "F.SilkS")
		)
		(fp_poly
			(pts
				(xy -1.524 -1.778) (xy 1.524 -1.778) (xy 1.524 1.778) (xy -1.524 1.778)
			)
			(stroke
				(width 0)
				(type default)
			)
			(fill no)
			(layer "F.CrtYd")
		)
		(fp_poly
			(pts
				(xy -1.524 -1.778) (xy 1.524 -1.778) (xy 1.524 1.778) (xy -1.524 1.778)
			)
			(stroke
				(width 0)
				(type default)
			)
			(fill no)
			(layer "F.Fab")
		)
		(pad "1" smd rect
			(at -0.65024 0.9398 180)
			(size 0.4064 1.016)
			(layers "F.Cu" "F.Mask" "F.Paste")
			(net "GND")
		)
		(pad "2" smd rect
			(at 0 0.9398 180)
			(size 0.4064 1.016)
			(layers "F.Cu" "F.Mask" "F.Paste")
			(net "SW_PWR_R_HDD28")
		)
		(pad "3" smd rect
			(at 0.65024 0.9398 180)
			(size 0.4064 1.016)
			(layers "F.Cu" "F.Mask" "F.Paste")
			(net "SW_HDD_P28")
		)
		(pad "4" smd rect
			(at 0.65024 -0.9398 180)
			(size 0.4064 1.016)
			(layers "F.Cu" "F.Mask" "F.Paste")
			(net "GND")
		)
		(pad "5" smd rect
			(at 0 -0.9398 180)
			(size 0.4064 1.016)
			(layers "F.Cu" "F.Mask" "F.Paste")
			(net "SW_HDD_G28")
		)
		(pad "6" smd rect
			(at -0.65024 -0.9398 180)
			(size 0.4064 1.016)
			(layers "F.Cu" "F.Mask" "F.Paste")
			(net "SW_HDD_R28")
		)
	)
	(footprint ""
		(layer "F.Cu")
		(at 287.048448 -347.541342)
		(property "Reference" "R1079"
			(at 0 0 0)
			(layer "F.SilkS")
			(hide yes)
			(effects
				(font
					(size 1.27 1.27)
				)
			)
		)
		(property "Value" "0R2J-2-GP"
			(at 0.064008 -3.993896 0)
			(unlocked yes)
			(layer "F.Fab")
			(hide yes)
			(effects
				(font
					(size 1.016 1.016)
					(thickness 0.1524)
				)
			)
		)
		(property "Device Type" "R402H16"
			(at 0.064008 -5.517896 0)
			(unlocked yes)
			(layer "F.Fab")
			(hide yes)
			(effects
				(font
					(size 1.016 1.016)
					(thickness 0.1524)
				)
			)
		)
		(duplicate_pad_numbers_are_jumpers no)
		(fp_line
			(start -0.508 -0.9398)
			(end -0.508 0.9398)
			(stroke
				(width 0.1524)
				(type default)
			)
			(layer "F.SilkS")
		)
		(fp_line
			(start 0.508 -0.9398)
			(end -0.508 -0.9398)
			(stroke
				(width 0.1524)
				(type default)
			)
			(layer "F.SilkS")
		)
		(fp_rect
			(start -0.508 0.9398)
			(end 0.508 -0.9398)
			(stroke
				(width 0)
				(type default)
			)
			(fill no)
			(layer "F.CrtYd")
		)
		(fp_rect
			(start -0.508 0.9398)
			(end 0.508 -0.9398)
			(stroke
				(width 0)
				(type default)
			)
			(fill no)
			(layer "F.Fab")
		)
		(pad "1" smd custom
			(at 0 -0.4445)
			(size 0.1397 0.1397)
			(layers "F.Cu" "F.Mask" "F.Paste")
			(net "MAX31790_B_ADD0")
			(options
				(clearance outline)
				(anchor circle)
			)
			(primitives
				(gr_poly
					(pts
						(arc
							(start -0.1778 -0.2794)
							(mid -0.249642 -0.249642)
							(end -0.2794 -0.1778)
						)
						(arc
							(start -0.2794 0.1778)
							(mid -0.249642 0.249642)
							(end -0.1778 0.2794)
						)
						(arc
							(start 0.1778 0.2794)
							(mid 0.249642 0.249642)
							(end 0.2794 0.1778)
						)
						(arc
							(start 0.2794 -0.1778)
							(mid 0.249642 -0.249642)
							(end 0.1778 -0.2794)
						)
					)
					(width 0)
					(fill yes)
				)
			)
		)
		(pad "2" smd custom
			(at 0 0.4445)
			(size 0.1397 0.1397)
			(layers "F.Cu" "F.Mask" "F.Paste")
			(net "GND")
			(options
				(clearance outline)
				(anchor circle)
			)
			(primitives
				(gr_poly
					(pts
						(arc
							(start -0.1778 -0.2794)
							(mid -0.249642 -0.249642)
							(end -0.2794 -0.1778)
						)
						(arc
							(start -0.2794 0.1778)
							(mid -0.249642 0.249642)
							(end -0.1778 0.2794)
						)
						(arc
							(start 0.1778 0.2794)
							(mid 0.249642 0.249642)
							(end 0.2794 0.1778)
						)
						(arc
							(start 0.2794 -0.1778)
							(mid 0.249642 -0.249642)
							(end 0.1778 -0.2794)
						)
					)
					(width 0)
					(fill yes)
				)
			)
		)
	)
	(footprint ""
		(layer "F.Cu")
		(at 44.528232 -212.323172 90)
		(property "Reference" "R157"
			(at 0 0 90)
			(layer "F.SilkS")
			(hide yes)
			(effects
				(font
					(size 1.27 1.27)
				)
			)
		)
		(property "Value" "4K7R2F-GP"
			(at 0.064008 -3.993896 90)
			(unlocked yes)
			(layer "F.Fab")
			(hide yes)
			(effects
				(font
					(size 1.016 1.016)
					(thickness 0.1524)
				)
			)
		)
		(property "Device Type" "R402H16"
			(at 0.064008 -5.517896 90)
			(unlocked yes)
			(layer "F.Fab")
			(hide yes)
			(effects
				(font
					(size 1.016 1.016)
					(thickness 0.1524)
				)
			)
		)
		(duplicate_pad_numbers_are_jumpers no)
		(fp_line
			(start 0.508 -0.9398)
			(end -0.508 -0.9398)
			(stroke
				(width 0.1524)
				(type default)
			)
			(layer "F.SilkS")
		)
		(fp_line
			(start -0.508 -0.9398)
			(end -0.508 0.9398)
			(stroke
				(width 0.1524)
				(type default)
			)
			(layer "F.SilkS")
		)
		(fp_rect
			(start -0.508 0.9398)
			(end 0.508 -0.9398)
			(stroke
				(width 0)
				(type default)
			)
			(fill no)
			(layer "F.CrtYd")
		)
		(fp_rect
			(start -0.508 0.9398)
			(end 0.508 -0.9398)
			(stroke
				(width 0)
				(type default)
			)
			(fill no)
			(layer "F.Fab")
		)
		(pad "1" smd custom
			(at 0 -0.4445 90)
			(size 0.1397 0.1397)
			(layers "F.Cu" "F.Mask" "F.Paste")
			(net "DRIVE_B_1_ACT")
			(options
				(clearance outline)
				(anchor circle)
			)
			(primitives
				(gr_poly
					(pts
						(arc
							(start -0.1778 -0.2794)
							(mid -0.249642 -0.249642)
							(end -0.2794 -0.1778)
						)
						(arc
							(start -0.2794 0.1778)
							(mid -0.249642 0.249642)
							(end -0.1778 0.2794)
						)
						(arc
							(start 0.1778 0.2794)
							(mid 0.249642 0.249642)
							(end 0.2794 0.1778)
						)
						(arc
							(start 0.2794 -0.1778)
							(mid 0.249642 -0.249642)
							(end 0.1778 -0.2794)
						)
					)
					(width 0)
					(fill yes)
				)
			)
		)
		(pad "2" smd custom
			(at 0 0.4445 90)
			(size 0.1397 0.1397)
			(layers "F.Cu" "F.Mask" "F.Paste")
			(net "GND")
			(options
				(clearance outline)
				(anchor circle)
			)
			(primitives
				(gr_poly
					(pts
						(arc
							(start -0.1778 -0.2794)
							(mid -0.249642 -0.249642)
							(end -0.2794 -0.1778)
						)
						(arc
							(start -0.2794 0.1778)
							(mid -0.249642 0.249642)
							(end -0.1778 0.2794)
						)
						(arc
							(start 0.1778 0.2794)
							(mid 0.249642 0.249642)
							(end 0.2794 0.1778)
						)
						(arc
							(start 0.2794 -0.1778)
							(mid 0.249642 -0.249642)
							(end 0.1778 -0.2794)
						)
					)
					(width 0)
					(fill yes)
				)
			)
		)
	)
	(footprint ""
		(layer "F.Cu")
		(at 77.978 -25.527 90)
		(property "Reference" "C377"
			(at 0 0 90)
			(layer "F.SilkS")
			(hide yes)
			(effects
				(font
					(size 1.27 1.27)
				)
			)
		)
		(property "Value" "SCD033U25V2KX-GP"
			(at 1.1811 -2.7051 90)
			(unlocked yes)
			(layer "F.Fab")
			(hide yes)
			(effects
				(font
					(size 1.016 1.016)
					(thickness 0.1524)
				)
			)
		)
		(property "Device Type" "C402H22"
			(at 1.1811 -4.2291 90)
			(unlocked yes)
			(layer "F.Fab")
			(hide yes)
			(effects
				(font
					(size 1.016 1.016)
					(thickness 0.1524)
				)
			)
		)
		(duplicate_pad_numbers_are_jumpers no)
		(fp_rect
			(start -0.4318 0.9525)
			(end 0.4318 -0.9525)
			(stroke
				(width 0)
				(type default)
			)
			(fill no)
			(layer "F.CrtYd")
		)
		(fp_rect
			(start -0.4318 0.9525)
			(end 0.4318 -0.9525)
			(stroke
				(width 0)
				(type default)
			)
			(fill no)
			(layer "F.Fab")
		)
		(pad "1" smd custom
			(at 0 -0.4445 90)
			(size 0.1524 0.1524)
			(layers "F.Cu" "F.Mask" "F.Paste")
			(net "P12V_B")
			(options
				(clearance outline)
				(anchor circle)
			)
			(primitives
				(gr_poly
					(pts
						(arc
							(start 0.3048 -0.2032)
							(mid 0.275042 -0.275042)
							(end 0.2032 -0.3048)
						)
						(arc
							(start -0.2032 -0.3048)
							(mid -0.275042 -0.275042)
							(end -0.3048 -0.2032)
						)
						(arc
							(start -0.3048 0.2032)
							(mid -0.275042 0.275042)
							(end -0.2032 0.3048)
						)
						(arc
							(start 0.2032 0.3048)
							(mid 0.275042 0.275042)
							(end 0.3048 0.2032)
						)
					)
					(width 0)
					(fill yes)
				)
			)
		)
		(pad "2" smd custom
			(at 0 0.4445 90)
			(size 0.1524 0.1524)
			(layers "F.Cu" "F.Mask" "F.Paste")
			(net "SW_HDD_N26")
			(options
				(clearance outline)
				(anchor circle)
			)
			(primitives
				(gr_poly
					(pts
						(arc
							(start 0.3048 -0.2032)
							(mid 0.275042 -0.275042)
							(end 0.2032 -0.3048)
						)
						(arc
							(start -0.2032 -0.3048)
							(mid -0.275042 -0.275042)
							(end -0.3048 -0.2032)
						)
						(arc
							(start -0.3048 0.2032)
							(mid -0.275042 0.275042)
							(end -0.2032 0.3048)
						)
						(arc
							(start 0.2032 0.3048)
							(mid 0.275042 0.275042)
							(end 0.3048 0.2032)
						)
					)
					(width 0)
					(fill yes)
				)
			)
		)
	)
	(footprint ""
		(layer "F.Cu")
		(at 213.35238 -245.91518 180)
		(property "Reference" "R35"
			(at 0 0 180)
			(layer "F.SilkS")
			(hide yes)
			(effects
				(font
					(size 1.27 1.27)
				)
			)
		)
		(property "Value" "0R2J-2-GP"
			(at 0.064008 -3.993896 180)
			(unlocked yes)
			(layer "F.Fab")
			(hide yes)
			(effects
				(font
					(size 1.016 1.016)
					(thickness 0.1524)
				)
			)
		)
		(property "Device Type" "R402H16"
			(at 0.064008 -5.517896 180)
			(unlocked yes)
			(layer "F.Fab")
			(hide yes)
			(effects
				(font
					(size 1.016 1.016)
					(thickness 0.1524)
				)
			)
		)
		(duplicate_pad_numbers_are_jumpers no)
		(fp_line
			(start 0.508 -0.9398)
			(end -0.508 -0.9398)
			(stroke
				(width 0.1524)
				(type default)
			)
			(layer "F.SilkS")
		)
		(fp_line
			(start -0.508 -0.9398)
			(end -0.508 0.9398)
			(stroke
				(width 0.1524)
				(type default)
			)
			(layer "F.SilkS")
		)
		(fp_rect
			(start -0.508 0.9398)
			(end 0.508 -0.9398)
			(stroke
				(width 0)
				(type default)
			)
			(fill no)
			(layer "F.CrtYd")
		)
		(fp_rect
			(start -0.508 0.9398)
			(end 0.508 -0.9398)
			(stroke
				(width 0)
				(type default)
			)
			(fill no)
			(layer "F.Fab")
		)
		(pad "1" smd custom
			(at 0 -0.4445 180)
			(size 0.1397 0.1397)
			(layers "F.Cu" "F.Mask" "F.Paste")
			(net "IO_EXP4_INT_N")
			(options
				(clearance outline)
				(anchor circle)
			)
			(primitives
				(gr_poly
					(pts
						(arc
							(start -0.1778 -0.2794)
							(mid -0.249642 -0.249642)
							(end -0.2794 -0.1778)
						)
						(arc
							(start -0.2794 0.1778)
							(mid -0.249642 0.249642)
							(end -0.1778 0.2794)
						)
						(arc
							(start 0.1778 0.2794)
							(mid 0.249642 0.249642)
							(end 0.2794 0.1778)
						)
						(arc
							(start 0.2794 -0.1778)
							(mid 0.249642 -0.249642)
							(end 0.1778 -0.2794)
						)
					)
					(width 0)
					(fill yes)
				)
			)
		)
		(pad "2" smd custom
			(at 0 0.4445 180)
			(size 0.1397 0.1397)
			(layers "F.Cu" "F.Mask" "F.Paste")
			(net "DRIVE_INSERT_ALERT_B_N")
			(options
				(clearance outline)
				(anchor circle)
			)
			(primitives
				(gr_poly
					(pts
						(arc
							(start -0.1778 -0.2794)
							(mid -0.249642 -0.249642)
							(end -0.2794 -0.1778)
						)
						(arc
							(start -0.2794 0.1778)
							(mid -0.249642 0.249642)
							(end -0.1778 0.2794)
						)
						(arc
							(start 0.1778 0.2794)
							(mid 0.249642 0.249642)
							(end 0.2794 0.1778)
						)
						(arc
							(start 0.2794 -0.1778)
							(mid 0.249642 -0.249642)
							(end 0.1778 -0.2794)
						)
					)
					(width 0)
					(fill yes)
				)
			)
		)
	)
	(footprint ""
		(layer "F.Cu")
		(at 416.1028 -146.6342)
		(property "Reference" "C310"
			(at 0 0 0)
			(layer "F.SilkS")
			(hide yes)
			(effects
				(font
					(size 1.27 1.27)
				)
			)
		)
		(property "Value" "SCD01U50V2KX-1GP"
			(at 1.1811 -2.7051 0)
			(unlocked yes)
			(layer "F.Fab")
			(hide yes)
			(effects
				(font
					(size 1.016 1.016)
					(thickness 0.1524)
				)
			)
		)
		(property "Device Type" "C402H22"
			(at 1.1811 -4.2291 0)
			(unlocked yes)
			(layer "F.Fab")
			(hide yes)
			(effects
				(font
					(size 1.016 1.016)
					(thickness 0.1524)
				)
			)
		)
		(duplicate_pad_numbers_are_jumpers no)
		(fp_rect
			(start -0.4318 0.9525)
			(end 0.4318 -0.9525)
			(stroke
				(width 0)
				(type default)
			)
			(fill no)
			(layer "F.CrtYd")
		)
		(fp_rect
			(start -0.4318 0.9525)
			(end 0.4318 -0.9525)
			(stroke
				(width 0)
				(type default)
			)
			(fill no)
			(layer "F.Fab")
		)
		(pad "1" smd custom
			(at 0 -0.4445)
			(size 0.1524 0.1524)
			(layers "F.Cu" "F.Mask" "F.Paste")
			(net "HDD_PRSNT_21")
			(options
				(clearance outline)
				(anchor circle)
			)
			(primitives
				(gr_poly
					(pts
						(arc
							(start 0.3048 -0.2032)
							(mid 0.275042 -0.275042)
							(end 0.2032 -0.3048)
						)
						(arc
							(start -0.2032 -0.3048)
							(mid -0.275042 -0.275042)
							(end -0.3048 -0.2032)
						)
						(arc
							(start -0.3048 0.2032)
							(mid -0.275042 0.275042)
							(end -0.2032 0.3048)
						)
						(arc
							(start 0.2032 0.3048)
							(mid 0.275042 0.275042)
							(end 0.3048 0.2032)
						)
					)
					(width 0)
					(fill yes)
				)
			)
		)
		(pad "2" smd custom
			(at 0 0.4445)
			(size 0.1524 0.1524)
			(layers "F.Cu" "F.Mask" "F.Paste")
			(net "GND")
			(options
				(clearance outline)
				(anchor circle)
			)
			(primitives
				(gr_poly
					(pts
						(arc
							(start 0.3048 -0.2032)
							(mid 0.275042 -0.275042)
							(end 0.2032 -0.3048)
						)
						(arc
							(start -0.2032 -0.3048)
							(mid -0.275042 -0.275042)
							(end -0.3048 -0.2032)
						)
						(arc
							(start -0.3048 0.2032)
							(mid -0.275042 0.275042)
							(end -0.2032 0.3048)
						)
						(arc
							(start 0.2032 0.3048)
							(mid 0.275042 0.275042)
							(end 0.3048 0.2032)
						)
					)
					(width 0)
					(fill yes)
				)
			)
		)
	)
	(footprint ""
		(layer "F.Cu")
		(at 253.451614 -140.228574 -90)
		(property "Reference" "R447"
			(at 0 0 270)
			(layer "F.SilkS")
			(hide yes)
			(effects
				(font
					(size 1.27 1.27)
				)
			)
		)
		(property "Value" "1KR2J-1-GP"
			(at 0.064008 -3.993896 270)
			(unlocked yes)
			(layer "F.Fab")
			(hide yes)
			(effects
				(font
					(size 1.016 1.016)
					(thickness 0.1524)
				)
			)
		)
		(property "Device Type" "R402H16"
			(at 0.064008 -5.517896 270)
			(unlocked yes)
			(layer "F.Fab")
			(hide yes)
			(effects
				(font
					(size 1.016 1.016)
					(thickness 0.1524)
				)
			)
		)
		(duplicate_pad_numbers_are_jumpers no)
		(fp_line
			(start -0.508 -0.9398)
			(end -0.508 0.9398)
			(stroke
				(width 0.1524)
				(type default)
			)
			(layer "F.SilkS")
		)
		(fp_line
			(start 0.508 -0.9398)
			(end -0.508 -0.9398)
			(stroke
				(width 0.1524)
				(type default)
			)
			(layer "F.SilkS")
		)
		(fp_rect
			(start -0.508 0.9398)
			(end 0.508 -0.9398)
			(stroke
				(width 0)
				(type default)
			)
			(fill no)
			(layer "F.CrtYd")
		)
		(fp_rect
			(start -0.508 0.9398)
			(end 0.508 -0.9398)
			(stroke
				(width 0)
				(type default)
			)
			(fill no)
			(layer "F.Fab")
		)
		(pad "1" smd custom
			(at 0 -0.4445 270)
			(size 0.1397 0.1397)
			(layers "F.Cu" "F.Mask" "F.Paste")
			(net "P3V3_STBY_B")
			(options
				(clearance outline)
				(anchor circle)
			)
			(primitives
				(gr_poly
					(pts
						(arc
							(start -0.1778 -0.2794)
							(mid -0.249642 -0.249642)
							(end -0.2794 -0.1778)
						)
						(arc
							(start -0.2794 0.1778)
							(mid -0.249642 0.249642)
							(end -0.1778 0.2794)
						)
						(arc
							(start 0.1778 0.2794)
							(mid 0.249642 0.249642)
							(end 0.2794 0.1778)
						)
						(arc
							(start 0.2794 -0.1778)
							(mid 0.249642 -0.249642)
							(end 0.1778 -0.2794)
						)
					)
					(width 0)
					(fill yes)
				)
			)
		)
		(pad "2" smd custom
			(at 0 0.4445 270)
			(size 0.1397 0.1397)
			(layers "F.Cu" "F.Mask" "F.Paste")
			(net "I2C_SCC_B_SDA_BUF")
			(options
				(clearance outline)
				(anchor circle)
			)
			(primitives
				(gr_poly
					(pts
						(arc
							(start -0.1778 -0.2794)
							(mid -0.249642 -0.249642)
							(end -0.2794 -0.1778)
						)
						(arc
							(start -0.2794 0.1778)
							(mid -0.249642 0.249642)
							(end -0.1778 0.2794)
						)
						(arc
							(start 0.1778 0.2794)
							(mid 0.249642 0.249642)
							(end 0.2794 0.1778)
						)
						(arc
							(start 0.2794 -0.1778)
							(mid 0.249642 -0.249642)
							(end 0.1778 -0.2794)
						)
					)
					(width 0)
					(fill yes)
				)
			)
		)
	)
	(footprint ""
		(layer "F.Cu")
		(at 40.252396 -360.9594)
		(property "Reference" "C66"
			(at 0 0 0)
			(layer "F.SilkS")
			(hide yes)
			(effects
				(font
					(size 1.27 1.27)
				)
			)
		)
		(property "Value" "SCD1U16V2KX-3GP"
			(at 1.1811 -2.7051 0)
			(unlocked yes)
			(layer "F.Fab")
			(hide yes)
			(effects
				(font
					(size 1.016 1.016)
					(thickness 0.1524)
				)
			)
		)
		(property "Device Type" "C402H22"
			(at 1.1811 -4.2291 0)
			(unlocked yes)
			(layer "F.Fab")
			(hide yes)
			(effects
				(font
					(size 1.016 1.016)
					(thickness 0.1524)
				)
			)
		)
		(duplicate_pad_numbers_are_jumpers no)
		(fp_rect
			(start -0.4318 0.9525)
			(end 0.4318 -0.9525)
			(stroke
				(width 0)
				(type default)
			)
			(fill no)
			(layer "F.CrtYd")
		)
		(fp_rect
			(start -0.4318 0.9525)
			(end 0.4318 -0.9525)
			(stroke
				(width 0)
				(type default)
			)
			(fill no)
			(layer "F.Fab")
		)
		(pad "1" smd custom
			(at 0 -0.4445)
			(size 0.1524 0.1524)
			(layers "F.Cu" "F.Mask" "F.Paste")
			(net "P3V3_IN")
			(options
				(clearance outline)
				(anchor circle)
			)
			(primitives
				(gr_poly
					(pts
						(arc
							(start 0.3048 -0.2032)
							(mid 0.275042 -0.275042)
							(end 0.2032 -0.3048)
						)
						(arc
							(start -0.2032 -0.3048)
							(mid -0.275042 -0.275042)
							(end -0.3048 -0.2032)
						)
						(arc
							(start -0.3048 0.2032)
							(mid -0.275042 0.275042)
							(end -0.2032 0.3048)
						)
						(arc
							(start 0.2032 0.3048)
							(mid 0.275042 0.275042)
							(end 0.3048 0.2032)
						)
					)
					(width 0)
					(fill yes)
				)
			)
		)
		(pad "2" smd custom
			(at 0 0.4445)
			(size 0.1524 0.1524)
			(layers "F.Cu" "F.Mask" "F.Paste")
			(net "GND")
			(options
				(clearance outline)
				(anchor circle)
			)
			(primitives
				(gr_poly
					(pts
						(arc
							(start 0.3048 -0.2032)
							(mid 0.275042 -0.275042)
							(end 0.2032 -0.3048)
						)
						(arc
							(start -0.2032 -0.3048)
							(mid -0.275042 -0.275042)
							(end -0.3048 -0.2032)
						)
						(arc
							(start -0.3048 0.2032)
							(mid -0.275042 0.275042)
							(end -0.2032 0.3048)
						)
						(arc
							(start 0.2032 0.3048)
							(mid 0.275042 0.275042)
							(end 0.3048 0.2032)
						)
					)
					(width 0)
					(fill yes)
				)
			)
		)
	)
	(footprint ""
		(layer "F.Cu")
		(at 221.73946 -163.37026 -90)
		(property "Reference" "R54"
			(at 0 0 270)
			(layer "F.SilkS")
			(hide yes)
			(effects
				(font
					(size 1.27 1.27)
				)
			)
		)
		(property "Value" "4K7R2F-GP"
			(at 0.064008 -3.993896 270)
			(unlocked yes)
			(layer "F.Fab")
			(hide yes)
			(effects
				(font
					(size 1.016 1.016)
					(thickness 0.1524)
				)
			)
		)
		(property "Device Type" "R402H16"
			(at 0.064008 -5.517896 270)
			(unlocked yes)
			(layer "F.Fab")
			(hide yes)
			(effects
				(font
					(size 1.016 1.016)
					(thickness 0.1524)
				)
			)
		)
		(duplicate_pad_numbers_are_jumpers no)
		(fp_line
			(start -0.508 -0.9398)
			(end -0.508 0.9398)
			(stroke
				(width 0.1524)
				(type default)
			)
			(layer "F.SilkS")
		)
		(fp_line
			(start 0.508 -0.9398)
			(end -0.508 -0.9398)
			(stroke
				(width 0.1524)
				(type default)
			)
			(layer "F.SilkS")
		)
		(fp_rect
			(start -0.508 0.9398)
			(end 0.508 -0.9398)
			(stroke
				(width 0)
				(type default)
			)
			(fill no)
			(layer "F.CrtYd")
		)
		(fp_rect
			(start -0.508 0.9398)
			(end 0.508 -0.9398)
			(stroke
				(width 0)
				(type default)
			)
			(fill no)
			(layer "F.Fab")
		)
		(pad "1" smd custom
			(at 0 -0.4445 270)
			(size 0.1397 0.1397)
			(layers "F.Cu" "F.Mask" "F.Paste")
			(net "P3V3_STBY_B")
			(options
				(clearance outline)
				(anchor circle)
			)
			(primitives
				(gr_poly
					(pts
						(arc
							(start -0.1778 -0.2794)
							(mid -0.249642 -0.249642)
							(end -0.2794 -0.1778)
						)
						(arc
							(start -0.2794 0.1778)
							(mid -0.249642 0.249642)
							(end -0.1778 0.2794)
						)
						(arc
							(start 0.1778 0.2794)
							(mid 0.249642 0.249642)
							(end 0.2794 0.1778)
						)
						(arc
							(start 0.2794 -0.1778)
							(mid 0.249642 -0.249642)
							(end 0.1778 -0.2794)
						)
					)
					(width 0)
					(fill yes)
				)
			)
		)
		(pad "2" smd custom
			(at 0 0.4445 270)
			(size 0.1397 0.1397)
			(layers "F.Cu" "F.Mask" "F.Paste")
			(net "IO_EXP6_A1")
			(options
				(clearance outline)
				(anchor circle)
			)
			(primitives
				(gr_poly
					(pts
						(arc
							(start -0.1778 -0.2794)
							(mid -0.249642 -0.249642)
							(end -0.2794 -0.1778)
						)
						(arc
							(start -0.2794 0.1778)
							(mid -0.249642 0.249642)
							(end -0.1778 0.2794)
						)
						(arc
							(start 0.1778 0.2794)
							(mid 0.249642 0.249642)
							(end 0.2794 0.1778)
						)
						(arc
							(start 0.2794 -0.1778)
							(mid 0.249642 -0.249642)
							(end 0.1778 -0.2794)
						)
					)
					(width 0)
					(fill yes)
				)
			)
		)
	)
	(footprint ""
		(layer "F.Cu")
		(at 29.431996 -369.7478 180)
		(property "Reference" "U49"
			(at 0 0 180)
			(layer "F.SilkS")
			(hide yes)
			(effects
				(font
					(size 1.27 1.27)
				)
			)
		)
		(property "Value" "SN74LVC1G08DCKR-GP"
			(at -2.3368 -8.6868 180)
			(unlocked yes)
			(layer "F.Fab")
			(hide yes)
			(effects
				(font
					(size 1.016 1.016)
					(thickness 0.1524)
				)
			)
		)
		(property "Device Type" "SC70-5H44"
			(at -2.3114 -10.414 180)
			(unlocked yes)
			(layer "F.Fab")
			(hide yes)
			(effects
				(font
					(size 1.016 1.016)
					(thickness 0.1524)
				)
			)
		)
		(duplicate_pad_numbers_are_jumpers no)
		(fp_line
			(start 1.3843 -1.8034)
			(end 1.3843 -1.1176)
			(stroke
				(width 0.3302)
				(type default)
			)
			(layer "F.SilkS")
		)
		(fp_line
			(start 1.27 1.7018)
			(end -1.27 1.7018)
			(stroke
				(width 0.1524)
				(type default)
			)
			(layer "F.SilkS")
		)
		(fp_line
			(start 1.27 -1.7018)
			(end 1.27 1.7018)
			(stroke
				(width 0.1524)
				(type default)
			)
			(layer "F.SilkS")
		)
		(fp_line
			(start 0.6604 -1.8034)
			(end 1.3843 -1.8034)
			(stroke
				(width 0.3302)
				(type default)
			)
			(layer "F.SilkS")
		)
		(fp_line
			(start -1.27 1.7018)
			(end -1.27 -1.7018)
			(stroke
				(width 0.1524)
				(type default)
			)
			(layer "F.SilkS")
		)
		(fp_line
			(start -1.27 -1.7018)
			(end 1.27 -1.7018)
			(stroke
				(width 0.1524)
				(type default)
			)
			(layer "F.SilkS")
		)
		(fp_rect
			(start -1.524 1.9558)
			(end 1.524 -1.9558)
			(stroke
				(width 0)
				(type default)
			)
			(fill no)
			(layer "F.CrtYd")
		)
		(fp_poly
			(pts
				(xy -1.524 -1.9558) (xy 1.524 -1.9558) (xy 1.524 1.9558) (xy -1.524 1.9558)
			)
			(stroke
				(width 0)
				(type default)
			)
			(fill no)
			(layer "F.Fab")
		)
		(pad "1" smd rect
			(at 0.65024 -0.8255 180)
			(size 0.4064 1.2192)
			(layers "F.Cu" "F.Mask" "F.Paste")
			(net "RDPB_FAN_LED0")
		)
		(pad "2" smd rect
			(at 0 -0.8255 180)
			(size 0.4064 1.2192)
			(layers "F.Cu" "F.Mask" "F.Paste")
			(net "FDPB_FAN_LED0")
		)
		(pad "3" smd rect
			(at -0.65024 -0.8255 180)
			(size 0.4064 1.2192)
			(layers "F.Cu" "F.Mask" "F.Paste")
			(net "GND")
		)
		(pad "4" smd rect
			(at -0.65024 0.8255 180)
			(size 0.4064 1.2192)
			(layers "F.Cu" "F.Mask" "F.Paste")
			(net "FAN_LED0")
		)
		(pad "5" smd rect
			(at 0.65024 0.8255 180)
			(size 0.4064 1.2192)
			(layers "F.Cu" "F.Mask" "F.Paste")
			(net "P3V3_IN")
		)
	)
	(footprint ""
		(layer "F.Cu")
		(at 209.941668 -356.274624 90)
		(property "Reference" "R1020"
			(at 0 0 90)
			(layer "F.SilkS")
			(hide yes)
			(effects
				(font
					(size 1.27 1.27)
				)
			)
		)
		(property "Value" "10R5F-1-GP"
			(at 0 -8.9535 90)
			(unlocked yes)
			(layer "F.Fab")
			(hide yes)
			(effects
				(font
					(size 1.27 1.016)
					(thickness 0.1524)
				)
			)
		)
		(property "Device Type" "R805H24"
			(at 0 -10.6299 90)
			(unlocked yes)
			(layer "F.Fab")
			(hide yes)
			(effects
				(font
					(size 1.27 1.016)
					(thickness 0.1524)
				)
			)
		)
		(duplicate_pad_numbers_are_jumpers no)
		(fp_line
			(start 0.889 -1.7018)
			(end -0.889 -1.7018)
			(stroke
				(width 0.1524)
				(type default)
			)
			(layer "F.SilkS")
		)
		(fp_line
			(start 0.889 -1.7018)
			(end 0.889 -0.381)
			(stroke
				(width 0.1524)
				(type default)
			)
			(layer "F.SilkS")
		)
		(fp_line
			(start -0.889 -1.7018)
			(end -0.889 0.2794)
			(stroke
				(width 0.1524)
				(type default)
			)
			(layer "F.SilkS")
		)
		(fp_line
			(start -0.889 0.0762)
			(end -0.889 1.7018)
			(stroke
				(width 0.1524)
				(type default)
			)
			(layer "F.SilkS")
		)
		(fp_line
			(start 0.889 1.7018)
			(end 0.889 -0.508)
			(stroke
				(width 0.1524)
				(type default)
			)
			(layer "F.SilkS")
		)
		(fp_line
			(start -0.889 1.7018)
			(end 0.889 1.7018)
			(stroke
				(width 0.1524)
				(type default)
			)
			(layer "F.SilkS")
		)
		(fp_poly
			(pts
				(xy 0.9652 -1.778) (xy 0.9652 1.778) (xy -0.9652 1.778) (xy -0.9652 -1.778)
			)
			(stroke
				(width 0)
				(type default)
			)
			(fill no)
			(layer "F.CrtYd")
		)
		(fp_rect
			(start -0.9652 1.778)
			(end 0.9652 -1.778)
			(stroke
				(width 0)
				(type default)
			)
			(fill no)
			(layer "F.Fab")
		)
		(pad "1" smd rect
			(at 0 -0.9652 90)
			(size 1.397 1.143)
			(layers "F.Cu" "F.Mask" "F.Paste")
			(net "MB0_12V_CTRL_GATE6")
		)
		(pad "2" smd rect
			(at 0 0.9652 90)
			(size 1.397 1.143)
			(layers "F.Cu" "F.Mask" "F.Paste")
			(net "MB0_CM_GATE_R")
		)
	)
	(footprint ""
		(layer "F.Cu")
		(at 44.225718 -112.809274 90)
		(property "Reference" "C639"
			(at 0 0 90)
			(layer "F.SilkS")
			(hide yes)
			(effects
				(font
					(size 1.27 1.27)
				)
			)
		)
		(property "Value" "SC10U16V5KX-7-GP-U"
			(at -0.0762 -6.1214 90)
			(unlocked yes)
			(layer "F.Fab")
			(hide yes)
			(effects
				(font
					(size 1.016 1.016)
					(thickness 0.1524)
				)
			)
		)
		(property "Device Type" "C805H58"
			(at -0.0762 -8.1534 90)
			(unlocked yes)
			(layer "F.Fab")
			(hide yes)
			(effects
				(font
					(size 1.016 1.016)
					(thickness 0.1524)
				)
			)
		)
		(duplicate_pad_numbers_are_jumpers no)
		(fp_line
			(start 0.635 0)
			(end -0.635 0)
			(stroke
				(width 0.508)
				(type default)
			)
			(layer "F.SilkS")
		)
		(fp_rect
			(start -0.9652 1.778)
			(end 0.9652 -1.778)
			(stroke
				(width 0)
				(type default)
			)
			(fill no)
			(layer "F.CrtYd")
		)
		(fp_poly
			(pts
				(xy -0.9652 -1.778) (xy 0.9652 -1.778) (xy 0.9652 1.778) (xy -0.9652 1.778)
			)
			(stroke
				(width 0)
				(type default)
			)
			(fill no)
			(layer "F.Fab")
		)
		(pad "1" smd rect
			(at 0 -0.9652 90)
			(size 1.397 1.143)
			(layers "F.Cu" "F.Mask" "F.Paste")
			(net "P12V_B_2_VIN_U32")
		)
		(pad "2" smd rect
			(at 0 0.9652 90)
			(size 1.397 1.143)
			(layers "F.Cu" "F.Mask" "F.Paste")
			(net "GND")
		)
	)
	(footprint ""
		(layer "F.Cu")
		(at 364.236 -20.574 90)
		(property "Reference" "C441"
			(at 0 0 90)
			(layer "F.SilkS")
			(hide yes)
			(effects
				(font
					(size 1.27 1.27)
				)
			)
		)
		(property "Value" "SCD033U25V2KX-GP"
			(at 1.1811 -2.7051 90)
			(unlocked yes)
			(layer "F.Fab")
			(hide yes)
			(effects
				(font
					(size 1.016 1.016)
					(thickness 0.1524)
				)
			)
		)
		(property "Device Type" "C402H22"
			(at 1.1811 -4.2291 90)
			(unlocked yes)
			(layer "F.Fab")
			(hide yes)
			(effects
				(font
					(size 1.016 1.016)
					(thickness 0.1524)
				)
			)
		)
		(duplicate_pad_numbers_are_jumpers no)
		(fp_rect
			(start -0.4318 0.9525)
			(end 0.4318 -0.9525)
			(stroke
				(width 0)
				(type default)
			)
			(fill no)
			(layer "F.CrtYd")
		)
		(fp_rect
			(start -0.4318 0.9525)
			(end 0.4318 -0.9525)
			(stroke
				(width 0)
				(type default)
			)
			(fill no)
			(layer "F.Fab")
		)
		(pad "1" smd custom
			(at 0 -0.4445 90)
			(size 0.1524 0.1524)
			(layers "F.Cu" "F.Mask" "F.Paste")
			(net "SW_HDD_P31")
			(options
				(clearance outline)
				(anchor circle)
			)
			(primitives
				(gr_poly
					(pts
						(arc
							(start 0.3048 -0.2032)
							(mid 0.275042 -0.275042)
							(end 0.2032 -0.3048)
						)
						(arc
							(start -0.2032 -0.3048)
							(mid -0.275042 -0.275042)
							(end -0.3048 -0.2032)
						)
						(arc
							(start -0.3048 0.2032)
							(mid -0.275042 0.275042)
							(end -0.2032 0.3048)
						)
						(arc
							(start 0.2032 0.3048)
							(mid 0.275042 0.275042)
							(end 0.3048 0.2032)
						)
					)
					(width 0)
					(fill yes)
				)
			)
		)
		(pad "2" smd custom
			(at 0 0.4445 90)
			(size 0.1524 0.1524)
			(layers "F.Cu" "F.Mask" "F.Paste")
			(net "GND")
			(options
				(clearance outline)
				(anchor circle)
			)
			(primitives
				(gr_poly
					(pts
						(arc
							(start 0.3048 -0.2032)
							(mid 0.275042 -0.275042)
							(end 0.2032 -0.3048)
						)
						(arc
							(start -0.2032 -0.3048)
							(mid -0.275042 -0.275042)
							(end -0.3048 -0.2032)
						)
						(arc
							(start -0.3048 0.2032)
							(mid -0.275042 0.275042)
							(end -0.2032 0.3048)
						)
						(arc
							(start 0.2032 0.3048)
							(mid 0.275042 0.275042)
							(end 0.3048 0.2032)
						)
					)
					(width 0)
					(fill yes)
				)
			)
		)
	)
	(footprint ""
		(layer "F.Cu")
		(at 334.7466 -16.3576 180)
		(property "Reference" "D30"
			(at 0 0 180)
			(layer "F.SilkS")
			(hide yes)
			(effects
				(font
					(size 1.27 1.27)
				)
			)
		)
		(property "Value" "RB551V30-GP"
			(at 0 -6.7818 180)
			(unlocked yes)
			(layer "F.Fab")
			(hide yes)
			(effects
				(font
					(size 1.016 1.016)
					(thickness 0.1524)
				)
			)
		)
		(property "Device Type" "SOD323AKH38"
			(at 0 -8.6868 180)
			(unlocked yes)
			(layer "F.Fab")
			(hide yes)
			(effects
				(font
					(size 1.016 1.016)
					(thickness 0.1524)
				)
			)
		)
		(duplicate_pad_numbers_are_jumpers no)
		(fp_line
			(start 0.889 2.159)
			(end -0.889 2.159)
			(stroke
				(width 0.1524)
				(type default)
			)
			(layer "F.SilkS")
		)
		(fp_line
			(start 0.889 -1.9304)
			(end 0.889 2.159)
			(stroke
				(width 0.1524)
				(type default)
			)
			(layer "F.SilkS")
		)
		(fp_line
			(start 0.762 2.0574)
			(end -0.762 2.0574)
			(stroke
				(width 0.508)
				(type default)
			)
			(layer "F.SilkS")
		)
		(fp_line
			(start -0.889 2.159)
			(end -0.889 -1.9304)
			(stroke
				(width 0.1524)
				(type default)
			)
			(layer "F.SilkS")
		)
		(fp_line
			(start -0.889 -1.9304)
			(end 0.889 -1.9304)
			(stroke
				(width 0.1524)
				(type default)
			)
			(layer "F.SilkS")
		)
		(fp_rect
			(start -1.016 2.3114)
			(end 1.016 -2.0066)
			(stroke
				(width 0)
				(type default)
			)
			(fill no)
			(layer "F.CrtYd")
		)
		(fp_poly
			(pts
				(xy -1.016 -2.0066) (xy 1.016 -2.0066) (xy 1.016 2.3114) (xy -1.016 2.3114)
			)
			(stroke
				(width 0)
				(type default)
			)
			(fill no)
			(layer "F.Fab")
		)
		(pad "A" smd rect
			(at 0 -1.143 180)
			(size 0.5588 1.016)
			(layers "F.Cu" "F.Mask" "F.Paste")
			(net "SW_HDD_R30")
		)
		(pad "K" smd rect
			(at 0 1.143 180)
			(size 0.5588 1.016)
			(layers "F.Cu" "F.Mask" "F.Paste")
			(net "SW_HDD_N30")
		)
	)
	(footprint ""
		(layer "F.Cu")
		(at 301.371 -228.473 -90)
		(property "Reference" "R4"
			(at 0 0 270)
			(layer "F.SilkS")
			(hide yes)
			(effects
				(font
					(size 1.27 1.27)
				)
			)
		)
		(property "Value" "10KR2F-2-GP"
			(at 0.064008 -3.993896 270)
			(unlocked yes)
			(layer "F.Fab")
			(hide yes)
			(effects
				(font
					(size 1.016 1.016)
					(thickness 0.1524)
				)
			)
		)
		(property "Device Type" "R402H16"
			(at 0.064008 -5.517896 270)
			(unlocked yes)
			(layer "F.Fab")
			(hide yes)
			(effects
				(font
					(size 1.016 1.016)
					(thickness 0.1524)
				)
			)
		)
		(duplicate_pad_numbers_are_jumpers no)
		(fp_line
			(start -0.508 -0.9398)
			(end -0.508 0.9398)
			(stroke
				(width 0.1524)
				(type default)
			)
			(layer "F.SilkS")
		)
		(fp_line
			(start 0.508 -0.9398)
			(end -0.508 -0.9398)
			(stroke
				(width 0.1524)
				(type default)
			)
			(layer "F.SilkS")
		)
		(fp_rect
			(start -0.508 0.9398)
			(end 0.508 -0.9398)
			(stroke
				(width 0)
				(type default)
			)
			(fill no)
			(layer "F.CrtYd")
		)
		(fp_rect
			(start -0.508 0.9398)
			(end 0.508 -0.9398)
			(stroke
				(width 0)
				(type default)
			)
			(fill no)
			(layer "F.Fab")
		)
		(pad "1" smd custom
			(at 0 -0.4445 270)
			(size 0.1397 0.1397)
			(layers "F.Cu" "F.Mask" "F.Paste")
			(net "P3V3_STBY_B")
			(options
				(clearance outline)
				(anchor circle)
			)
			(primitives
				(gr_poly
					(pts
						(arc
							(start -0.1778 -0.2794)
							(mid -0.249642 -0.249642)
							(end -0.2794 -0.1778)
						)
						(arc
							(start -0.2794 0.1778)
							(mid -0.249642 0.249642)
							(end -0.1778 0.2794)
						)
						(arc
							(start 0.1778 0.2794)
							(mid 0.249642 0.249642)
							(end 0.2794 0.1778)
						)
						(arc
							(start 0.2794 -0.1778)
							(mid 0.249642 -0.249642)
							(end 0.1778 -0.2794)
						)
					)
					(width 0)
					(fill yes)
				)
			)
		)
		(pad "2" smd custom
			(at 0 0.4445 270)
			(size 0.1397 0.1397)
			(layers "F.Cu" "F.Mask" "F.Paste")
			(net "SCC_B_TYPE_0")
			(options
				(clearance outline)
				(anchor circle)
			)
			(primitives
				(gr_poly
					(pts
						(arc
							(start -0.1778 -0.2794)
							(mid -0.249642 -0.249642)
							(end -0.2794 -0.1778)
						)
						(arc
							(start -0.2794 0.1778)
							(mid -0.249642 0.249642)
							(end -0.1778 0.2794)
						)
						(arc
							(start 0.1778 0.2794)
							(mid 0.249642 0.249642)
							(end 0.2794 0.1778)
						)
						(arc
							(start 0.2794 -0.1778)
							(mid 0.249642 -0.249642)
							(end 0.1778 -0.2794)
						)
					)
					(width 0)
					(fill yes)
				)
			)
		)
	)
	(footprint ""
		(layer "F.Cu")
		(at 431.419 -148.082)
		(property "Reference" "Q102"
			(at 0 0 0)
			(layer "F.SilkS")
			(hide yes)
			(effects
				(font
					(size 1.27 1.27)
				)
			)
		)
		(property "Value" "AO4407AL-GP"
			(at -3.707384 -1.5367 0)
			(unlocked yes)
			(layer "F.Fab")
			(hide yes)
			(effects
				(font
					(size 1.016 1.016)
					(thickness 0.1524)
				)
			)
		)
		(property "Device Type" "SOIC8H69"
			(at -3.707384 -3.0607 0)
			(unlocked yes)
			(layer "F.Fab")
			(hide yes)
			(effects
				(font
					(size 1.016 1.016)
					(thickness 0.1524)
				)
			)
		)
		(duplicate_pad_numbers_are_jumpers no)
		(fp_line
			(start -2.7432 -1.4224)
			(end -2.7432 1.4224)
			(stroke
				(width 0.1524)
				(type default)
			)
			(layer "F.SilkS")
		)
		(fp_line
			(start -2.7432 1.4224)
			(end -2.6416 1.4224)
			(stroke
				(width 0.1524)
				(type default)
			)
			(layer "F.SilkS")
		)
		(fp_line
			(start -2.7432 1.4224)
			(end 2.1336 1.4224)
			(stroke
				(width 0.1524)
				(type default)
			)
			(layer "F.SilkS")
		)
		(fp_line
			(start -2.7178 -0.508)
			(end -2.1844 -0.0508)
			(stroke
				(width 0.1524)
				(type default)
			)
			(layer "F.SilkS")
		)
		(fp_line
			(start -2.6289 3.4417)
			(end -2.6289 1.4732)
			(stroke
				(width 0.381)
				(type default)
			)
			(layer "F.SilkS")
		)
		(fp_line
			(start -2.1844 -0.0508)
			(end -2.7178 0.508)
			(stroke
				(width 0.1524)
				(type default)
			)
			(layer "F.SilkS")
		)
		(fp_line
			(start 2.1336 -1.4224)
			(end -2.7432 -1.4224)
			(stroke
				(width 0.1524)
				(type default)
			)
			(layer "F.SilkS")
		)
		(fp_line
			(start 2.1336 1.4224)
			(end 2.1336 -1.4224)
			(stroke
				(width 0.1524)
				(type default)
			)
			(layer "F.SilkS")
		)
		(fp_poly
			(pts
				(xy -2.2098 -1.4224) (xy -2.2098 1.4224) (xy 2.2098 1.4224) (xy 2.2098 -1.4224)
			)
			(stroke
				(width 0)
				(type default)
			)
			(fill yes)
			(layer "F.SilkS")
		)
		(fp_rect
			(start -2.450084 2.999994)
			(end 2.450084 -2.999994)
			(stroke
				(width 0)
				(type default)
			)
			(fill no)
			(layer "F.CrtYd")
		)
		(fp_poly
			(pts
				(xy -2.8194 3.6322) (xy -2.8194 -3.6322) (xy 2.8194 -3.6322) (xy 2.8194 1.18364) (xy 2.450084 1.18364)
				(xy 2.450084 -2.999994) (xy -2.450084 -2.999994) (xy -2.450084 2.999994) (xy 2.450084 2.999994)
				(xy 2.450084 1.18618) (xy 2.8194 1.18618) (xy 2.8194 3.6322)
			)
			(stroke
				(width 0)
				(type default)
			)
			(fill no)
			(layer "F.CrtYd")
		)
		(fp_rect
			(start -2.8194 3.6322)
			(end 2.8194 -3.6322)
			(stroke
				(width 0)
				(type default)
			)
			(fill no)
			(layer "F.Fab")
		)
		(pad "1" smd rect
			(at -1.905 2.54)
			(size 0.635 1.651)
			(layers "F.Cu" "F.Mask" "F.Paste")
			(net "P12V_B")
		)
		(pad "2" smd rect
			(at -0.635 2.54)
			(size 0.635 1.651)
			(layers "F.Cu" "F.Mask" "F.Paste")
			(net "P12V_B")
		)
		(pad "3" smd rect
			(at 0.635 2.54)
			(size 0.635 1.651)
			(layers "F.Cu" "F.Mask" "F.Paste")
			(net "P12V_B")
		)
		(pad "4" smd rect
			(at 1.905 2.54)
			(size 0.635 1.651)
			(layers "F.Cu" "F.Mask" "F.Paste")
			(net "SW_HDD_N21")
		)
		(pad "5" smd rect
			(at 1.905 -2.54)
			(size 0.635 1.651)
			(layers "F.Cu" "F.Mask" "F.Paste")
			(net "P12V_HDD21")
		)
		(pad "6" smd rect
			(at 0.635 -2.54)
			(size 0.635 1.651)
			(layers "F.Cu" "F.Mask" "F.Paste")
			(net "P12V_HDD21")
		)
		(pad "7" smd rect
			(at -0.635 -2.54)
			(size 0.635 1.651)
			(layers "F.Cu" "F.Mask" "F.Paste")
			(net "P12V_HDD21")
		)
		(pad "8" smd rect
			(at -1.905 -2.54)
			(size 0.635 1.651)
			(layers "F.Cu" "F.Mask" "F.Paste")
			(net "P12V_HDD21")
		)
	)
	(footprint ""
		(layer "F.Cu")
		(at 234.38104 -233.01198)
		(property "Reference" "R64"
			(at 0 0 0)
			(layer "F.SilkS")
			(hide yes)
			(effects
				(font
					(size 1.27 1.27)
				)
			)
		)
		(property "Value" "4K7R2F-GP"
			(at 0.064008 -3.993896 0)
			(unlocked yes)
			(layer "F.Fab")
			(hide yes)
			(effects
				(font
					(size 1.016 1.016)
					(thickness 0.1524)
				)
			)
		)
		(property "Device Type" "R402H16"
			(at 0.064008 -5.517896 0)
			(unlocked yes)
			(layer "F.Fab")
			(hide yes)
			(effects
				(font
					(size 1.016 1.016)
					(thickness 0.1524)
				)
			)
		)
		(duplicate_pad_numbers_are_jumpers no)
		(fp_line
			(start -0.508 -0.9398)
			(end -0.508 0.9398)
			(stroke
				(width 0.1524)
				(type default)
			)
			(layer "F.SilkS")
		)
		(fp_line
			(start 0.508 -0.9398)
			(end -0.508 -0.9398)
			(stroke
				(width 0.1524)
				(type default)
			)
			(layer "F.SilkS")
		)
		(fp_rect
			(start -0.508 0.9398)
			(end 0.508 -0.9398)
			(stroke
				(width 0)
				(type default)
			)
			(fill no)
			(layer "F.CrtYd")
		)
		(fp_rect
			(start -0.508 0.9398)
			(end 0.508 -0.9398)
			(stroke
				(width 0)
				(type default)
			)
			(fill no)
			(layer "F.Fab")
		)
		(pad "1" smd custom
			(at 0 -0.4445)
			(size 0.1397 0.1397)
			(layers "F.Cu" "F.Mask" "F.Paste")
			(net "P3V3_STBY_B")
			(options
				(clearance outline)
				(anchor circle)
			)
			(primitives
				(gr_poly
					(pts
						(arc
							(start -0.1778 -0.2794)
							(mid -0.249642 -0.249642)
							(end -0.2794 -0.1778)
						)
						(arc
							(start -0.2794 0.1778)
							(mid -0.249642 0.249642)
							(end -0.1778 0.2794)
						)
						(arc
							(start 0.1778 0.2794)
							(mid 0.249642 0.249642)
							(end 0.2794 0.1778)
						)
						(arc
							(start 0.2794 -0.1778)
							(mid 0.249642 -0.249642)
							(end 0.1778 -0.2794)
						)
					)
					(width 0)
					(fill yes)
				)
			)
		)
		(pad "2" smd custom
			(at 0 0.4445)
			(size 0.1397 0.1397)
			(layers "F.Cu" "F.Mask" "F.Paste")
			(net "IO_EXP1_A1")
			(options
				(clearance outline)
				(anchor circle)
			)
			(primitives
				(gr_poly
					(pts
						(arc
							(start -0.1778 -0.2794)
							(mid -0.249642 -0.249642)
							(end -0.2794 -0.1778)
						)
						(arc
							(start -0.2794 0.1778)
							(mid -0.249642 0.249642)
							(end -0.1778 0.2794)
						)
						(arc
							(start 0.1778 0.2794)
							(mid 0.249642 0.249642)
							(end 0.2794 0.1778)
						)
						(arc
							(start 0.2794 -0.1778)
							(mid 0.249642 -0.249642)
							(end 0.1778 -0.2794)
						)
					)
					(width 0)
					(fill yes)
				)
			)
		)
	)
	(footprint ""
		(layer "F.Cu")
		(at 384.734562 -15.219426 -90)
		(property "Reference" "C444"
			(at 0 0 270)
			(layer "F.SilkS")
			(hide yes)
			(effects
				(font
					(size 1.27 1.27)
				)
			)
		)
		(property "Value" "SCD01U16V1KX-GP"
			(at -2.8321 -1.7399 270)
			(unlocked yes)
			(layer "F.Fab")
			(hide yes)
			(effects
				(font
					(size 1.016 1.016)
					(thickness 0.1524)
				)
			)
		)
		(property "Device Type" "C0201H13"
			(at -2.8321 -3.2639 270)
			(unlocked yes)
			(layer "F.Fab")
			(hide yes)
			(effects
				(font
					(size 1.016 1.016)
					(thickness 0.1524)
				)
			)
		)
		(duplicate_pad_numbers_are_jumpers no)
		(fp_rect
			(start -0.2794 0.6477)
			(end 0.2794 -0.6477)
			(stroke
				(width 0)
				(type default)
			)
			(fill no)
			(layer "F.CrtYd")
		)
		(fp_rect
			(start -0.2794 0.6477)
			(end 0.2794 -0.6477)
			(stroke
				(width 0)
				(type default)
			)
			(fill no)
			(layer "F.Fab")
		)
		(pad "1" smd custom
			(at 0 -0.2794 270)
			(size 0.0762 0.0762)
			(layers "F.Cu" "F.Mask" "F.Paste")
			(net "SAS_HDD_RX_N32")
			(options
				(clearance outline)
				(anchor circle)
			)
			(primitives
				(gr_poly
					(pts
						(arc
							(start 0.1524 -0.127)
							(mid 0.137521 -0.162921)
							(end 0.1016 -0.1778)
						)
						(arc
							(start -0.1016 -0.1778)
							(mid -0.137521 -0.162921)
							(end -0.1524 -0.127)
						)
						(arc
							(start -0.1524 0.127)
							(mid -0.137521 0.162921)
							(end -0.1016 0.1778)
						)
						(arc
							(start 0.1016 0.1778)
							(mid 0.137521 0.162921)
							(end 0.1524 0.127)
						)
					)
					(width 0)
					(fill yes)
				)
			)
		)
		(pad "2" smd custom
			(at 0 0.2794 270)
			(size 0.0762 0.0762)
			(layers "F.Cu" "F.Mask" "F.Paste")
			(net "PHY_SCC_B_TO_DRV_B_32_DN")
			(options
				(clearance outline)
				(anchor circle)
			)
			(primitives
				(gr_poly
					(pts
						(arc
							(start 0.1524 -0.127)
							(mid 0.137521 -0.162921)
							(end 0.1016 -0.1778)
						)
						(arc
							(start -0.1016 -0.1778)
							(mid -0.137521 -0.162921)
							(end -0.1524 -0.127)
						)
						(arc
							(start -0.1524 0.127)
							(mid -0.137521 0.162921)
							(end -0.1016 0.1778)
						)
						(arc
							(start 0.1016 0.1778)
							(mid 0.137521 0.162921)
							(end 0.1524 0.127)
						)
					)
					(width 0)
					(fill yes)
				)
			)
		)
	)
	(footprint ""
		(layer "F.Cu")
		(at 463.042 -131.826 180)
		(property "Reference" "R590"
			(at 0 0 180)
			(layer "F.SilkS")
			(hide yes)
			(effects
				(font
					(size 1.27 1.27)
				)
			)
		)
		(property "Value" "4K7R2J-2-GP"
			(at 0.064008 -3.993896 180)
			(unlocked yes)
			(layer "F.Fab")
			(hide yes)
			(effects
				(font
					(size 1.016 1.016)
					(thickness 0.1524)
				)
			)
		)
		(property "Device Type" "R402H16"
			(at 0.064008 -5.517896 180)
			(unlocked yes)
			(layer "F.Fab")
			(hide yes)
			(effects
				(font
					(size 1.016 1.016)
					(thickness 0.1524)
				)
			)
		)
		(duplicate_pad_numbers_are_jumpers no)
		(fp_line
			(start 0.508 -0.9398)
			(end -0.508 -0.9398)
			(stroke
				(width 0.1524)
				(type default)
			)
			(layer "F.SilkS")
		)
		(fp_line
			(start -0.508 -0.9398)
			(end -0.508 0.9398)
			(stroke
				(width 0.1524)
				(type default)
			)
			(layer "F.SilkS")
		)
		(fp_rect
			(start -0.508 0.9398)
			(end 0.508 -0.9398)
			(stroke
				(width 0)
				(type default)
			)
			(fill no)
			(layer "F.CrtYd")
		)
		(fp_rect
			(start -0.508 0.9398)
			(end 0.508 -0.9398)
			(stroke
				(width 0)
				(type default)
			)
			(fill no)
			(layer "F.Fab")
		)
		(pad "1" smd custom
			(at 0 -0.4445 180)
			(size 0.1397 0.1397)
			(layers "F.Cu" "F.Mask" "F.Paste")
			(net "P12V_B")
			(options
				(clearance outline)
				(anchor circle)
			)
			(primitives
				(gr_poly
					(pts
						(arc
							(start -0.1778 -0.2794)
							(mid -0.249642 -0.249642)
							(end -0.2794 -0.1778)
						)
						(arc
							(start -0.2794 0.1778)
							(mid -0.249642 0.249642)
							(end -0.1778 0.2794)
						)
						(arc
							(start 0.1778 0.2794)
							(mid 0.249642 0.249642)
							(end 0.2794 0.1778)
						)
						(arc
							(start 0.2794 -0.1778)
							(mid 0.249642 -0.249642)
							(end 0.1778 -0.2794)
						)
					)
					(width 0)
					(fill yes)
				)
			)
		)
		(pad "2" smd custom
			(at 0 0.4445 180)
			(size 0.1397 0.1397)
			(layers "F.Cu" "F.Mask" "F.Paste")
			(net "SW_HDD_R22")
			(options
				(clearance outline)
				(anchor circle)
			)
			(primitives
				(gr_poly
					(pts
						(arc
							(start -0.1778 -0.2794)
							(mid -0.249642 -0.249642)
							(end -0.2794 -0.1778)
						)
						(arc
							(start -0.2794 0.1778)
							(mid -0.249642 0.249642)
							(end -0.1778 0.2794)
						)
						(arc
							(start 0.1778 0.2794)
							(mid 0.249642 0.249642)
							(end 0.2794 0.1778)
						)
						(arc
							(start 0.2794 -0.1778)
							(mid 0.249642 -0.249642)
							(end 0.1778 -0.2794)
						)
					)
					(width 0)
					(fill yes)
				)
			)
		)
	)
	(footprint ""
		(layer "F.Cu")
		(at 22.32533 -229.963218 90)
		(property "Reference" "R1108"
			(at 0 0 90)
			(layer "F.SilkS")
			(hide yes)
			(effects
				(font
					(size 1.27 1.27)
				)
			)
		)
		(property "Value" "100KR2F-L1-GP"
			(at 0.064008 -3.993896 90)
			(unlocked yes)
			(layer "F.Fab")
			(hide yes)
			(effects
				(font
					(size 1.016 1.016)
					(thickness 0.1524)
				)
			)
		)
		(property "Device Type" "R402H16"
			(at 0.064008 -5.517896 90)
			(unlocked yes)
			(layer "F.Fab")
			(hide yes)
			(effects
				(font
					(size 1.016 1.016)
					(thickness 0.1524)
				)
			)
		)
		(duplicate_pad_numbers_are_jumpers no)
		(fp_line
			(start 0.508 -0.9398)
			(end -0.508 -0.9398)
			(stroke
				(width 0.1524)
				(type default)
			)
			(layer "F.SilkS")
		)
		(fp_line
			(start -0.508 -0.9398)
			(end -0.508 0.9398)
			(stroke
				(width 0.1524)
				(type default)
			)
			(layer "F.SilkS")
		)
		(fp_rect
			(start -0.508 0.9398)
			(end 0.508 -0.9398)
			(stroke
				(width 0)
				(type default)
			)
			(fill no)
			(layer "F.CrtYd")
		)
		(fp_rect
			(start -0.508 0.9398)
			(end 0.508 -0.9398)
			(stroke
				(width 0)
				(type default)
			)
			(fill no)
			(layer "F.Fab")
		)
		(pad "1" smd custom
			(at 0 -0.4445 90)
			(size 0.1397 0.1397)
			(layers "F.Cu" "F.Mask" "F.Paste")
			(net "AGND_P5V_B_1")
			(options
				(clearance outline)
				(anchor circle)
			)
			(primitives
				(gr_poly
					(pts
						(arc
							(start -0.1778 -0.2794)
							(mid -0.249642 -0.249642)
							(end -0.2794 -0.1778)
						)
						(arc
							(start -0.2794 0.1778)
							(mid -0.249642 0.249642)
							(end -0.1778 0.2794)
						)
						(arc
							(start 0.1778 0.2794)
							(mid 0.249642 0.249642)
							(end 0.2794 0.1778)
						)
						(arc
							(start 0.2794 -0.1778)
							(mid 0.249642 -0.249642)
							(end 0.1778 -0.2794)
						)
					)
					(width 0)
					(fill yes)
				)
			)
		)
		(pad "2" smd custom
			(at 0 0.4445 90)
			(size 0.1397 0.1397)
			(layers "F.Cu" "F.Mask" "F.Paste")
			(net "P5V_B_1_MODE")
			(options
				(clearance outline)
				(anchor circle)
			)
			(primitives
				(gr_poly
					(pts
						(arc
							(start -0.1778 -0.2794)
							(mid -0.249642 -0.249642)
							(end -0.2794 -0.1778)
						)
						(arc
							(start -0.2794 0.1778)
							(mid -0.249642 0.249642)
							(end -0.1778 0.2794)
						)
						(arc
							(start 0.1778 0.2794)
							(mid 0.249642 0.249642)
							(end 0.2794 0.1778)
						)
						(arc
							(start 0.2794 -0.1778)
							(mid 0.249642 -0.249642)
							(end 0.1778 -0.2794)
						)
					)
					(width 0)
					(fill yes)
				)
			)
		)
	)
	(footprint ""
		(layer "F.Cu")
		(at 32.352996 -376.9868 90)
		(property "Reference" "R1297"
			(at 0 0 90)
			(layer "F.SilkS")
			(hide yes)
			(effects
				(font
					(size 1.27 1.27)
				)
			)
		)
		(property "Value" "4K7R2F-GP"
			(at 0.064008 -3.993896 90)
			(unlocked yes)
			(layer "F.Fab")
			(hide yes)
			(effects
				(font
					(size 1.016 1.016)
					(thickness 0.1524)
				)
			)
		)
		(property "Device Type" "R402H16"
			(at 0.064008 -5.517896 90)
			(unlocked yes)
			(layer "F.Fab")
			(hide yes)
			(effects
				(font
					(size 1.016 1.016)
					(thickness 0.1524)
				)
			)
		)
		(duplicate_pad_numbers_are_jumpers no)
		(fp_line
			(start 0.508 -0.9398)
			(end -0.508 -0.9398)
			(stroke
				(width 0.1524)
				(type default)
			)
			(layer "F.SilkS")
		)
		(fp_line
			(start -0.508 -0.9398)
			(end -0.508 0.9398)
			(stroke
				(width 0.1524)
				(type default)
			)
			(layer "F.SilkS")
		)
		(fp_rect
			(start -0.508 0.9398)
			(end 0.508 -0.9398)
			(stroke
				(width 0)
				(type default)
			)
			(fill no)
			(layer "F.CrtYd")
		)
		(fp_rect
			(start -0.508 0.9398)
			(end 0.508 -0.9398)
			(stroke
				(width 0)
				(type default)
			)
			(fill no)
			(layer "F.Fab")
		)
		(pad "1" smd custom
			(at 0 -0.4445 90)
			(size 0.1397 0.1397)
			(layers "F.Cu" "F.Mask" "F.Paste")
			(net "FAN_YELLOW_LED0")
			(options
				(clearance outline)
				(anchor circle)
			)
			(primitives
				(gr_poly
					(pts
						(arc
							(start -0.1778 -0.2794)
							(mid -0.249642 -0.249642)
							(end -0.2794 -0.1778)
						)
						(arc
							(start -0.2794 0.1778)
							(mid -0.249642 0.249642)
							(end -0.1778 0.2794)
						)
						(arc
							(start 0.1778 0.2794)
							(mid 0.249642 0.249642)
							(end 0.2794 0.1778)
						)
						(arc
							(start 0.2794 -0.1778)
							(mid 0.249642 -0.249642)
							(end 0.1778 -0.2794)
						)
					)
					(width 0)
					(fill yes)
				)
			)
		)
		(pad "2" smd custom
			(at 0 0.4445 90)
			(size 0.1397 0.1397)
			(layers "F.Cu" "F.Mask" "F.Paste")
			(net "P12V_IN")
			(options
				(clearance outline)
				(anchor circle)
			)
			(primitives
				(gr_poly
					(pts
						(arc
							(start -0.1778 -0.2794)
							(mid -0.249642 -0.249642)
							(end -0.2794 -0.1778)
						)
						(arc
							(start -0.2794 0.1778)
							(mid -0.249642 0.249642)
							(end -0.1778 0.2794)
						)
						(arc
							(start 0.1778 0.2794)
							(mid 0.249642 0.249642)
							(end 0.2794 0.1778)
						)
						(arc
							(start 0.2794 -0.1778)
							(mid 0.249642 -0.249642)
							(end 0.1778 -0.2794)
						)
					)
					(width 0)
					(fill yes)
				)
			)
		)
	)
	(footprint ""
		(layer "F.Cu")
		(at 242.63858 -221.52102)
		(property "Reference" "U10"
			(at 0 0 0)
			(layer "F.SilkS")
			(hide yes)
			(effects
				(font
					(size 1.27 1.27)
				)
			)
		)
		(property "Value" "PCA9557PWR-1-GP-U"
			(at 0.127 -12.573 0)
			(unlocked yes)
			(layer "F.Fab")
			(hide yes)
			(effects
				(font
					(size 1.016 1.016)
					(thickness 0.1524)
				)
			)
		)
		(property "Device Type" "TSOIC16H48"
			(at 0.1016 -14.5796 0)
			(unlocked yes)
			(layer "F.Fab")
			(hide yes)
			(effects
				(font
					(size 1.016 1.016)
					(thickness 0.1524)
				)
			)
		)
		(duplicate_pad_numbers_are_jumpers no)
		(fp_line
			(start -3.0988 -1.778)
			(end -3.0988 1.778)
			(stroke
				(width 0.1524)
				(type default)
			)
			(layer "F.SilkS")
		)
		(fp_line
			(start -3.0988 -1.778)
			(end 2.3622 -1.778)
			(stroke
				(width 0.1524)
				(type default)
			)
			(layer "F.SilkS")
		)
		(fp_line
			(start -2.921 3.81)
			(end -2.921 1.778)
			(stroke
				(width 0.508)
				(type default)
			)
			(layer "F.SilkS")
		)
		(fp_line
			(start -2.54 0)
			(end -3.0988 -0.5588)
			(stroke
				(width 0.1524)
				(type default)
			)
			(layer "F.SilkS")
		)
		(fp_line
			(start -2.54 0)
			(end -3.0988 0.5588)
			(stroke
				(width 0.1524)
				(type default)
			)
			(layer "F.SilkS")
		)
		(fp_line
			(start 2.3622 -1.778)
			(end 2.3622 1.778)
			(stroke
				(width 0.1524)
				(type default)
			)
			(layer "F.SilkS")
		)
		(fp_line
			(start 2.3622 1.778)
			(end -2.921 1.778)
			(stroke
				(width 0.1524)
				(type default)
			)
			(layer "F.SilkS")
		)
		(fp_poly
			(pts
				(xy -2.4638 -1.778) (xy -2.4638 1.778) (xy 2.3622 1.778) (xy 2.3622 -1.778)
			)
			(stroke
				(width 0)
				(type default)
			)
			(fill yes)
			(layer "F.SilkS")
		)
		(fp_rect
			(start -3.175 4.064)
			(end 3.175 -4.064)
			(stroke
				(width 0)
				(type default)
			)
			(fill no)
			(layer "F.CrtYd")
		)
		(fp_poly
			(pts
				(xy -3.175 -4.064) (xy 3.175 -4.064) (xy 3.175 4.064) (xy -3.175 4.064)
			)
			(stroke
				(width 0)
				(type default)
			)
			(fill no)
			(layer "F.Fab")
		)
		(pad "1" smd rect
			(at -2.27584 2.8194)
			(size 0.3556 1.524)
			(layers "F.Cu" "F.Mask" "F.Paste")
			(net "IO_EXP3_SCL")
		)
		(pad "2" smd rect
			(at -1.6256 2.8194)
			(size 0.3556 1.524)
			(layers "F.Cu" "F.Mask" "F.Paste")
			(net "IO_EXP3_SDA")
		)
		(pad "3" smd rect
			(at -0.97536 2.8194)
			(size 0.3556 1.524)
			(layers "F.Cu" "F.Mask" "F.Paste")
			(net "IO_EXP3_A0")
		)
		(pad "4" smd rect
			(at -0.32512 2.8194)
			(size 0.3556 1.524)
			(layers "F.Cu" "F.Mask" "F.Paste")
			(net "IO_EXP3_A1")
		)
		(pad "5" smd rect
			(at 0.32512 2.8194)
			(size 0.3556 1.524)
			(layers "F.Cu" "F.Mask" "F.Paste")
			(net "IO_EXP3_A2")
		)
		(pad "6" smd rect
			(at 0.97536 2.8194)
			(size 0.3556 1.524)
			(layers "F.Cu" "F.Mask" "F.Paste")
			(net "Net_5")
		)
		(pad "7" smd rect
			(at 1.6256 2.8194)
			(size 0.3556 1.524)
			(layers "F.Cu" "F.Mask" "F.Paste")
			(net "DRIVE_B_32_PWR")
		)
		(pad "8" smd rect
			(at 2.27584 2.8194)
			(size 0.3556 1.524)
			(layers "F.Cu" "F.Mask" "F.Paste")
			(net "GND")
		)
		(pad "9" smd rect
			(at 2.27584 -2.8194)
			(size 0.3556 1.524)
			(layers "F.Cu" "F.Mask" "F.Paste")
			(net "DRIVE_B_33_PWR")
		)
		(pad "10" smd rect
			(at 1.6256 -2.8194)
			(size 0.3556 1.524)
			(layers "F.Cu" "F.Mask" "F.Paste")
			(net "DRIVE_B_34_PWR")
		)
		(pad "11" smd rect
			(at 0.97536 -2.8194)
			(size 0.3556 1.524)
			(layers "F.Cu" "F.Mask" "F.Paste")
			(net "DRIVE_B_35_PWR")
		)
		(pad "12" smd rect
			(at 0.32512 -2.8194)
			(size 0.3556 1.524)
			(layers "F.Cu" "F.Mask" "F.Paste")
			(net "Net_984")
		)
		(pad "13" smd rect
			(at -0.32512 -2.8194)
			(size 0.3556 1.524)
			(layers "F.Cu" "F.Mask" "F.Paste")
			(net "Net_207")
		)
		(pad "14" smd rect
			(at -0.97536 -2.8194)
			(size 0.3556 1.524)
			(layers "F.Cu" "F.Mask" "F.Paste")
			(net "Net_202")
		)
		(pad "15" smd rect
			(at -1.6256 -2.8194)
			(size 0.3556 1.524)
			(layers "F.Cu" "F.Mask" "F.Paste")
			(net "IO_EXP3_RESET#")
		)
		(pad "16" smd rect
			(at -2.27584 -2.8194)
			(size 0.3556 1.524)
			(layers "F.Cu" "F.Mask" "F.Paste")
			(net "GPIO_VCC_U10")
		)
	)
	(footprint ""
		(layer "F.Cu")
		(at 37.1602 -6.4008 -90)
		(property "Reference" "C27"
			(at 0 0 270)
			(layer "F.SilkS")
			(hide yes)
			(effects
				(font
					(size 1.27 1.27)
				)
			)
		)
		(property "Value" "SCD1U16V2KX-3GP"
			(at 1.1811 -2.7051 270)
			(unlocked yes)
			(layer "F.Fab")
			(hide yes)
			(effects
				(font
					(size 1.016 1.016)
					(thickness 0.1524)
				)
			)
		)
		(property "Device Type" "C402H22"
			(at 1.1811 -4.2291 270)
			(unlocked yes)
			(layer "F.Fab")
			(hide yes)
			(effects
				(font
					(size 1.016 1.016)
					(thickness 0.1524)
				)
			)
		)
		(duplicate_pad_numbers_are_jumpers no)
		(fp_rect
			(start -0.4318 0.9525)
			(end 0.4318 -0.9525)
			(stroke
				(width 0)
				(type default)
			)
			(fill no)
			(layer "F.CrtYd")
		)
		(fp_rect
			(start -0.4318 0.9525)
			(end 0.4318 -0.9525)
			(stroke
				(width 0)
				(type default)
			)
			(fill no)
			(layer "F.Fab")
		)
		(pad "1" smd custom
			(at 0 -0.4445 270)
			(size 0.1524 0.1524)
			(layers "F.Cu" "F.Mask" "F.Paste")
			(net "GND")
			(options
				(clearance outline)
				(anchor circle)
			)
			(primitives
				(gr_poly
					(pts
						(arc
							(start 0.3048 -0.2032)
							(mid 0.275042 -0.275042)
							(end 0.2032 -0.3048)
						)
						(arc
							(start -0.2032 -0.3048)
							(mid -0.275042 -0.275042)
							(end -0.3048 -0.2032)
						)
						(arc
							(start -0.3048 0.2032)
							(mid -0.275042 0.275042)
							(end -0.2032 0.3048)
						)
						(arc
							(start 0.2032 0.3048)
							(mid 0.275042 0.275042)
							(end 0.3048 0.2032)
						)
					)
					(width 0)
					(fill yes)
				)
			)
		)
		(pad "2" smd custom
			(at 0 0.4445 270)
			(size 0.1524 0.1524)
			(layers "F.Cu" "F.Mask" "F.Paste")
			(net "P3V3_STBY_A")
			(options
				(clearance outline)
				(anchor circle)
			)
			(primitives
				(gr_poly
					(pts
						(arc
							(start 0.3048 -0.2032)
							(mid 0.275042 -0.275042)
							(end 0.2032 -0.3048)
						)
						(arc
							(start -0.2032 -0.3048)
							(mid -0.275042 -0.275042)
							(end -0.3048 -0.2032)
						)
						(arc
							(start -0.3048 0.2032)
							(mid -0.275042 0.275042)
							(end -0.2032 0.3048)
						)
						(arc
							(start 0.2032 0.3048)
							(mid 0.275042 0.275042)
							(end 0.3048 0.2032)
						)
					)
					(width 0)
					(fill yes)
				)
			)
		)
	)
	(footprint ""
		(layer "F.Cu")
		(at 190.5 -33.147 -90)
		(property "Reference" "R737"
			(at 0 0 270)
			(layer "F.SilkS")
			(hide yes)
			(effects
				(font
					(size 1.27 1.27)
				)
			)
		)
		(property "Value" "10KR2F-2-GP"
			(at 0.064008 -3.993896 270)
			(unlocked yes)
			(layer "F.Fab")
			(hide yes)
			(effects
				(font
					(size 1.016 1.016)
					(thickness 0.1524)
				)
			)
		)
		(property "Device Type" "R402H16"
			(at 0.064008 -5.517896 270)
			(unlocked yes)
			(layer "F.Fab")
			(hide yes)
			(effects
				(font
					(size 1.016 1.016)
					(thickness 0.1524)
				)
			)
		)
		(duplicate_pad_numbers_are_jumpers no)
		(fp_line
			(start -0.508 -0.9398)
			(end -0.508 0.9398)
			(stroke
				(width 0.1524)
				(type default)
			)
			(layer "F.SilkS")
		)
		(fp_line
			(start 0.508 -0.9398)
			(end -0.508 -0.9398)
			(stroke
				(width 0.1524)
				(type default)
			)
			(layer "F.SilkS")
		)
		(fp_rect
			(start -0.508 0.9398)
			(end 0.508 -0.9398)
			(stroke
				(width 0)
				(type default)
			)
			(fill no)
			(layer "F.CrtYd")
		)
		(fp_rect
			(start -0.508 0.9398)
			(end 0.508 -0.9398)
			(stroke
				(width 0)
				(type default)
			)
			(fill no)
			(layer "F.Fab")
		)
		(pad "1" smd custom
			(at 0 -0.4445 270)
			(size 0.1397 0.1397)
			(layers "F.Cu" "F.Mask" "F.Paste")
			(net "P3V3_STBY_B")
			(options
				(clearance outline)
				(anchor circle)
			)
			(primitives
				(gr_poly
					(pts
						(arc
							(start -0.1778 -0.2794)
							(mid -0.249642 -0.249642)
							(end -0.2794 -0.1778)
						)
						(arc
							(start -0.2794 0.1778)
							(mid -0.249642 0.249642)
							(end -0.1778 0.2794)
						)
						(arc
							(start 0.1778 0.2794)
							(mid 0.249642 0.249642)
							(end 0.2794 0.1778)
						)
						(arc
							(start 0.2794 -0.1778)
							(mid 0.249642 -0.249642)
							(end 0.1778 -0.2794)
						)
					)
					(width 0)
					(fill yes)
				)
			)
		)
		(pad "2" smd custom
			(at 0 0.4445 270)
			(size 0.1397 0.1397)
			(layers "F.Cu" "F.Mask" "F.Paste")
			(net "HDD_PRSNT_29")
			(options
				(clearance outline)
				(anchor circle)
			)
			(primitives
				(gr_poly
					(pts
						(arc
							(start -0.1778 -0.2794)
							(mid -0.249642 -0.249642)
							(end -0.2794 -0.1778)
						)
						(arc
							(start -0.2794 0.1778)
							(mid -0.249642 0.249642)
							(end -0.1778 0.2794)
						)
						(arc
							(start 0.1778 0.2794)
							(mid 0.249642 0.249642)
							(end 0.2794 0.1778)
						)
						(arc
							(start 0.2794 -0.1778)
							(mid 0.249642 -0.249642)
							(end 0.1778 -0.2794)
						)
					)
					(width 0)
					(fill yes)
				)
			)
		)
	)
	(footprint ""
		(layer "F.Cu")
		(at 34.763964 -154.70505)
		(property "Reference" "TP81"
			(at 0 0 0)
			(layer "F.SilkS")
			(hide yes)
			(effects
				(font
					(size 1.27 1.27)
				)
			)
		)
		(property "Value" "*"
			(at -0.0508 -1.6764 0)
			(unlocked yes)
			(layer "F.Fab")
			(hide yes)
			(effects
				(font
					(size 1.016 1.016)
					(thickness 0.1524)
				)
			)
		)
		(property "Device Type" "TPAD32"
			(at -0.0508 -3.2004 0)
			(unlocked yes)
			(layer "F.Fab")
			(hide yes)
			(effects
				(font
					(size 1.016 1.016)
					(thickness 0.1524)
				)
			)
		)
		(duplicate_pad_numbers_are_jumpers no)
		(fp_poly
			(pts
				(arc
					(start 0.4064 0)
					(mid -0.4064 0)
					(end 0.4064 0)
				)
			)
			(stroke
				(width 0)
				(type default)
			)
			(fill no)
			(layer "F.CrtYd")
		)
		(fp_poly
			(pts
				(arc
					(start 0.7112 0)
					(mid -0.7112 0)
					(end 0.7112 0)
				)
			)
			(stroke
				(width 0)
				(type default)
			)
			(fill no)
			(layer "F.Fab")
		)
		(pad "1" smd circle
			(at 0 0)
			(size 0.8128 0.8128)
			(layers "F.Cu" "F.Mask" "F.Paste")
			(net "ACT_HDD_12")
		)
	)
	(footprint ""
		(layer "F.Cu")
		(at 22.987 -19.558 90)
		(property "Reference" "R635"
			(at 0 0 90)
			(layer "F.SilkS")
			(hide yes)
			(effects
				(font
					(size 1.27 1.27)
				)
			)
		)
		(property "Value" "4K7R2F-GP"
			(at 0.064008 -3.993896 90)
			(unlocked yes)
			(layer "F.Fab")
			(hide yes)
			(effects
				(font
					(size 1.016 1.016)
					(thickness 0.1524)
				)
			)
		)
		(property "Device Type" "R402H16"
			(at 0.064008 -5.517896 90)
			(unlocked yes)
			(layer "F.Fab")
			(hide yes)
			(effects
				(font
					(size 1.016 1.016)
					(thickness 0.1524)
				)
			)
		)
		(duplicate_pad_numbers_are_jumpers no)
		(fp_line
			(start 0.508 -0.9398)
			(end -0.508 -0.9398)
			(stroke
				(width 0.1524)
				(type default)
			)
			(layer "F.SilkS")
		)
		(fp_line
			(start -0.508 -0.9398)
			(end -0.508 0.9398)
			(stroke
				(width 0.1524)
				(type default)
			)
			(layer "F.SilkS")
		)
		(fp_rect
			(start -0.508 0.9398)
			(end 0.508 -0.9398)
			(stroke
				(width 0)
				(type default)
			)
			(fill no)
			(layer "F.CrtYd")
		)
		(fp_rect
			(start -0.508 0.9398)
			(end 0.508 -0.9398)
			(stroke
				(width 0)
				(type default)
			)
			(fill no)
			(layer "F.Fab")
		)
		(pad "1" smd custom
			(at 0 -0.4445 90)
			(size 0.1397 0.1397)
			(layers "F.Cu" "F.Mask" "F.Paste")
			(net "SW_PWR_R_HDD24")
			(options
				(clearance outline)
				(anchor circle)
			)
			(primitives
				(gr_poly
					(pts
						(arc
							(start -0.1778 -0.2794)
							(mid -0.249642 -0.249642)
							(end -0.2794 -0.1778)
						)
						(arc
							(start -0.2794 0.1778)
							(mid -0.249642 0.249642)
							(end -0.1778 0.2794)
						)
						(arc
							(start 0.1778 0.2794)
							(mid 0.249642 0.249642)
							(end 0.2794 0.1778)
						)
						(arc
							(start 0.2794 -0.1778)
							(mid 0.249642 -0.249642)
							(end 0.1778 -0.2794)
						)
					)
					(width 0)
					(fill yes)
				)
			)
		)
		(pad "2" smd custom
			(at 0 0.4445 90)
			(size 0.1397 0.1397)
			(layers "F.Cu" "F.Mask" "F.Paste")
			(net "GND")
			(options
				(clearance outline)
				(anchor circle)
			)
			(primitives
				(gr_poly
					(pts
						(arc
							(start -0.1778 -0.2794)
							(mid -0.249642 -0.249642)
							(end -0.2794 -0.1778)
						)
						(arc
							(start -0.2794 0.1778)
							(mid -0.249642 0.249642)
							(end -0.1778 0.2794)
						)
						(arc
							(start 0.1778 0.2794)
							(mid 0.249642 0.249642)
							(end 0.2794 0.1778)
						)
						(arc
							(start 0.2794 -0.1778)
							(mid 0.249642 -0.249642)
							(end 0.1778 -0.2794)
						)
					)
					(width 0)
					(fill yes)
				)
			)
		)
	)
	(footprint ""
		(layer "F.Cu")
		(at 256.413 -283.845 90)
		(property "Reference" "R1178"
			(at 0 0 90)
			(layer "F.SilkS")
			(hide yes)
			(effects
				(font
					(size 1.27 1.27)
				)
			)
		)
		(property "Value" "0R2J-2-GP"
			(at 0.064008 -3.993896 90)
			(unlocked yes)
			(layer "F.Fab")
			(hide yes)
			(effects
				(font
					(size 1.016 1.016)
					(thickness 0.1524)
				)
			)
		)
		(property "Device Type" "R402H16"
			(at 0.064008 -5.517896 90)
			(unlocked yes)
			(layer "F.Fab")
			(hide yes)
			(effects
				(font
					(size 1.016 1.016)
					(thickness 0.1524)
				)
			)
		)
		(duplicate_pad_numbers_are_jumpers no)
		(fp_line
			(start 0.508 -0.9398)
			(end -0.508 -0.9398)
			(stroke
				(width 0.1524)
				(type default)
			)
			(layer "F.SilkS")
		)
		(fp_line
			(start -0.508 -0.9398)
			(end -0.508 0.9398)
			(stroke
				(width 0.1524)
				(type default)
			)
			(layer "F.SilkS")
		)
		(fp_rect
			(start -0.508 0.9398)
			(end 0.508 -0.9398)
			(stroke
				(width 0)
				(type default)
			)
			(fill no)
			(layer "F.CrtYd")
		)
		(fp_rect
			(start -0.508 0.9398)
			(end 0.508 -0.9398)
			(stroke
				(width 0)
				(type default)
			)
			(fill no)
			(layer "F.Fab")
		)
		(pad "1" smd custom
			(at 0 -0.4445 90)
			(size 0.1397 0.1397)
			(layers "F.Cu" "F.Mask" "F.Paste")
			(net "P3V3_STBY_VO")
			(options
				(clearance outline)
				(anchor circle)
			)
			(primitives
				(gr_poly
					(pts
						(arc
							(start -0.1778 -0.2794)
							(mid -0.249642 -0.249642)
							(end -0.2794 -0.1778)
						)
						(arc
							(start -0.2794 0.1778)
							(mid -0.249642 0.249642)
							(end -0.1778 0.2794)
						)
						(arc
							(start 0.1778 0.2794)
							(mid 0.249642 0.249642)
							(end 0.2794 0.1778)
						)
						(arc
							(start 0.2794 -0.1778)
							(mid 0.249642 -0.249642)
							(end 0.1778 -0.2794)
						)
					)
					(width 0)
					(fill yes)
				)
			)
		)
		(pad "2" smd custom
			(at 0 0.4445 90)
			(size 0.1397 0.1397)
			(layers "F.Cu" "F.Mask" "F.Paste")
			(net "P3V3_STBY_CC_R")
			(options
				(clearance outline)
				(anchor circle)
			)
			(primitives
				(gr_poly
					(pts
						(arc
							(start -0.1778 -0.2794)
							(mid -0.249642 -0.249642)
							(end -0.2794 -0.1778)
						)
						(arc
							(start -0.2794 0.1778)
							(mid -0.249642 0.249642)
							(end -0.1778 0.2794)
						)
						(arc
							(start 0.1778 0.2794)
							(mid 0.249642 0.249642)
							(end 0.2794 0.1778)
						)
						(arc
							(start 0.2794 -0.1778)
							(mid 0.249642 -0.249642)
							(end 0.1778 -0.2794)
						)
					)
					(width 0)
					(fill yes)
				)
			)
		)
	)
	(footprint ""
		(layer "F.Cu")
		(at 109.855 -248.158 180)
		(property "Reference" "R218"
			(at 0 0 180)
			(layer "F.SilkS")
			(hide yes)
			(effects
				(font
					(size 1.27 1.27)
				)
			)
		)
		(property "Value" "200KR2F-L-GP"
			(at 0.064008 -3.993896 180)
			(unlocked yes)
			(layer "F.Fab")
			(hide yes)
			(effects
				(font
					(size 1.016 1.016)
					(thickness 0.1524)
				)
			)
		)
		(property "Device Type" "R402H16"
			(at 0.064008 -5.517896 180)
			(unlocked yes)
			(layer "F.Fab")
			(hide yes)
			(effects
				(font
					(size 1.016 1.016)
					(thickness 0.1524)
				)
			)
		)
		(duplicate_pad_numbers_are_jumpers no)
		(fp_line
			(start 0.508 -0.9398)
			(end -0.508 -0.9398)
			(stroke
				(width 0.1524)
				(type default)
			)
			(layer "F.SilkS")
		)
		(fp_line
			(start -0.508 -0.9398)
			(end -0.508 0.9398)
			(stroke
				(width 0.1524)
				(type default)
			)
			(layer "F.SilkS")
		)
		(fp_rect
			(start -0.508 0.9398)
			(end 0.508 -0.9398)
			(stroke
				(width 0)
				(type default)
			)
			(fill no)
			(layer "F.CrtYd")
		)
		(fp_rect
			(start -0.508 0.9398)
			(end 0.508 -0.9398)
			(stroke
				(width 0)
				(type default)
			)
			(fill no)
			(layer "F.Fab")
		)
		(pad "1" smd custom
			(at 0 -0.4445 180)
			(size 0.1397 0.1397)
			(layers "F.Cu" "F.Mask" "F.Paste")
			(net "SW_HDD_R3")
			(options
				(clearance outline)
				(anchor circle)
			)
			(primitives
				(gr_poly
					(pts
						(arc
							(start -0.1778 -0.2794)
							(mid -0.249642 -0.249642)
							(end -0.2794 -0.1778)
						)
						(arc
							(start -0.2794 0.1778)
							(mid -0.249642 0.249642)
							(end -0.1778 0.2794)
						)
						(arc
							(start 0.1778 0.2794)
							(mid 0.249642 0.249642)
							(end 0.2794 0.1778)
						)
						(arc
							(start 0.2794 -0.1778)
							(mid 0.249642 -0.249642)
							(end 0.1778 -0.2794)
						)
					)
					(width 0)
					(fill yes)
				)
			)
		)
		(pad "2" smd custom
			(at 0 0.4445 180)
			(size 0.1397 0.1397)
			(layers "F.Cu" "F.Mask" "F.Paste")
			(net "SW_HDD_N3")
			(options
				(clearance outline)
				(anchor circle)
			)
			(primitives
				(gr_poly
					(pts
						(arc
							(start -0.1778 -0.2794)
							(mid -0.249642 -0.249642)
							(end -0.2794 -0.1778)
						)
						(arc
							(start -0.2794 0.1778)
							(mid -0.249642 0.249642)
							(end -0.1778 0.2794)
						)
						(arc
							(start 0.1778 0.2794)
							(mid 0.249642 0.249642)
							(end 0.2794 0.1778)
						)
						(arc
							(start 0.2794 -0.1778)
							(mid 0.249642 -0.249642)
							(end 0.1778 -0.2794)
						)
					)
					(width 0)
					(fill yes)
				)
			)
		)
	)
	(footprint ""
		(layer "F.Cu")
		(at 149.225 -248.4374 -90)
		(property "Reference" "R228"
			(at 0 0 270)
			(layer "F.SilkS")
			(hide yes)
			(effects
				(font
					(size 1.27 1.27)
				)
			)
		)
		(property "Value" "1KR2F-3-GP"
			(at 0.064008 -3.993896 270)
			(unlocked yes)
			(layer "F.Fab")
			(hide yes)
			(effects
				(font
					(size 1.016 1.016)
					(thickness 0.1524)
				)
			)
		)
		(property "Device Type" "R402H16"
			(at 0.064008 -5.517896 270)
			(unlocked yes)
			(layer "F.Fab")
			(hide yes)
			(effects
				(font
					(size 1.016 1.016)
					(thickness 0.1524)
				)
			)
		)
		(duplicate_pad_numbers_are_jumpers no)
		(fp_line
			(start -0.508 -0.9398)
			(end -0.508 0.9398)
			(stroke
				(width 0.1524)
				(type default)
			)
			(layer "F.SilkS")
		)
		(fp_line
			(start 0.508 -0.9398)
			(end -0.508 -0.9398)
			(stroke
				(width 0.1524)
				(type default)
			)
			(layer "F.SilkS")
		)
		(fp_rect
			(start -0.508 0.9398)
			(end 0.508 -0.9398)
			(stroke
				(width 0)
				(type default)
			)
			(fill no)
			(layer "F.CrtYd")
		)
		(fp_rect
			(start -0.508 0.9398)
			(end 0.508 -0.9398)
			(stroke
				(width 0)
				(type default)
			)
			(fill no)
			(layer "F.Fab")
		)
		(pad "1" smd custom
			(at 0 -0.4445 270)
			(size 0.1397 0.1397)
			(layers "F.Cu" "F.Mask" "F.Paste")
			(net "P3V3_STBY_B")
			(options
				(clearance outline)
				(anchor circle)
			)
			(primitives
				(gr_poly
					(pts
						(arc
							(start -0.1778 -0.2794)
							(mid -0.249642 -0.249642)
							(end -0.2794 -0.1778)
						)
						(arc
							(start -0.2794 0.1778)
							(mid -0.249642 0.249642)
							(end -0.1778 0.2794)
						)
						(arc
							(start 0.1778 0.2794)
							(mid 0.249642 0.249642)
							(end 0.2794 0.1778)
						)
						(arc
							(start 0.2794 -0.1778)
							(mid 0.249642 -0.249642)
							(end 0.1778 -0.2794)
						)
					)
					(width 0)
					(fill yes)
				)
			)
		)
		(pad "2" smd custom
			(at 0 0.4445 270)
			(size 0.1397 0.1397)
			(layers "F.Cu" "F.Mask" "F.Paste")
			(net "SW_PWR_R_HDD4")
			(options
				(clearance outline)
				(anchor circle)
			)
			(primitives
				(gr_poly
					(pts
						(arc
							(start -0.1778 -0.2794)
							(mid -0.249642 -0.249642)
							(end -0.2794 -0.1778)
						)
						(arc
							(start -0.2794 0.1778)
							(mid -0.249642 0.249642)
							(end -0.1778 0.2794)
						)
						(arc
							(start 0.1778 0.2794)
							(mid 0.249642 0.249642)
							(end 0.2794 0.1778)
						)
						(arc
							(start 0.2794 -0.1778)
							(mid 0.249642 -0.249642)
							(end 0.1778 -0.2794)
						)
					)
					(width 0)
					(fill yes)
				)
			)
		)
	)
	(footprint ""
		(layer "F.Cu")
		(at 424.434 -267.843 180)
		(property "Reference" "C147"
			(at 0 0 180)
			(layer "F.SilkS")
			(hide yes)
			(effects
				(font
					(size 1.27 1.27)
				)
			)
		)
		(property "Value" "SC1U16V3KX-5GP"
			(at 0 -2.8194 180)
			(unlocked yes)
			(layer "F.Fab")
			(hide yes)
			(effects
				(font
					(size 1.016 1.016)
					(thickness 0.1524)
				)
			)
		)
		(property "Device Type" "C603H36"
			(at 0 -4.3434 180)
			(unlocked yes)
			(layer "F.Fab")
			(hide yes)
			(effects
				(font
					(size 1.016 1.016)
					(thickness 0.1524)
				)
			)
		)
		(duplicate_pad_numbers_are_jumpers no)
		(fp_line
			(start 0.508 0)
			(end -0.508 0)
			(stroke
				(width 0.2032)
				(type default)
			)
			(layer "F.SilkS")
		)
		(fp_rect
			(start -0.5842 1.3335)
			(end 0.5842 -1.3335)
			(stroke
				(width 0)
				(type default)
			)
			(fill no)
			(layer "F.CrtYd")
		)
		(fp_rect
			(start -0.5842 1.3335)
			(end 0.5842 -1.3335)
			(stroke
				(width 0)
				(type default)
			)
			(fill no)
			(layer "F.Fab")
		)
		(pad "1" smd custom
			(at 0 -0.762 180)
			(size 0.2159 0.2159)
			(layers "F.Cu" "F.Mask" "F.Paste")
			(net "P5V_HDD9")
			(options
				(clearance outline)
				(anchor circle)
			)
			(primitives
				(gr_poly
					(pts
						(arc
							(start -0.3302 -0.4318)
							(mid -0.402042 -0.402042)
							(end -0.4318 -0.3302)
						)
						(arc
							(start -0.4318 0.3302)
							(mid -0.402042 0.402042)
							(end -0.3302 0.4318)
						)
						(arc
							(start 0.3302 0.4318)
							(mid 0.402042 0.402042)
							(end 0.4318 0.3302)
						)
						(arc
							(start 0.4318 -0.3302)
							(mid 0.402042 -0.402042)
							(end 0.3302 -0.4318)
						)
					)
					(width 0)
					(fill yes)
				)
			)
		)
		(pad "2" smd custom
			(at 0 0.762 180)
			(size 0.2159 0.2159)
			(layers "F.Cu" "F.Mask" "F.Paste")
			(net "GND")
			(options
				(clearance outline)
				(anchor circle)
			)
			(primitives
				(gr_poly
					(pts
						(arc
							(start -0.3302 -0.4318)
							(mid -0.402042 -0.402042)
							(end -0.4318 -0.3302)
						)
						(arc
							(start -0.4318 0.3302)
							(mid -0.402042 0.402042)
							(end -0.3302 0.4318)
						)
						(arc
							(start 0.3302 0.4318)
							(mid 0.402042 0.402042)
							(end 0.4318 0.3302)
						)
						(arc
							(start 0.4318 -0.3302)
							(mid 0.402042 -0.402042)
							(end 0.3302 -0.4318)
						)
					)
					(width 0)
					(fill yes)
				)
			)
		)
	)
	(footprint ""
		(layer "F.Cu")
		(at 338.074 -250.444 90)
		(property "Reference" "R266"
			(at 0 0 90)
			(layer "F.SilkS")
			(hide yes)
			(effects
				(font
					(size 1.27 1.27)
				)
			)
		)
		(property "Value" "200KR2F-L-GP"
			(at 0.064008 -3.993896 90)
			(unlocked yes)
			(layer "F.Fab")
			(hide yes)
			(effects
				(font
					(size 1.016 1.016)
					(thickness 0.1524)
				)
			)
		)
		(property "Device Type" "R402H16"
			(at 0.064008 -5.517896 90)
			(unlocked yes)
			(layer "F.Fab")
			(hide yes)
			(effects
				(font
					(size 1.016 1.016)
					(thickness 0.1524)
				)
			)
		)
		(duplicate_pad_numbers_are_jumpers no)
		(fp_line
			(start 0.508 -0.9398)
			(end -0.508 -0.9398)
			(stroke
				(width 0.1524)
				(type default)
			)
			(layer "F.SilkS")
		)
		(fp_line
			(start -0.508 -0.9398)
			(end -0.508 0.9398)
			(stroke
				(width 0.1524)
				(type default)
			)
			(layer "F.SilkS")
		)
		(fp_rect
			(start -0.508 0.9398)
			(end 0.508 -0.9398)
			(stroke
				(width 0)
				(type default)
			)
			(fill no)
			(layer "F.CrtYd")
		)
		(fp_rect
			(start -0.508 0.9398)
			(end 0.508 -0.9398)
			(stroke
				(width 0)
				(type default)
			)
			(fill no)
			(layer "F.Fab")
		)
		(pad "1" smd custom
			(at 0 -0.4445 90)
			(size 0.1397 0.1397)
			(layers "F.Cu" "F.Mask" "F.Paste")
			(net "SW_HDD_R6")
			(options
				(clearance outline)
				(anchor circle)
			)
			(primitives
				(gr_poly
					(pts
						(arc
							(start -0.1778 -0.2794)
							(mid -0.249642 -0.249642)
							(end -0.2794 -0.1778)
						)
						(arc
							(start -0.2794 0.1778)
							(mid -0.249642 0.249642)
							(end -0.1778 0.2794)
						)
						(arc
							(start 0.1778 0.2794)
							(mid 0.249642 0.249642)
							(end 0.2794 0.1778)
						)
						(arc
							(start 0.2794 -0.1778)
							(mid 0.249642 -0.249642)
							(end 0.1778 -0.2794)
						)
					)
					(width 0)
					(fill yes)
				)
			)
		)
		(pad "2" smd custom
			(at 0 0.4445 90)
			(size 0.1397 0.1397)
			(layers "F.Cu" "F.Mask" "F.Paste")
			(net "SW_HDD_N6")
			(options
				(clearance outline)
				(anchor circle)
			)
			(primitives
				(gr_poly
					(pts
						(arc
							(start -0.1778 -0.2794)
							(mid -0.249642 -0.249642)
							(end -0.2794 -0.1778)
						)
						(arc
							(start -0.2794 0.1778)
							(mid -0.249642 0.249642)
							(end -0.1778 0.2794)
						)
						(arc
							(start 0.1778 0.2794)
							(mid 0.249642 0.249642)
							(end 0.2794 0.1778)
						)
						(arc
							(start 0.2794 -0.1778)
							(mid 0.249642 -0.249642)
							(end 0.1778 -0.2794)
						)
					)
					(width 0)
					(fill yes)
				)
			)
		)
	)
	(footprint ""
		(layer "F.Cu")
		(at 311.6834 -340.812882)
		(property "Reference" "R160"
			(at 0 0 0)
			(layer "F.SilkS")
			(hide yes)
			(effects
				(font
					(size 1.27 1.27)
				)
			)
		)
		(property "Value" "4K7R2F-GP"
			(at 0.064008 -3.993896 0)
			(unlocked yes)
			(layer "F.Fab")
			(hide yes)
			(effects
				(font
					(size 1.016 1.016)
					(thickness 0.1524)
				)
			)
		)
		(property "Device Type" "R402H16"
			(at 0.064008 -5.517896 0)
			(unlocked yes)
			(layer "F.Fab")
			(hide yes)
			(effects
				(font
					(size 1.016 1.016)
					(thickness 0.1524)
				)
			)
		)
		(duplicate_pad_numbers_are_jumpers no)
		(fp_line
			(start -0.508 -0.9398)
			(end -0.508 0.9398)
			(stroke
				(width 0.1524)
				(type default)
			)
			(layer "F.SilkS")
		)
		(fp_line
			(start 0.508 -0.9398)
			(end -0.508 -0.9398)
			(stroke
				(width 0.1524)
				(type default)
			)
			(layer "F.SilkS")
		)
		(fp_rect
			(start -0.508 0.9398)
			(end 0.508 -0.9398)
			(stroke
				(width 0)
				(type default)
			)
			(fill no)
			(layer "F.CrtYd")
		)
		(fp_rect
			(start -0.508 0.9398)
			(end 0.508 -0.9398)
			(stroke
				(width 0)
				(type default)
			)
			(fill no)
			(layer "F.Fab")
		)
		(pad "1" smd custom
			(at 0 -0.4445)
			(size 0.1397 0.1397)
			(layers "F.Cu" "F.Mask" "F.Paste")
			(net "P3V3_IN")
			(options
				(clearance outline)
				(anchor circle)
			)
			(primitives
				(gr_poly
					(pts
						(arc
							(start -0.1778 -0.2794)
							(mid -0.249642 -0.249642)
							(end -0.2794 -0.1778)
						)
						(arc
							(start -0.2794 0.1778)
							(mid -0.249642 0.249642)
							(end -0.1778 0.2794)
						)
						(arc
							(start 0.1778 0.2794)
							(mid 0.249642 0.249642)
							(end 0.2794 0.1778)
						)
						(arc
							(start 0.2794 -0.1778)
							(mid 0.249642 -0.249642)
							(end 0.1778 -0.2794)
						)
					)
					(width 0)
					(fill yes)
				)
			)
		)
		(pad "2" smd custom
			(at 0 0.4445)
			(size 0.1397 0.1397)
			(layers "F.Cu" "F.Mask" "F.Paste")
			(net "THERMHOT#_D")
			(options
				(clearance outline)
				(anchor circle)
			)
			(primitives
				(gr_poly
					(pts
						(arc
							(start -0.1778 -0.2794)
							(mid -0.249642 -0.249642)
							(end -0.2794 -0.1778)
						)
						(arc
							(start -0.2794 0.1778)
							(mid -0.249642 0.249642)
							(end -0.1778 0.2794)
						)
						(arc
							(start 0.1778 0.2794)
							(mid 0.249642 0.249642)
							(end 0.2794 0.1778)
						)
						(arc
							(start 0.2794 -0.1778)
							(mid 0.249642 -0.249642)
							(end 0.1778 -0.2794)
						)
					)
					(width 0)
					(fill yes)
				)
			)
		)
	)
	(footprint ""
		(layer "F.Cu")
		(at 181.991 -45.466 180)
		(property "Reference" "C413"
			(at 0 0 180)
			(layer "F.SilkS")
			(hide yes)
			(effects
				(font
					(size 1.27 1.27)
				)
			)
		)
		(property "Value" "SC1U25V3KX-GP"
			(at 0 -2.8194 180)
			(unlocked yes)
			(layer "F.Fab")
			(hide yes)
			(effects
				(font
					(size 1.016 1.016)
					(thickness 0.1524)
				)
			)
		)
		(property "Device Type" "C603H36"
			(at 0 -4.3434 180)
			(unlocked yes)
			(layer "F.Fab")
			(hide yes)
			(effects
				(font
					(size 1.016 1.016)
					(thickness 0.1524)
				)
			)
		)
		(duplicate_pad_numbers_are_jumpers no)
		(fp_line
			(start 0.508 0)
			(end -0.508 0)
			(stroke
				(width 0.2032)
				(type default)
			)
			(layer "F.SilkS")
		)
		(fp_rect
			(start -0.5842 1.3335)
			(end 0.5842 -1.3335)
			(stroke
				(width 0)
				(type default)
			)
			(fill no)
			(layer "F.CrtYd")
		)
		(fp_rect
			(start -0.5842 1.3335)
			(end 0.5842 -1.3335)
			(stroke
				(width 0)
				(type default)
			)
			(fill no)
			(layer "F.Fab")
		)
		(pad "1" smd custom
			(at 0 -0.762 180)
			(size 0.2159 0.2159)
			(layers "F.Cu" "F.Mask" "F.Paste")
			(net "P12V_HDD29")
			(options
				(clearance outline)
				(anchor circle)
			)
			(primitives
				(gr_poly
					(pts
						(arc
							(start -0.3302 -0.4318)
							(mid -0.402042 -0.402042)
							(end -0.4318 -0.3302)
						)
						(arc
							(start -0.4318 0.3302)
							(mid -0.402042 0.402042)
							(end -0.3302 0.4318)
						)
						(arc
							(start 0.3302 0.4318)
							(mid 0.402042 0.402042)
							(end 0.4318 0.3302)
						)
						(arc
							(start 0.4318 -0.3302)
							(mid 0.402042 -0.402042)
							(end 0.3302 -0.4318)
						)
					)
					(width 0)
					(fill yes)
				)
			)
		)
		(pad "2" smd custom
			(at 0 0.762 180)
			(size 0.2159 0.2159)
			(layers "F.Cu" "F.Mask" "F.Paste")
			(net "GND")
			(options
				(clearance outline)
				(anchor circle)
			)
			(primitives
				(gr_poly
					(pts
						(arc
							(start -0.3302 -0.4318)
							(mid -0.402042 -0.402042)
							(end -0.4318 -0.3302)
						)
						(arc
							(start -0.4318 0.3302)
							(mid -0.402042 0.402042)
							(end -0.3302 0.4318)
						)
						(arc
							(start 0.3302 0.4318)
							(mid 0.402042 0.402042)
							(end 0.4318 0.3302)
						)
						(arc
							(start 0.4318 -0.3302)
							(mid 0.402042 -0.402042)
							(end 0.3302 -0.4318)
						)
					)
					(width 0)
					(fill yes)
				)
			)
		)
	)
	(footprint ""
		(layer "F.Cu")
		(at 402.843746 -214.860378 90)
		(property "Reference" "Q252"
			(at 0 0 90)
			(layer "F.SilkS")
			(hide yes)
			(effects
				(font
					(size 1.27 1.27)
				)
			)
		)
		(property "Value" "SSM3K324R-GP"
			(at 0.127 -8.9662 90)
			(unlocked yes)
			(layer "F.Fab")
			(hide yes)
			(effects
				(font
					(size 1.016 1.016)
					(thickness 0.1524)
				)
			)
		)
		(property "Device Type" "SOT23DGS2D4H35"
			(at 0.127 -10.4902 90)
			(unlocked yes)
			(layer "F.Fab")
			(hide yes)
			(effects
				(font
					(size 1.016 1.016)
					(thickness 0.1524)
				)
			)
		)
		(duplicate_pad_numbers_are_jumpers no)
		(fp_line
			(start 1.651 -1.778)
			(end -1.651 -1.778)
			(stroke
				(width 0.1524)
				(type default)
			)
			(layer "F.SilkS")
		)
		(fp_line
			(start -1.651 -1.778)
			(end -1.651 1.778)
			(stroke
				(width 0.1524)
				(type default)
			)
			(layer "F.SilkS")
		)
		(fp_line
			(start 1.651 1.778)
			(end 1.651 -1.778)
			(stroke
				(width 0.1524)
				(type default)
			)
			(layer "F.SilkS")
		)
		(fp_line
			(start -1.651 1.778)
			(end 1.651 1.778)
			(stroke
				(width 0.1524)
				(type default)
			)
			(layer "F.SilkS")
		)
		(fp_poly
			(pts
				(xy -1.778 1.8796) (xy -1.778 -1.8796) (xy 1.778 -1.8796) (xy 1.778 1.8796)
			)
			(stroke
				(width 0)
				(type default)
			)
			(fill no)
			(layer "F.CrtYd")
		)
		(fp_poly
			(pts
				(xy -1.778 1.8796) (xy -1.778 -1.8796) (xy 1.778 -1.8796) (xy 1.778 1.8796)
			)
			(stroke
				(width 0)
				(type default)
			)
			(fill no)
			(layer "F.Fab")
		)
		(pad "D" smd custom
			(at 0 -0.9525 90)
			(size 0.1905 0.1905)
			(layers "F.Cu" "F.Mask" "F.Paste")
			(net "DRV_ACT_9_N")
			(options
				(clearance outline)
				(anchor circle)
			)
			(primitives
				(gr_poly
					(pts
						(arc
							(start -0.1778 0.5715)
							(mid -0.321484 0.511984)
							(end -0.381 0.3683)
						)
						(arc
							(start -0.381 -0.3683)
							(mid -0.321484 -0.511984)
							(end -0.1778 -0.5715)
						)
						(arc
							(start 0.1778 -0.5715)
							(mid 0.321484 -0.511984)
							(end 0.381 -0.3683)
						)
						(arc
							(start 0.381 0.3683)
							(mid 0.321484 0.511984)
							(end 0.1778 0.5715)
						)
					)
					(width 0)
					(fill yes)
				)
			)
		)
		(pad "G" smd custom
			(at -0.98425 0.9525 90)
			(size 0.1905 0.1905)
			(layers "F.Cu" "F.Mask" "F.Paste")
			(net "DRIVE_B_9_ACT")
			(options
				(clearance outline)
				(anchor circle)
			)
			(primitives
				(gr_poly
					(pts
						(arc
							(start -0.1778 0.5715)
							(mid -0.321484 0.511984)
							(end -0.381 0.3683)
						)
						(arc
							(start -0.381 -0.3683)
							(mid -0.321484 -0.511984)
							(end -0.1778 -0.5715)
						)
						(arc
							(start 0.1778 -0.5715)
							(mid 0.321484 -0.511984)
							(end 0.381 -0.3683)
						)
						(arc
							(start 0.381 0.3683)
							(mid 0.321484 0.511984)
							(end 0.1778 0.5715)
						)
					)
					(width 0)
					(fill yes)
				)
			)
		)
		(pad "S" smd custom
			(at 0.98425 0.9525 90)
			(size 0.1905 0.1905)
			(layers "F.Cu" "F.Mask" "F.Paste")
			(net "GND")
			(options
				(clearance outline)
				(anchor circle)
			)
			(primitives
				(gr_poly
					(pts
						(arc
							(start -0.1778 0.5715)
							(mid -0.321484 0.511984)
							(end -0.381 0.3683)
						)
						(arc
							(start -0.381 -0.3683)
							(mid -0.321484 -0.511984)
							(end -0.1778 -0.5715)
						)
						(arc
							(start 0.1778 -0.5715)
							(mid 0.321484 -0.511984)
							(end 0.381 -0.3683)
						)
						(arc
							(start 0.381 0.3683)
							(mid 0.321484 0.511984)
							(end 0.1778 0.5715)
						)
					)
					(width 0)
					(fill yes)
				)
			)
		)
	)
	(footprint ""
		(layer "F.Cu")
		(at 32.4104 -31.5976)
		(property "Reference" "C349"
			(at 0 0 0)
			(layer "F.SilkS")
			(hide yes)
			(effects
				(font
					(size 1.27 1.27)
				)
			)
		)
		(property "Value" "SCD01U50V2KX-1GP"
			(at 1.1811 -2.7051 0)
			(unlocked yes)
			(layer "F.Fab")
			(hide yes)
			(effects
				(font
					(size 1.016 1.016)
					(thickness 0.1524)
				)
			)
		)
		(property "Device Type" "C402H22"
			(at 1.1811 -4.2291 0)
			(unlocked yes)
			(layer "F.Fab")
			(hide yes)
			(effects
				(font
					(size 1.016 1.016)
					(thickness 0.1524)
				)
			)
		)
		(duplicate_pad_numbers_are_jumpers no)
		(fp_rect
			(start -0.4318 0.9525)
			(end 0.4318 -0.9525)
			(stroke
				(width 0)
				(type default)
			)
			(fill no)
			(layer "F.CrtYd")
		)
		(fp_rect
			(start -0.4318 0.9525)
			(end 0.4318 -0.9525)
			(stroke
				(width 0)
				(type default)
			)
			(fill no)
			(layer "F.Fab")
		)
		(pad "1" smd custom
			(at 0 -0.4445)
			(size 0.1524 0.1524)
			(layers "F.Cu" "F.Mask" "F.Paste")
			(net "HDD_PRSNT_24")
			(options
				(clearance outline)
				(anchor circle)
			)
			(primitives
				(gr_poly
					(pts
						(arc
							(start 0.3048 -0.2032)
							(mid 0.275042 -0.275042)
							(end 0.2032 -0.3048)
						)
						(arc
							(start -0.2032 -0.3048)
							(mid -0.275042 -0.275042)
							(end -0.3048 -0.2032)
						)
						(arc
							(start -0.3048 0.2032)
							(mid -0.275042 0.275042)
							(end -0.2032 0.3048)
						)
						(arc
							(start 0.2032 0.3048)
							(mid 0.275042 0.275042)
							(end 0.3048 0.2032)
						)
					)
					(width 0)
					(fill yes)
				)
			)
		)
		(pad "2" smd custom
			(at 0 0.4445)
			(size 0.1524 0.1524)
			(layers "F.Cu" "F.Mask" "F.Paste")
			(net "GND")
			(options
				(clearance outline)
				(anchor circle)
			)
			(primitives
				(gr_poly
					(pts
						(arc
							(start 0.3048 -0.2032)
							(mid 0.275042 -0.275042)
							(end 0.2032 -0.3048)
						)
						(arc
							(start -0.2032 -0.3048)
							(mid -0.275042 -0.275042)
							(end -0.3048 -0.2032)
						)
						(arc
							(start -0.3048 0.2032)
							(mid -0.275042 0.275042)
							(end -0.2032 0.3048)
						)
						(arc
							(start 0.2032 0.3048)
							(mid 0.275042 0.275042)
							(end 0.3048 0.2032)
						)
					)
					(width 0)
					(fill yes)
				)
			)
		)
	)
	(footprint ""
		(layer "F.Cu")
		(at 424.434 -37.846 180)
		(property "Reference" "C459"
			(at 0 0 180)
			(layer "F.SilkS")
			(hide yes)
			(effects
				(font
					(size 1.27 1.27)
				)
			)
		)
		(property "Value" "SC1U16V3KX-5GP"
			(at 0 -2.8194 180)
			(unlocked yes)
			(layer "F.Fab")
			(hide yes)
			(effects
				(font
					(size 1.016 1.016)
					(thickness 0.1524)
				)
			)
		)
		(property "Device Type" "C603H36"
			(at 0 -4.3434 180)
			(unlocked yes)
			(layer "F.Fab")
			(hide yes)
			(effects
				(font
					(size 1.016 1.016)
					(thickness 0.1524)
				)
			)
		)
		(duplicate_pad_numbers_are_jumpers no)
		(fp_line
			(start 0.508 0)
			(end -0.508 0)
			(stroke
				(width 0.2032)
				(type default)
			)
			(layer "F.SilkS")
		)
		(fp_rect
			(start -0.5842 1.3335)
			(end 0.5842 -1.3335)
			(stroke
				(width 0)
				(type default)
			)
			(fill no)
			(layer "F.CrtYd")
		)
		(fp_rect
			(start -0.5842 1.3335)
			(end 0.5842 -1.3335)
			(stroke
				(width 0)
				(type default)
			)
			(fill no)
			(layer "F.Fab")
		)
		(pad "1" smd custom
			(at 0 -0.762 180)
			(size 0.2159 0.2159)
			(layers "F.Cu" "F.Mask" "F.Paste")
			(net "P5V_HDD33")
			(options
				(clearance outline)
				(anchor circle)
			)
			(primitives
				(gr_poly
					(pts
						(arc
							(start -0.3302 -0.4318)
							(mid -0.402042 -0.402042)
							(end -0.4318 -0.3302)
						)
						(arc
							(start -0.4318 0.3302)
							(mid -0.402042 0.402042)
							(end -0.3302 0.4318)
						)
						(arc
							(start 0.3302 0.4318)
							(mid 0.402042 0.402042)
							(end 0.4318 0.3302)
						)
						(arc
							(start 0.4318 -0.3302)
							(mid 0.402042 -0.402042)
							(end 0.3302 -0.4318)
						)
					)
					(width 0)
					(fill yes)
				)
			)
		)
		(pad "2" smd custom
			(at 0 0.762 180)
			(size 0.2159 0.2159)
			(layers "F.Cu" "F.Mask" "F.Paste")
			(net "GND")
			(options
				(clearance outline)
				(anchor circle)
			)
			(primitives
				(gr_poly
					(pts
						(arc
							(start -0.3302 -0.4318)
							(mid -0.402042 -0.402042)
							(end -0.4318 -0.3302)
						)
						(arc
							(start -0.4318 0.3302)
							(mid -0.402042 0.402042)
							(end -0.3302 0.4318)
						)
						(arc
							(start 0.3302 0.4318)
							(mid 0.402042 0.402042)
							(end 0.4318 0.3302)
						)
						(arc
							(start 0.4318 -0.3302)
							(mid 0.402042 -0.402042)
							(end 0.3302 -0.4318)
						)
					)
					(width 0)
					(fill yes)
				)
			)
		)
	)
	(footprint ""
		(layer "F.Cu")
		(at 137.030968 -99.874578 90)
		(property "Reference" "Q265"
			(at 0 0 90)
			(layer "F.SilkS")
			(hide yes)
			(effects
				(font
					(size 1.27 1.27)
				)
			)
		)
		(property "Value" "SSM3K324R-GP"
			(at 0.127 -8.9662 90)
			(unlocked yes)
			(layer "F.Fab")
			(hide yes)
			(effects
				(font
					(size 1.016 1.016)
					(thickness 0.1524)
				)
			)
		)
		(property "Device Type" "SOT23DGS2D4H35"
			(at 0.127 -10.4902 90)
			(unlocked yes)
			(layer "F.Fab")
			(hide yes)
			(effects
				(font
					(size 1.016 1.016)
					(thickness 0.1524)
				)
			)
		)
		(duplicate_pad_numbers_are_jumpers no)
		(fp_line
			(start 1.651 -1.778)
			(end -1.651 -1.778)
			(stroke
				(width 0.1524)
				(type default)
			)
			(layer "F.SilkS")
		)
		(fp_line
			(start -1.651 -1.778)
			(end -1.651 1.778)
			(stroke
				(width 0.1524)
				(type default)
			)
			(layer "F.SilkS")
		)
		(fp_line
			(start 1.651 1.778)
			(end 1.651 -1.778)
			(stroke
				(width 0.1524)
				(type default)
			)
			(layer "F.SilkS")
		)
		(fp_line
			(start -1.651 1.778)
			(end 1.651 1.778)
			(stroke
				(width 0.1524)
				(type default)
			)
			(layer "F.SilkS")
		)
		(fp_poly
			(pts
				(xy -1.778 1.8796) (xy -1.778 -1.8796) (xy 1.778 -1.8796) (xy 1.778 1.8796)
			)
			(stroke
				(width 0)
				(type default)
			)
			(fill no)
			(layer "F.CrtYd")
		)
		(fp_poly
			(pts
				(xy -1.778 1.8796) (xy -1.778 -1.8796) (xy 1.778 -1.8796) (xy 1.778 1.8796)
			)
			(stroke
				(width 0)
				(type default)
			)
			(fill no)
			(layer "F.Fab")
		)
		(pad "D" smd custom
			(at 0 -0.9525 90)
			(size 0.1905 0.1905)
			(layers "F.Cu" "F.Mask" "F.Paste")
			(net "DRV_ACT_16_N")
			(options
				(clearance outline)
				(anchor circle)
			)
			(primitives
				(gr_poly
					(pts
						(arc
							(start -0.1778 0.5715)
							(mid -0.321484 0.511984)
							(end -0.381 0.3683)
						)
						(arc
							(start -0.381 -0.3683)
							(mid -0.321484 -0.511984)
							(end -0.1778 -0.5715)
						)
						(arc
							(start 0.1778 -0.5715)
							(mid 0.321484 -0.511984)
							(end 0.381 -0.3683)
						)
						(arc
							(start 0.381 0.3683)
							(mid 0.321484 0.511984)
							(end 0.1778 0.5715)
						)
					)
					(width 0)
					(fill yes)
				)
			)
		)
		(pad "G" smd custom
			(at -0.98425 0.9525 90)
			(size 0.1905 0.1905)
			(layers "F.Cu" "F.Mask" "F.Paste")
			(net "DRIVE_B_16_ACT")
			(options
				(clearance outline)
				(anchor circle)
			)
			(primitives
				(gr_poly
					(pts
						(arc
							(start -0.1778 0.5715)
							(mid -0.321484 0.511984)
							(end -0.381 0.3683)
						)
						(arc
							(start -0.381 -0.3683)
							(mid -0.321484 -0.511984)
							(end -0.1778 -0.5715)
						)
						(arc
							(start 0.1778 -0.5715)
							(mid 0.321484 -0.511984)
							(end 0.381 -0.3683)
						)
						(arc
							(start 0.381 0.3683)
							(mid 0.321484 0.511984)
							(end 0.1778 0.5715)
						)
					)
					(width 0)
					(fill yes)
				)
			)
		)
		(pad "S" smd custom
			(at 0.98425 0.9525 90)
			(size 0.1905 0.1905)
			(layers "F.Cu" "F.Mask" "F.Paste")
			(net "GND")
			(options
				(clearance outline)
				(anchor circle)
			)
			(primitives
				(gr_poly
					(pts
						(arc
							(start -0.1778 0.5715)
							(mid -0.321484 0.511984)
							(end -0.381 0.3683)
						)
						(arc
							(start -0.381 -0.3683)
							(mid -0.321484 -0.511984)
							(end -0.1778 -0.5715)
						)
						(arc
							(start 0.1778 -0.5715)
							(mid 0.321484 -0.511984)
							(end 0.381 -0.3683)
						)
						(arc
							(start 0.381 0.3683)
							(mid 0.321484 0.511984)
							(end 0.1778 0.5715)
						)
					)
					(width 0)
					(fill yes)
				)
			)
		)
	)
	(footprint ""
		(layer "F.Cu")
		(at 468.122 -252.095 180)
		(property "Reference" "R346"
			(at 0 0 180)
			(layer "F.SilkS")
			(hide yes)
			(effects
				(font
					(size 1.27 1.27)
				)
			)
		)
		(property "Value" "200KR2F-L-GP"
			(at 0.064008 -3.993896 180)
			(unlocked yes)
			(layer "F.Fab")
			(hide yes)
			(effects
				(font
					(size 1.016 1.016)
					(thickness 0.1524)
				)
			)
		)
		(property "Device Type" "R402H16"
			(at 0.064008 -5.517896 180)
			(unlocked yes)
			(layer "F.Fab")
			(hide yes)
			(effects
				(font
					(size 1.016 1.016)
					(thickness 0.1524)
				)
			)
		)
		(duplicate_pad_numbers_are_jumpers no)
		(fp_line
			(start 0.508 -0.9398)
			(end -0.508 -0.9398)
			(stroke
				(width 0.1524)
				(type default)
			)
			(layer "F.SilkS")
		)
		(fp_line
			(start -0.508 -0.9398)
			(end -0.508 0.9398)
			(stroke
				(width 0.1524)
				(type default)
			)
			(layer "F.SilkS")
		)
		(fp_rect
			(start -0.508 0.9398)
			(end 0.508 -0.9398)
			(stroke
				(width 0)
				(type default)
			)
			(fill no)
			(layer "F.CrtYd")
		)
		(fp_rect
			(start -0.508 0.9398)
			(end 0.508 -0.9398)
			(stroke
				(width 0)
				(type default)
			)
			(fill no)
			(layer "F.Fab")
		)
		(pad "1" smd custom
			(at 0 -0.4445 180)
			(size 0.1397 0.1397)
			(layers "F.Cu" "F.Mask" "F.Paste")
			(net "SW_HDD_R11")
			(options
				(clearance outline)
				(anchor circle)
			)
			(primitives
				(gr_poly
					(pts
						(arc
							(start -0.1778 -0.2794)
							(mid -0.249642 -0.249642)
							(end -0.2794 -0.1778)
						)
						(arc
							(start -0.2794 0.1778)
							(mid -0.249642 0.249642)
							(end -0.1778 0.2794)
						)
						(arc
							(start 0.1778 0.2794)
							(mid 0.249642 0.249642)
							(end 0.2794 0.1778)
						)
						(arc
							(start 0.2794 -0.1778)
							(mid 0.249642 -0.249642)
							(end 0.1778 -0.2794)
						)
					)
					(width 0)
					(fill yes)
				)
			)
		)
		(pad "2" smd custom
			(at 0 0.4445 180)
			(size 0.1397 0.1397)
			(layers "F.Cu" "F.Mask" "F.Paste")
			(net "SW_HDD_N11")
			(options
				(clearance outline)
				(anchor circle)
			)
			(primitives
				(gr_poly
					(pts
						(arc
							(start -0.1778 -0.2794)
							(mid -0.249642 -0.249642)
							(end -0.2794 -0.1778)
						)
						(arc
							(start -0.2794 0.1778)
							(mid -0.249642 0.249642)
							(end -0.1778 0.2794)
						)
						(arc
							(start 0.1778 0.2794)
							(mid 0.249642 0.249642)
							(end 0.2794 0.1778)
						)
						(arc
							(start 0.2794 -0.1778)
							(mid 0.249642 -0.249642)
							(end 0.1778 -0.2794)
						)
					)
					(width 0)
					(fill yes)
				)
			)
		)
	)
	(footprint ""
		(layer "F.Cu")
		(at 47.402496 -357.8352 90)
		(property "Reference" "R150"
			(at 0 0 90)
			(layer "F.SilkS")
			(hide yes)
			(effects
				(font
					(size 1.27 1.27)
				)
			)
		)
		(property "Value" "300KR2F-GP"
			(at 0.064008 -3.993896 90)
			(unlocked yes)
			(layer "F.Fab")
			(hide yes)
			(effects
				(font
					(size 1.016 1.016)
					(thickness 0.1524)
				)
			)
		)
		(property "Device Type" "R402H16"
			(at 0.064008 -5.517896 90)
			(unlocked yes)
			(layer "F.Fab")
			(hide yes)
			(effects
				(font
					(size 1.016 1.016)
					(thickness 0.1524)
				)
			)
		)
		(duplicate_pad_numbers_are_jumpers no)
		(fp_line
			(start 0.508 -0.9398)
			(end -0.508 -0.9398)
			(stroke
				(width 0.1524)
				(type default)
			)
			(layer "F.SilkS")
		)
		(fp_line
			(start -0.508 -0.9398)
			(end -0.508 0.9398)
			(stroke
				(width 0.1524)
				(type default)
			)
			(layer "F.SilkS")
		)
		(fp_rect
			(start -0.508 0.9398)
			(end 0.508 -0.9398)
			(stroke
				(width 0)
				(type default)
			)
			(fill no)
			(layer "F.CrtYd")
		)
		(fp_rect
			(start -0.508 0.9398)
			(end 0.508 -0.9398)
			(stroke
				(width 0)
				(type default)
			)
			(fill no)
			(layer "F.Fab")
		)
		(pad "1" smd custom
			(at 0 -0.4445 90)
			(size 0.1397 0.1397)
			(layers "F.Cu" "F.Mask" "F.Paste")
			(net "GATE_FAN0_R")
			(options
				(clearance outline)
				(anchor circle)
			)
			(primitives
				(gr_poly
					(pts
						(arc
							(start -0.1778 -0.2794)
							(mid -0.249642 -0.249642)
							(end -0.2794 -0.1778)
						)
						(arc
							(start -0.2794 0.1778)
							(mid -0.249642 0.249642)
							(end -0.1778 0.2794)
						)
						(arc
							(start 0.1778 0.2794)
							(mid 0.249642 0.249642)
							(end 0.2794 0.1778)
						)
						(arc
							(start 0.2794 -0.1778)
							(mid 0.249642 -0.249642)
							(end 0.1778 -0.2794)
						)
					)
					(width 0)
					(fill yes)
				)
			)
		)
		(pad "2" smd custom
			(at 0 0.4445 90)
			(size 0.1397 0.1397)
			(layers "F.Cu" "F.Mask" "F.Paste")
			(net "P12V_IN")
			(options
				(clearance outline)
				(anchor circle)
			)
			(primitives
				(gr_poly
					(pts
						(arc
							(start -0.1778 -0.2794)
							(mid -0.249642 -0.249642)
							(end -0.2794 -0.1778)
						)
						(arc
							(start -0.2794 0.1778)
							(mid -0.249642 0.249642)
							(end -0.1778 0.2794)
						)
						(arc
							(start 0.1778 0.2794)
							(mid 0.249642 0.249642)
							(end 0.2794 0.1778)
						)
						(arc
							(start 0.2794 -0.1778)
							(mid 0.249642 -0.249642)
							(end 0.1778 -0.2794)
						)
					)
					(width 0)
					(fill yes)
				)
			)
		)
	)
	(footprint ""
		(layer "F.Cu")
		(at 467.741 -135.509 90)
		(property "Reference" "R613"
			(at 0 0 90)
			(layer "F.SilkS")
			(hide yes)
			(effects
				(font
					(size 1.27 1.27)
				)
			)
		)
		(property "Value" "4K7R2J-2-GP"
			(at 0.064008 -3.993896 90)
			(unlocked yes)
			(layer "F.Fab")
			(hide yes)
			(effects
				(font
					(size 1.016 1.016)
					(thickness 0.1524)
				)
			)
		)
		(property "Device Type" "R402H16"
			(at 0.064008 -5.517896 90)
			(unlocked yes)
			(layer "F.Fab")
			(hide yes)
			(effects
				(font
					(size 1.016 1.016)
					(thickness 0.1524)
				)
			)
		)
		(duplicate_pad_numbers_are_jumpers no)
		(fp_line
			(start 0.508 -0.9398)
			(end -0.508 -0.9398)
			(stroke
				(width 0.1524)
				(type default)
			)
			(layer "F.SilkS")
		)
		(fp_line
			(start -0.508 -0.9398)
			(end -0.508 0.9398)
			(stroke
				(width 0.1524)
				(type default)
			)
			(layer "F.SilkS")
		)
		(fp_rect
			(start -0.508 0.9398)
			(end 0.508 -0.9398)
			(stroke
				(width 0)
				(type default)
			)
			(fill no)
			(layer "F.CrtYd")
		)
		(fp_rect
			(start -0.508 0.9398)
			(end 0.508 -0.9398)
			(stroke
				(width 0)
				(type default)
			)
			(fill no)
			(layer "F.Fab")
		)
		(pad "1" smd custom
			(at 0 -0.4445 90)
			(size 0.1397 0.1397)
			(layers "F.Cu" "F.Mask" "F.Paste")
			(net "P12V_B")
			(options
				(clearance outline)
				(anchor circle)
			)
			(primitives
				(gr_poly
					(pts
						(arc
							(start -0.1778 -0.2794)
							(mid -0.249642 -0.249642)
							(end -0.2794 -0.1778)
						)
						(arc
							(start -0.2794 0.1778)
							(mid -0.249642 0.249642)
							(end -0.1778 0.2794)
						)
						(arc
							(start 0.1778 0.2794)
							(mid 0.249642 0.249642)
							(end 0.2794 0.1778)
						)
						(arc
							(start 0.2794 -0.1778)
							(mid 0.249642 -0.249642)
							(end 0.1778 -0.2794)
						)
					)
					(width 0)
					(fill yes)
				)
			)
		)
		(pad "2" smd custom
			(at 0 0.4445 90)
			(size 0.1397 0.1397)
			(layers "F.Cu" "F.Mask" "F.Paste")
			(net "SW_HDD_R23")
			(options
				(clearance outline)
				(anchor circle)
			)
			(primitives
				(gr_poly
					(pts
						(arc
							(start -0.1778 -0.2794)
							(mid -0.249642 -0.249642)
							(end -0.2794 -0.1778)
						)
						(arc
							(start -0.2794 0.1778)
							(mid -0.249642 0.249642)
							(end -0.1778 0.2794)
						)
						(arc
							(start 0.1778 0.2794)
							(mid 0.249642 0.249642)
							(end 0.2794 0.1778)
						)
						(arc
							(start 0.2794 -0.1778)
							(mid 0.249642 -0.249642)
							(end 0.1778 -0.2794)
						)
					)
					(width 0)
					(fill yes)
				)
			)
		)
	)
	(footprint ""
		(layer "F.Cu")
		(at 51.5112 -9.9568)
		(property "Reference" "R660"
			(at 0 0 0)
			(layer "F.SilkS")
			(hide yes)
			(effects
				(font
					(size 1.27 1.27)
				)
			)
		)
		(property "Value" "300KR2F-GP"
			(at 0.064008 -3.993896 0)
			(unlocked yes)
			(layer "F.Fab")
			(hide yes)
			(effects
				(font
					(size 1.016 1.016)
					(thickness 0.1524)
				)
			)
		)
		(property "Device Type" "R402H16"
			(at 0.064008 -5.517896 0)
			(unlocked yes)
			(layer "F.Fab")
			(hide yes)
			(effects
				(font
					(size 1.016 1.016)
					(thickness 0.1524)
				)
			)
		)
		(duplicate_pad_numbers_are_jumpers no)
		(fp_line
			(start -0.508 -0.9398)
			(end -0.508 0.9398)
			(stroke
				(width 0.1524)
				(type default)
			)
			(layer "F.SilkS")
		)
		(fp_line
			(start 0.508 -0.9398)
			(end -0.508 -0.9398)
			(stroke
				(width 0.1524)
				(type default)
			)
			(layer "F.SilkS")
		)
		(fp_rect
			(start -0.508 0.9398)
			(end 0.508 -0.9398)
			(stroke
				(width 0)
				(type default)
			)
			(fill no)
			(layer "F.CrtYd")
		)
		(fp_rect
			(start -0.508 0.9398)
			(end 0.508 -0.9398)
			(stroke
				(width 0)
				(type default)
			)
			(fill no)
			(layer "F.Fab")
		)
		(pad "1" smd custom
			(at 0 -0.4445)
			(size 0.1397 0.1397)
			(layers "F.Cu" "F.Mask" "F.Paste")
			(net "SW_HDD_N25")
			(options
				(clearance outline)
				(anchor circle)
			)
			(primitives
				(gr_poly
					(pts
						(arc
							(start -0.1778 -0.2794)
							(mid -0.249642 -0.249642)
							(end -0.2794 -0.1778)
						)
						(arc
							(start -0.2794 0.1778)
							(mid -0.249642 0.249642)
							(end -0.1778 0.2794)
						)
						(arc
							(start 0.1778 0.2794)
							(mid 0.249642 0.249642)
							(end 0.2794 0.1778)
						)
						(arc
							(start 0.2794 -0.1778)
							(mid 0.249642 -0.249642)
							(end 0.1778 -0.2794)
						)
					)
					(width 0)
					(fill yes)
				)
			)
		)
		(pad "2" smd custom
			(at 0 0.4445)
			(size 0.1397 0.1397)
			(layers "F.Cu" "F.Mask" "F.Paste")
			(net "P12V_B")
			(options
				(clearance outline)
				(anchor circle)
			)
			(primitives
				(gr_poly
					(pts
						(arc
							(start -0.1778 -0.2794)
							(mid -0.249642 -0.249642)
							(end -0.2794 -0.1778)
						)
						(arc
							(start -0.2794 0.1778)
							(mid -0.249642 0.249642)
							(end -0.1778 0.2794)
						)
						(arc
							(start 0.1778 0.2794)
							(mid 0.249642 0.249642)
							(end 0.2794 0.1778)
						)
						(arc
							(start 0.2794 -0.1778)
							(mid 0.249642 -0.249642)
							(end 0.1778 -0.2794)
						)
					)
					(width 0)
					(fill yes)
				)
			)
		)
	)
	(footprint ""
		(layer "F.Cu")
		(at 331.47 -44.958 180)
		(property "Reference" "C424"
			(at 0 0 180)
			(layer "F.SilkS")
			(hide yes)
			(effects
				(font
					(size 1.27 1.27)
				)
			)
		)
		(property "Value" "SC4D7U25V5KX-1-GP"
			(at -0.0762 -6.1214 180)
			(unlocked yes)
			(layer "F.Fab")
			(hide yes)
			(effects
				(font
					(size 1.016 1.016)
					(thickness 0.1524)
				)
			)
		)
		(property "Device Type" "C805H58"
			(at -0.0762 -8.1534 180)
			(unlocked yes)
			(layer "F.Fab")
			(hide yes)
			(effects
				(font
					(size 1.016 1.016)
					(thickness 0.1524)
				)
			)
		)
		(duplicate_pad_numbers_are_jumpers no)
		(fp_line
			(start 0.635 0)
			(end -0.635 0)
			(stroke
				(width 0.508)
				(type default)
			)
			(layer "F.SilkS")
		)
		(fp_rect
			(start -0.9652 1.778)
			(end 0.9652 -1.778)
			(stroke
				(width 0)
				(type default)
			)
			(fill no)
			(layer "F.CrtYd")
		)
		(fp_poly
			(pts
				(xy -0.9652 -1.778) (xy 0.9652 -1.778) (xy 0.9652 1.778) (xy -0.9652 1.778)
			)
			(stroke
				(width 0)
				(type default)
			)
			(fill no)
			(layer "F.Fab")
		)
		(pad "1" smd rect
			(at 0 -0.9652 180)
			(size 1.397 1.143)
			(layers "F.Cu" "F.Mask" "F.Paste")
			(net "P12V_HDD30")
		)
		(pad "2" smd rect
			(at 0 0.9652 180)
			(size 1.397 1.143)
			(layers "F.Cu" "F.Mask" "F.Paste")
			(net "GND")
		)
	)
	(footprint ""
		(layer "F.Cu")
		(at 424.434 -45.339 180)
		(property "Reference" "C466"
			(at 0 0 180)
			(layer "F.SilkS")
			(hide yes)
			(effects
				(font
					(size 1.27 1.27)
				)
			)
		)
		(property "Value" "SC1U25V3KX-GP"
			(at 0 -2.8194 180)
			(unlocked yes)
			(layer "F.Fab")
			(hide yes)
			(effects
				(font
					(size 1.016 1.016)
					(thickness 0.1524)
				)
			)
		)
		(property "Device Type" "C603H36"
			(at 0 -4.3434 180)
			(unlocked yes)
			(layer "F.Fab")
			(hide yes)
			(effects
				(font
					(size 1.016 1.016)
					(thickness 0.1524)
				)
			)
		)
		(duplicate_pad_numbers_are_jumpers no)
		(fp_line
			(start 0.508 0)
			(end -0.508 0)
			(stroke
				(width 0.2032)
				(type default)
			)
			(layer "F.SilkS")
		)
		(fp_rect
			(start -0.5842 1.3335)
			(end 0.5842 -1.3335)
			(stroke
				(width 0)
				(type default)
			)
			(fill no)
			(layer "F.CrtYd")
		)
		(fp_rect
			(start -0.5842 1.3335)
			(end 0.5842 -1.3335)
			(stroke
				(width 0)
				(type default)
			)
			(fill no)
			(layer "F.Fab")
		)
		(pad "1" smd custom
			(at 0 -0.762 180)
			(size 0.2159 0.2159)
			(layers "F.Cu" "F.Mask" "F.Paste")
			(net "P12V_HDD33")
			(options
				(clearance outline)
				(anchor circle)
			)
			(primitives
				(gr_poly
					(pts
						(arc
							(start -0.3302 -0.4318)
							(mid -0.402042 -0.402042)
							(end -0.4318 -0.3302)
						)
						(arc
							(start -0.4318 0.3302)
							(mid -0.402042 0.402042)
							(end -0.3302 0.4318)
						)
						(arc
							(start 0.3302 0.4318)
							(mid 0.402042 0.402042)
							(end 0.4318 0.3302)
						)
						(arc
							(start 0.4318 -0.3302)
							(mid 0.402042 -0.402042)
							(end 0.3302 -0.4318)
						)
					)
					(width 0)
					(fill yes)
				)
			)
		)
		(pad "2" smd custom
			(at 0 0.762 180)
			(size 0.2159 0.2159)
			(layers "F.Cu" "F.Mask" "F.Paste")
			(net "GND")
			(options
				(clearance outline)
				(anchor circle)
			)
			(primitives
				(gr_poly
					(pts
						(arc
							(start -0.3302 -0.4318)
							(mid -0.402042 -0.402042)
							(end -0.4318 -0.3302)
						)
						(arc
							(start -0.4318 0.3302)
							(mid -0.402042 0.402042)
							(end -0.3302 0.4318)
						)
						(arc
							(start 0.3302 0.4318)
							(mid 0.402042 0.402042)
							(end 0.4318 0.3302)
						)
						(arc
							(start 0.4318 -0.3302)
							(mid 0.402042 -0.402042)
							(end 0.3302 -0.4318)
						)
					)
					(width 0)
					(fill yes)
				)
			)
		)
	)
	(footprint ""
		(layer "F.Cu")
		(at 336.931 -131.826 180)
		(property "Reference" "R498"
			(at 0 0 180)
			(layer "F.SilkS")
			(hide yes)
			(effects
				(font
					(size 1.27 1.27)
				)
			)
		)
		(property "Value" "4K7R2J-2-GP"
			(at 0.064008 -3.993896 180)
			(unlocked yes)
			(layer "F.Fab")
			(hide yes)
			(effects
				(font
					(size 1.016 1.016)
					(thickness 0.1524)
				)
			)
		)
		(property "Device Type" "R402H16"
			(at 0.064008 -5.517896 180)
			(unlocked yes)
			(layer "F.Fab")
			(hide yes)
			(effects
				(font
					(size 1.016 1.016)
					(thickness 0.1524)
				)
			)
		)
		(duplicate_pad_numbers_are_jumpers no)
		(fp_line
			(start 0.508 -0.9398)
			(end -0.508 -0.9398)
			(stroke
				(width 0.1524)
				(type default)
			)
			(layer "F.SilkS")
		)
		(fp_line
			(start -0.508 -0.9398)
			(end -0.508 0.9398)
			(stroke
				(width 0.1524)
				(type default)
			)
			(layer "F.SilkS")
		)
		(fp_rect
			(start -0.508 0.9398)
			(end 0.508 -0.9398)
			(stroke
				(width 0)
				(type default)
			)
			(fill no)
			(layer "F.CrtYd")
		)
		(fp_rect
			(start -0.508 0.9398)
			(end 0.508 -0.9398)
			(stroke
				(width 0)
				(type default)
			)
			(fill no)
			(layer "F.Fab")
		)
		(pad "1" smd custom
			(at 0 -0.4445 180)
			(size 0.1397 0.1397)
			(layers "F.Cu" "F.Mask" "F.Paste")
			(net "P12V_B")
			(options
				(clearance outline)
				(anchor circle)
			)
			(primitives
				(gr_poly
					(pts
						(arc
							(start -0.1778 -0.2794)
							(mid -0.249642 -0.249642)
							(end -0.2794 -0.1778)
						)
						(arc
							(start -0.2794 0.1778)
							(mid -0.249642 0.249642)
							(end -0.1778 0.2794)
						)
						(arc
							(start 0.1778 0.2794)
							(mid 0.249642 0.249642)
							(end 0.2794 0.1778)
						)
						(arc
							(start 0.2794 -0.1778)
							(mid 0.249642 -0.249642)
							(end 0.1778 -0.2794)
						)
					)
					(width 0)
					(fill yes)
				)
			)
		)
		(pad "2" smd custom
			(at 0 0.4445 180)
			(size 0.1397 0.1397)
			(layers "F.Cu" "F.Mask" "F.Paste")
			(net "SW_HDD_R18")
			(options
				(clearance outline)
				(anchor circle)
			)
			(primitives
				(gr_poly
					(pts
						(arc
							(start -0.1778 -0.2794)
							(mid -0.249642 -0.249642)
							(end -0.2794 -0.1778)
						)
						(arc
							(start -0.2794 0.1778)
							(mid -0.249642 0.249642)
							(end -0.1778 0.2794)
						)
						(arc
							(start 0.1778 0.2794)
							(mid 0.249642 0.249642)
							(end 0.2794 0.1778)
						)
						(arc
							(start 0.2794 -0.1778)
							(mid 0.249642 -0.249642)
							(end 0.1778 -0.2794)
						)
					)
					(width 0)
					(fill yes)
				)
			)
		)
	)
	(footprint ""
		(layer "F.Cu")
		(at 398.907 -131.826 180)
		(property "Reference" "R547"
			(at 0 0 180)
			(layer "F.SilkS")
			(hide yes)
			(effects
				(font
					(size 1.27 1.27)
				)
			)
		)
		(property "Value" "0R2J-2-GP"
			(at 0.064008 -3.993896 180)
			(unlocked yes)
			(layer "F.Fab")
			(hide yes)
			(effects
				(font
					(size 1.016 1.016)
					(thickness 0.1524)
				)
			)
		)
		(property "Device Type" "R402H16"
			(at 0.064008 -5.517896 180)
			(unlocked yes)
			(layer "F.Fab")
			(hide yes)
			(effects
				(font
					(size 1.016 1.016)
					(thickness 0.1524)
				)
			)
		)
		(duplicate_pad_numbers_are_jumpers no)
		(fp_line
			(start 0.508 -0.9398)
			(end -0.508 -0.9398)
			(stroke
				(width 0.1524)
				(type default)
			)
			(layer "F.SilkS")
		)
		(fp_line
			(start -0.508 -0.9398)
			(end -0.508 0.9398)
			(stroke
				(width 0.1524)
				(type default)
			)
			(layer "F.SilkS")
		)
		(fp_rect
			(start -0.508 0.9398)
			(end 0.508 -0.9398)
			(stroke
				(width 0)
				(type default)
			)
			(fill no)
			(layer "F.CrtYd")
		)
		(fp_rect
			(start -0.508 0.9398)
			(end 0.508 -0.9398)
			(stroke
				(width 0)
				(type default)
			)
			(fill no)
			(layer "F.Fab")
		)
		(pad "1" smd custom
			(at 0 -0.4445 180)
			(size 0.1397 0.1397)
			(layers "F.Cu" "F.Mask" "F.Paste")
			(net "SW_HDD_G20")
			(options
				(clearance outline)
				(anchor circle)
			)
			(primitives
				(gr_poly
					(pts
						(arc
							(start -0.1778 -0.2794)
							(mid -0.249642 -0.249642)
							(end -0.2794 -0.1778)
						)
						(arc
							(start -0.2794 0.1778)
							(mid -0.249642 0.249642)
							(end -0.1778 0.2794)
						)
						(arc
							(start 0.1778 0.2794)
							(mid 0.249642 0.249642)
							(end 0.2794 0.1778)
						)
						(arc
							(start 0.2794 -0.1778)
							(mid 0.249642 -0.249642)
							(end 0.1778 -0.2794)
						)
					)
					(width 0)
					(fill yes)
				)
			)
		)
		(pad "2" smd custom
			(at 0 0.4445 180)
			(size 0.1397 0.1397)
			(layers "F.Cu" "F.Mask" "F.Paste")
			(net "SW_HDD_R20")
			(options
				(clearance outline)
				(anchor circle)
			)
			(primitives
				(gr_poly
					(pts
						(arc
							(start -0.1778 -0.2794)
							(mid -0.249642 -0.249642)
							(end -0.2794 -0.1778)
						)
						(arc
							(start -0.2794 0.1778)
							(mid -0.249642 0.249642)
							(end -0.1778 0.2794)
						)
						(arc
							(start 0.1778 0.2794)
							(mid 0.249642 0.249642)
							(end 0.2794 0.1778)
						)
						(arc
							(start 0.2794 -0.1778)
							(mid 0.249642 -0.249642)
							(end 0.1778 -0.2794)
						)
					)
					(width 0)
					(fill yes)
				)
			)
		)
	)
	(footprint ""
		(layer "F.Cu")
		(at 429.514 -138.938 -90)
		(property "Reference" "Q100"
			(at 0 0 270)
			(layer "F.SilkS")
			(hide yes)
			(effects
				(font
					(size 1.27 1.27)
				)
			)
		)
		(property "Value" "AO4406AL-GP"
			(at -3.707384 -1.5367 270)
			(unlocked yes)
			(layer "F.Fab")
			(hide yes)
			(effects
				(font
					(size 1.016 1.016)
					(thickness 0.1524)
				)
			)
		)
		(property "Device Type" "SOIC8H69"
			(at -3.707384 -3.0607 270)
			(unlocked yes)
			(layer "F.Fab")
			(hide yes)
			(effects
				(font
					(size 1.016 1.016)
					(thickness 0.1524)
				)
			)
		)
		(duplicate_pad_numbers_are_jumpers no)
		(fp_line
			(start -2.6289 3.4417)
			(end -2.6289 1.4732)
			(stroke
				(width 0.381)
				(type default)
			)
			(layer "F.SilkS")
		)
		(fp_line
			(start -2.7432 1.4224)
			(end -2.6416 1.4224)
			(stroke
				(width 0.1524)
				(type default)
			)
			(layer "F.SilkS")
		)
		(fp_line
			(start -2.7432 1.4224)
			(end 2.1336 1.4224)
			(stroke
				(width 0.1524)
				(type default)
			)
			(layer "F.SilkS")
		)
		(fp_line
			(start 2.1336 1.4224)
			(end 2.1336 -1.4224)
			(stroke
				(width 0.1524)
				(type default)
			)
			(layer "F.SilkS")
		)
		(fp_line
			(start -2.1844 -0.0508)
			(end -2.7178 0.508)
			(stroke
				(width 0.1524)
				(type default)
			)
			(layer "F.SilkS")
		)
		(fp_line
			(start -2.7178 -0.508)
			(end -2.1844 -0.0508)
			(stroke
				(width 0.1524)
				(type default)
			)
			(layer "F.SilkS")
		)
		(fp_line
			(start -2.7432 -1.4224)
			(end -2.7432 1.4224)
			(stroke
				(width 0.1524)
				(type default)
			)
			(layer "F.SilkS")
		)
		(fp_line
			(start 2.1336 -1.4224)
			(end -2.7432 -1.4224)
			(stroke
				(width 0.1524)
				(type default)
			)
			(layer "F.SilkS")
		)
		(fp_poly
			(pts
				(xy -2.2098 -1.4224) (xy -2.2098 1.4224) (xy 2.2098 1.4224) (xy 2.2098 -1.4224)
			)
			(stroke
				(width 0)
				(type default)
			)
			(fill yes)
			(layer "F.SilkS")
		)
		(fp_rect
			(start -2.450084 2.999994)
			(end 2.450084 -2.999994)
			(stroke
				(width 0)
				(type default)
			)
			(fill no)
			(layer "F.CrtYd")
		)
		(fp_poly
			(pts
				(xy -2.8194 3.6322) (xy -2.8194 -3.6322) (xy 2.8194 -3.6322) (xy 2.8194 1.18364) (xy 2.450084 1.18364)
				(xy 2.450084 -2.999994) (xy -2.450084 -2.999994) (xy -2.450084 2.999994) (xy 2.450084 2.999994)
				(xy 2.450084 1.18618) (xy 2.8194 1.18618) (xy 2.8194 3.6322)
			)
			(stroke
				(width 0)
				(type default)
			)
			(fill no)
			(layer "F.CrtYd")
		)
		(fp_rect
			(start -2.8194 3.6322)
			(end 2.8194 -3.6322)
			(stroke
				(width 0)
				(type default)
			)
			(fill no)
			(layer "F.Fab")
		)
		(pad "1" smd rect
			(at -1.905 2.54 270)
			(size 0.635 1.651)
			(layers "F.Cu" "F.Mask" "F.Paste")
			(net "P5V_HDD21")
		)
		(pad "2" smd rect
			(at -0.635 2.54 270)
			(size 0.635 1.651)
			(layers "F.Cu" "F.Mask" "F.Paste")
			(net "P5V_HDD21")
		)
		(pad "3" smd rect
			(at 0.635 2.54 270)
			(size 0.635 1.651)
			(layers "F.Cu" "F.Mask" "F.Paste")
			(net "P5V_HDD21")
		)
		(pad "4" smd rect
			(at 1.905 2.54 270)
			(size 0.635 1.651)
			(layers "F.Cu" "F.Mask" "F.Paste")
			(net "SW_HDD_P21")
		)
		(pad "5" smd rect
			(at 1.905 -2.54 270)
			(size 0.635 1.651)
			(layers "F.Cu" "F.Mask" "F.Paste")
			(net "P5V_B_4")
		)
		(pad "6" smd rect
			(at 0.635 -2.54 270)
			(size 0.635 1.651)
			(layers "F.Cu" "F.Mask" "F.Paste")
			(net "P5V_B_4")
		)
		(pad "7" smd rect
			(at -0.635 -2.54 270)
			(size 0.635 1.651)
			(layers "F.Cu" "F.Mask" "F.Paste")
			(net "P5V_B_4")
		)
		(pad "8" smd rect
			(at -1.905 -2.54 270)
			(size 0.635 1.651)
			(layers "F.Cu" "F.Mask" "F.Paste")
			(net "P5V_B_4")
		)
	)
	(footprint ""
		(layer "F.Cu")
		(at 423.577004 -368.935 -90)
		(property "Reference" "R957"
			(at 0 0 270)
			(layer "F.SilkS")
			(hide yes)
			(effects
				(font
					(size 1.27 1.27)
				)
			)
		)
		(property "Value" "10KR2F-2-GP"
			(at 0.064008 -3.993896 270)
			(unlocked yes)
			(layer "F.Fab")
			(hide yes)
			(effects
				(font
					(size 1.016 1.016)
					(thickness 0.1524)
				)
			)
		)
		(property "Device Type" "R402H16"
			(at 0.064008 -5.517896 270)
			(unlocked yes)
			(layer "F.Fab")
			(hide yes)
			(effects
				(font
					(size 1.016 1.016)
					(thickness 0.1524)
				)
			)
		)
		(duplicate_pad_numbers_are_jumpers no)
		(fp_line
			(start -0.508 -0.9398)
			(end -0.508 0.9398)
			(stroke
				(width 0.1524)
				(type default)
			)
			(layer "F.SilkS")
		)
		(fp_line
			(start 0.508 -0.9398)
			(end -0.508 -0.9398)
			(stroke
				(width 0.1524)
				(type default)
			)
			(layer "F.SilkS")
		)
		(fp_rect
			(start -0.508 0.9398)
			(end 0.508 -0.9398)
			(stroke
				(width 0)
				(type default)
			)
			(fill no)
			(layer "F.CrtYd")
		)
		(fp_rect
			(start -0.508 0.9398)
			(end 0.508 -0.9398)
			(stroke
				(width 0)
				(type default)
			)
			(fill no)
			(layer "F.Fab")
		)
		(pad "1" smd custom
			(at 0 -0.4445 270)
			(size 0.1397 0.1397)
			(layers "F.Cu" "F.Mask" "F.Paste")
			(net "GND")
			(options
				(clearance outline)
				(anchor circle)
			)
			(primitives
				(gr_poly
					(pts
						(arc
							(start -0.1778 -0.2794)
							(mid -0.249642 -0.249642)
							(end -0.2794 -0.1778)
						)
						(arc
							(start -0.2794 0.1778)
							(mid -0.249642 0.249642)
							(end -0.1778 0.2794)
						)
						(arc
							(start 0.1778 0.2794)
							(mid 0.249642 0.249642)
							(end 0.2794 0.1778)
						)
						(arc
							(start 0.2794 -0.1778)
							(mid 0.249642 -0.249642)
							(end 0.1778 -0.2794)
						)
					)
					(width 0)
					(fill yes)
				)
			)
		)
		(pad "2" smd custom
			(at 0 0.4445 270)
			(size 0.1397 0.1397)
			(layers "F.Cu" "F.Mask" "F.Paste")
			(net "FANTACH_R3")
			(options
				(clearance outline)
				(anchor circle)
			)
			(primitives
				(gr_poly
					(pts
						(arc
							(start -0.1778 -0.2794)
							(mid -0.249642 -0.249642)
							(end -0.2794 -0.1778)
						)
						(arc
							(start -0.2794 0.1778)
							(mid -0.249642 0.249642)
							(end -0.1778 0.2794)
						)
						(arc
							(start 0.1778 0.2794)
							(mid 0.249642 0.249642)
							(end 0.2794 0.1778)
						)
						(arc
							(start 0.2794 -0.1778)
							(mid 0.249642 -0.249642)
							(end 0.1778 -0.2794)
						)
					)
					(width 0)
					(fill yes)
				)
			)
		)
	)
	(footprint ""
		(layer "F.Cu")
		(at 426.879004 -369.697)
		(property "Reference" "C534"
			(at 0 0 0)
			(layer "F.SilkS")
			(hide yes)
			(effects
				(font
					(size 1.27 1.27)
				)
			)
		)
		(property "Value" "SCD1U25V2KX-2-GP"
			(at 1.1811 -2.7051 0)
			(unlocked yes)
			(layer "F.Fab")
			(hide yes)
			(effects
				(font
					(size 1.016 1.016)
					(thickness 0.1524)
				)
			)
		)
		(property "Device Type" "C402H22"
			(at 1.1811 -4.2291 0)
			(unlocked yes)
			(layer "F.Fab")
			(hide yes)
			(effects
				(font
					(size 1.016 1.016)
					(thickness 0.1524)
				)
			)
		)
		(duplicate_pad_numbers_are_jumpers no)
		(fp_rect
			(start -0.4318 0.9525)
			(end 0.4318 -0.9525)
			(stroke
				(width 0)
				(type default)
			)
			(fill no)
			(layer "F.CrtYd")
		)
		(fp_rect
			(start -0.4318 0.9525)
			(end 0.4318 -0.9525)
			(stroke
				(width 0)
				(type default)
			)
			(fill no)
			(layer "F.Fab")
		)
		(pad "1" smd custom
			(at 0 -0.4445)
			(size 0.1524 0.1524)
			(layers "F.Cu" "F.Mask" "F.Paste")
			(net "FAN_3_TACH0")
			(options
				(clearance outline)
				(anchor circle)
			)
			(primitives
				(gr_poly
					(pts
						(arc
							(start 0.3048 -0.2032)
							(mid 0.275042 -0.275042)
							(end 0.2032 -0.3048)
						)
						(arc
							(start -0.2032 -0.3048)
							(mid -0.275042 -0.275042)
							(end -0.3048 -0.2032)
						)
						(arc
							(start -0.3048 0.2032)
							(mid -0.275042 0.275042)
							(end -0.2032 0.3048)
						)
						(arc
							(start 0.2032 0.3048)
							(mid 0.275042 0.275042)
							(end 0.3048 0.2032)
						)
					)
					(width 0)
					(fill yes)
				)
			)
		)
		(pad "2" smd custom
			(at 0 0.4445)
			(size 0.1524 0.1524)
			(layers "F.Cu" "F.Mask" "F.Paste")
			(net "GND")
			(options
				(clearance outline)
				(anchor circle)
			)
			(primitives
				(gr_poly
					(pts
						(arc
							(start 0.3048 -0.2032)
							(mid 0.275042 -0.275042)
							(end 0.2032 -0.3048)
						)
						(arc
							(start -0.2032 -0.3048)
							(mid -0.275042 -0.275042)
							(end -0.3048 -0.2032)
						)
						(arc
							(start -0.3048 0.2032)
							(mid -0.275042 0.275042)
							(end -0.2032 0.3048)
						)
						(arc
							(start 0.2032 0.3048)
							(mid 0.275042 0.275042)
							(end 0.3048 0.2032)
						)
					)
					(width 0)
					(fill yes)
				)
			)
		)
	)
	(footprint ""
		(layer "F.Cu")
		(at 15.24 -248.158 180)
		(property "Reference" "R914"
			(at 0 0 180)
			(layer "F.SilkS")
			(hide yes)
			(effects
				(font
					(size 1.27 1.27)
				)
			)
		)
		(property "Value" "200KR2F-L-GP"
			(at 0.064008 -3.993896 180)
			(unlocked yes)
			(layer "F.Fab")
			(hide yes)
			(effects
				(font
					(size 1.016 1.016)
					(thickness 0.1524)
				)
			)
		)
		(property "Device Type" "R402H16"
			(at 0.064008 -5.517896 180)
			(unlocked yes)
			(layer "F.Fab")
			(hide yes)
			(effects
				(font
					(size 1.016 1.016)
					(thickness 0.1524)
				)
			)
		)
		(duplicate_pad_numbers_are_jumpers no)
		(fp_line
			(start 0.508 -0.9398)
			(end -0.508 -0.9398)
			(stroke
				(width 0.1524)
				(type default)
			)
			(layer "F.SilkS")
		)
		(fp_line
			(start -0.508 -0.9398)
			(end -0.508 0.9398)
			(stroke
				(width 0.1524)
				(type default)
			)
			(layer "F.SilkS")
		)
		(fp_rect
			(start -0.508 0.9398)
			(end 0.508 -0.9398)
			(stroke
				(width 0)
				(type default)
			)
			(fill no)
			(layer "F.CrtYd")
		)
		(fp_rect
			(start -0.508 0.9398)
			(end 0.508 -0.9398)
			(stroke
				(width 0)
				(type default)
			)
			(fill no)
			(layer "F.Fab")
		)
		(pad "1" smd custom
			(at 0 -0.4445 180)
			(size 0.1397 0.1397)
			(layers "F.Cu" "F.Mask" "F.Paste")
			(net "SW_HDD_R0")
			(options
				(clearance outline)
				(anchor circle)
			)
			(primitives
				(gr_poly
					(pts
						(arc
							(start -0.1778 -0.2794)
							(mid -0.249642 -0.249642)
							(end -0.2794 -0.1778)
						)
						(arc
							(start -0.2794 0.1778)
							(mid -0.249642 0.249642)
							(end -0.1778 0.2794)
						)
						(arc
							(start 0.1778 0.2794)
							(mid 0.249642 0.249642)
							(end 0.2794 0.1778)
						)
						(arc
							(start 0.2794 -0.1778)
							(mid 0.249642 -0.249642)
							(end 0.1778 -0.2794)
						)
					)
					(width 0)
					(fill yes)
				)
			)
		)
		(pad "2" smd custom
			(at 0 0.4445 180)
			(size 0.1397 0.1397)
			(layers "F.Cu" "F.Mask" "F.Paste")
			(net "SW_HDD_N0")
			(options
				(clearance outline)
				(anchor circle)
			)
			(primitives
				(gr_poly
					(pts
						(arc
							(start -0.1778 -0.2794)
							(mid -0.249642 -0.249642)
							(end -0.2794 -0.1778)
						)
						(arc
							(start -0.2794 0.1778)
							(mid -0.249642 0.249642)
							(end -0.1778 0.2794)
						)
						(arc
							(start 0.1778 0.2794)
							(mid 0.249642 0.249642)
							(end 0.2794 0.1778)
						)
						(arc
							(start 0.2794 -0.1778)
							(mid 0.249642 -0.249642)
							(end 0.1778 -0.2794)
						)
					)
					(width 0)
					(fill yes)
				)
			)
		)
	)
	(footprint ""
		(layer "F.Cu")
		(at 143.002 -253.111 90)
		(property "Reference" "R227"
			(at 0 0 90)
			(layer "F.SilkS")
			(hide yes)
			(effects
				(font
					(size 1.27 1.27)
				)
			)
		)
		(property "Value" "4K7R2J-2-GP"
			(at 0.064008 -3.993896 90)
			(unlocked yes)
			(layer "F.Fab")
			(hide yes)
			(effects
				(font
					(size 1.016 1.016)
					(thickness 0.1524)
				)
			)
		)
		(property "Device Type" "R402H16"
			(at 0.064008 -5.517896 90)
			(unlocked yes)
			(layer "F.Fab")
			(hide yes)
			(effects
				(font
					(size 1.016 1.016)
					(thickness 0.1524)
				)
			)
		)
		(duplicate_pad_numbers_are_jumpers no)
		(fp_line
			(start 0.508 -0.9398)
			(end -0.508 -0.9398)
			(stroke
				(width 0.1524)
				(type default)
			)
			(layer "F.SilkS")
		)
		(fp_line
			(start -0.508 -0.9398)
			(end -0.508 0.9398)
			(stroke
				(width 0.1524)
				(type default)
			)
			(layer "F.SilkS")
		)
		(fp_rect
			(start -0.508 0.9398)
			(end 0.508 -0.9398)
			(stroke
				(width 0)
				(type default)
			)
			(fill no)
			(layer "F.CrtYd")
		)
		(fp_rect
			(start -0.508 0.9398)
			(end 0.508 -0.9398)
			(stroke
				(width 0)
				(type default)
			)
			(fill no)
			(layer "F.Fab")
		)
		(pad "1" smd custom
			(at 0 -0.4445 90)
			(size 0.1397 0.1397)
			(layers "F.Cu" "F.Mask" "F.Paste")
			(net "P12V_B")
			(options
				(clearance outline)
				(anchor circle)
			)
			(primitives
				(gr_poly
					(pts
						(arc
							(start -0.1778 -0.2794)
							(mid -0.249642 -0.249642)
							(end -0.2794 -0.1778)
						)
						(arc
							(start -0.2794 0.1778)
							(mid -0.249642 0.249642)
							(end -0.1778 0.2794)
						)
						(arc
							(start 0.1778 0.2794)
							(mid 0.249642 0.249642)
							(end 0.2794 0.1778)
						)
						(arc
							(start 0.2794 -0.1778)
							(mid 0.249642 -0.249642)
							(end 0.1778 -0.2794)
						)
					)
					(width 0)
					(fill yes)
				)
			)
		)
		(pad "2" smd custom
			(at 0 0.4445 90)
			(size 0.1397 0.1397)
			(layers "F.Cu" "F.Mask" "F.Paste")
			(net "SW_HDD_P4")
			(options
				(clearance outline)
				(anchor circle)
			)
			(primitives
				(gr_poly
					(pts
						(arc
							(start -0.1778 -0.2794)
							(mid -0.249642 -0.249642)
							(end -0.2794 -0.1778)
						)
						(arc
							(start -0.2794 0.1778)
							(mid -0.249642 0.249642)
							(end -0.1778 0.2794)
						)
						(arc
							(start 0.1778 0.2794)
							(mid 0.249642 0.249642)
							(end 0.2794 0.1778)
						)
						(arc
							(start 0.2794 -0.1778)
							(mid 0.249642 -0.249642)
							(end 0.1778 -0.2794)
						)
					)
					(width 0)
					(fill yes)
				)
			)
		)
	)
	(footprint ""
		(layer "F.Cu")
		(at 145.161 -265.684 90)
		(property "Reference" "R224"
			(at 0 0 90)
			(layer "F.SilkS")
			(hide yes)
			(effects
				(font
					(size 1.27 1.27)
				)
			)
		)
		(property "Value" "2R6F-GP"
			(at -0.0508 -4.8514 90)
			(unlocked yes)
			(layer "F.Fab")
			(hide yes)
			(effects
				(font
					(size 1.016 1.016)
					(thickness 0.1524)
				)
			)
		)
		(property "Device Type" "R1206H26"
			(at 0 -6.3754 90)
			(unlocked yes)
			(layer "F.Fab")
			(hide yes)
			(effects
				(font
					(size 1.016 1.016)
					(thickness 0.1524)
				)
			)
		)
		(duplicate_pad_numbers_are_jumpers no)
		(fp_line
			(start 1.016 -2.2352)
			(end 1.016 2.2352)
			(stroke
				(width 0.1524)
				(type default)
			)
			(layer "F.SilkS")
		)
		(fp_line
			(start -1.016 -2.2352)
			(end 1.016 -2.2352)
			(stroke
				(width 0.1524)
				(type default)
			)
			(layer "F.SilkS")
		)
		(fp_line
			(start 1.016 2.2352)
			(end -1.016 2.2352)
			(stroke
				(width 0.1524)
				(type default)
			)
			(layer "F.SilkS")
		)
		(fp_line
			(start -1.016 2.2352)
			(end -1.016 -2.2352)
			(stroke
				(width 0.1524)
				(type default)
			)
			(layer "F.SilkS")
		)
		(fp_rect
			(start -1.0922 2.3114)
			(end 1.0922 -2.3114)
			(stroke
				(width 0)
				(type default)
			)
			(fill no)
			(layer "F.CrtYd")
		)
		(fp_poly
			(pts
				(xy -1.0922 -2.3114) (xy 1.0922 -2.3114) (xy 1.0922 2.3114) (xy -1.0922 2.3114)
			)
			(stroke
				(width 0)
				(type default)
			)
			(fill no)
			(layer "F.Fab")
		)
		(pad "1" smd rect
			(at 0 -1.397 90)
			(size 1.651 1.27)
			(layers "F.Cu" "F.Mask" "F.Paste")
			(net "P12V_HDD4")
		)
		(pad "2" smd rect
			(at 0 1.397 90)
			(size 1.651 1.27)
			(layers "F.Cu" "F.Mask" "F.Paste")
			(net "12V_PRE_4")
		)
	)
	(footprint ""
		(layer "F.Cu")
		(at 180.6956 -133.4262 -90)
		(property "Reference" "R469"
			(at 0 0 270)
			(layer "F.SilkS")
			(hide yes)
			(effects
				(font
					(size 1.27 1.27)
				)
			)
		)
		(property "Value" "1KR2F-3-GP"
			(at 0.064008 -3.993896 270)
			(unlocked yes)
			(layer "F.Fab")
			(hide yes)
			(effects
				(font
					(size 1.016 1.016)
					(thickness 0.1524)
				)
			)
		)
		(property "Device Type" "R402H16"
			(at 0.064008 -5.517896 270)
			(unlocked yes)
			(layer "F.Fab")
			(hide yes)
			(effects
				(font
					(size 1.016 1.016)
					(thickness 0.1524)
				)
			)
		)
		(duplicate_pad_numbers_are_jumpers no)
		(fp_line
			(start -0.508 -0.9398)
			(end -0.508 0.9398)
			(stroke
				(width 0.1524)
				(type default)
			)
			(layer "F.SilkS")
		)
		(fp_line
			(start 0.508 -0.9398)
			(end -0.508 -0.9398)
			(stroke
				(width 0.1524)
				(type default)
			)
			(layer "F.SilkS")
		)
		(fp_rect
			(start -0.508 0.9398)
			(end 0.508 -0.9398)
			(stroke
				(width 0)
				(type default)
			)
			(fill no)
			(layer "F.CrtYd")
		)
		(fp_rect
			(start -0.508 0.9398)
			(end 0.508 -0.9398)
			(stroke
				(width 0)
				(type default)
			)
			(fill no)
			(layer "F.Fab")
		)
		(pad "1" smd custom
			(at 0 -0.4445 270)
			(size 0.1397 0.1397)
			(layers "F.Cu" "F.Mask" "F.Paste")
			(net "P3V3_STBY_B")
			(options
				(clearance outline)
				(anchor circle)
			)
			(primitives
				(gr_poly
					(pts
						(arc
							(start -0.1778 -0.2794)
							(mid -0.249642 -0.249642)
							(end -0.2794 -0.1778)
						)
						(arc
							(start -0.2794 0.1778)
							(mid -0.249642 0.249642)
							(end -0.1778 0.2794)
						)
						(arc
							(start 0.1778 0.2794)
							(mid 0.249642 0.249642)
							(end 0.2794 0.1778)
						)
						(arc
							(start 0.2794 -0.1778)
							(mid 0.249642 -0.249642)
							(end 0.1778 -0.2794)
						)
					)
					(width 0)
					(fill yes)
				)
			)
		)
		(pad "2" smd custom
			(at 0 0.4445 270)
			(size 0.1397 0.1397)
			(layers "F.Cu" "F.Mask" "F.Paste")
			(net "SW_PWR_R_HDD17")
			(options
				(clearance outline)
				(anchor circle)
			)
			(primitives
				(gr_poly
					(pts
						(arc
							(start -0.1778 -0.2794)
							(mid -0.249642 -0.249642)
							(end -0.2794 -0.1778)
						)
						(arc
							(start -0.2794 0.1778)
							(mid -0.249642 0.249642)
							(end -0.1778 0.2794)
						)
						(arc
							(start 0.1778 0.2794)
							(mid 0.249642 0.249642)
							(end 0.2794 0.1778)
						)
						(arc
							(start 0.2794 -0.1778)
							(mid 0.249642 -0.249642)
							(end 0.1778 -0.2794)
						)
					)
					(width 0)
					(fill yes)
				)
			)
		)
	)
	(footprint ""
		(layer "F.Cu")
		(at 260.051042 -94.953836 180)
		(property "Reference" "C2"
			(at 0 0 180)
			(layer "F.SilkS")
			(hide yes)
			(effects
				(font
					(size 1.27 1.27)
				)
			)
		)
		(property "Value" "SC22U25V6KX-2-GP-U"
			(at -2.860802 -5.279644 180)
			(unlocked yes)
			(layer "F.Fab")
			(hide yes)
			(effects
				(font
					(size 1.016 1.016)
					(thickness 0.1524)
				)
			)
		)
		(property "Device Type" "C1206-TO0D3H75"
			(at -2.860802 -6.803644 180)
			(unlocked yes)
			(layer "F.Fab")
			(hide yes)
			(effects
				(font
					(size 1.016 1.016)
					(thickness 0.1524)
				)
			)
		)
		(duplicate_pad_numbers_are_jumpers no)
		(fp_line
			(start 1.3081 2.3749)
			(end -1.3081 2.3749)
			(stroke
				(width 0.1524)
				(type default)
			)
			(layer "F.SilkS")
		)
		(fp_line
			(start 1.3081 -2.3749)
			(end 1.3081 2.3749)
			(stroke
				(width 0.1524)
				(type default)
			)
			(layer "F.SilkS")
		)
		(fp_line
			(start -1.3081 2.3749)
			(end -1.3081 -2.3749)
			(stroke
				(width 0.1524)
				(type default)
			)
			(layer "F.SilkS")
		)
		(fp_line
			(start -1.3081 -2.3749)
			(end 1.3081 -2.3749)
			(stroke
				(width 0.1524)
				(type default)
			)
			(layer "F.SilkS")
		)
		(fp_rect
			(start -0.8001 1.6002)
			(end 0.8001 -1.6002)
			(stroke
				(width 0)
				(type default)
			)
			(fill no)
			(layer "F.CrtYd")
		)
		(fp_poly
			(pts
				(xy -1.5621 2.4511) (xy -1.5621 1.6002) (xy 0.8001 1.6002) (xy 0.8001 -1.6002) (xy -0.8001 -1.6002)
				(xy -0.8001 1.5875) (xy -1.5621 1.5875) (xy -1.5621 -2.4511) (xy 1.5621 -2.4511) (xy 1.5621 2.4511)
			)
			(stroke
				(width 0)
				(type default)
			)
			(fill no)
			(layer "F.CrtYd")
		)
		(fp_rect
			(start -1.5621 2.4511)
			(end 1.5621 -2.4511)
			(stroke
				(width 0)
				(type default)
			)
			(fill no)
			(layer "F.Fab")
		)
		(pad "1" smd rect
			(at 0 -1.392936 180)
			(size 2.1082 1.4478)
			(layers "F.Cu" "F.Mask" "F.Paste")
			(net "P12V_B")
		)
		(pad "2" smd rect
			(at 0 1.392936 180)
			(size 2.1082 1.4478)
			(layers "F.Cu" "F.Mask" "F.Paste")
			(net "GND")
		)
	)
	(footprint ""
		(layer "F.Cu")
		(at 190.8302 -262.128 90)
		(property "Reference" "C102"
			(at 0 0 90)
			(layer "F.SilkS")
			(hide yes)
			(effects
				(font
					(size 1.27 1.27)
				)
			)
		)
		(property "Value" "SCD01U50V2KX-1GP"
			(at 1.1811 -2.7051 90)
			(unlocked yes)
			(layer "F.Fab")
			(hide yes)
			(effects
				(font
					(size 1.016 1.016)
					(thickness 0.1524)
				)
			)
		)
		(property "Device Type" "C402H22"
			(at 1.1811 -4.2291 90)
			(unlocked yes)
			(layer "F.Fab")
			(hide yes)
			(effects
				(font
					(size 1.016 1.016)
					(thickness 0.1524)
				)
			)
		)
		(duplicate_pad_numbers_are_jumpers no)
		(fp_rect
			(start -0.4318 0.9525)
			(end 0.4318 -0.9525)
			(stroke
				(width 0)
				(type default)
			)
			(fill no)
			(layer "F.CrtYd")
		)
		(fp_rect
			(start -0.4318 0.9525)
			(end 0.4318 -0.9525)
			(stroke
				(width 0)
				(type default)
			)
			(fill no)
			(layer "F.Fab")
		)
		(pad "1" smd custom
			(at 0 -0.4445 90)
			(size 0.1524 0.1524)
			(layers "F.Cu" "F.Mask" "F.Paste")
			(net "HDD_PRSNT_5")
			(options
				(clearance outline)
				(anchor circle)
			)
			(primitives
				(gr_poly
					(pts
						(arc
							(start 0.3048 -0.2032)
							(mid 0.275042 -0.275042)
							(end 0.2032 -0.3048)
						)
						(arc
							(start -0.2032 -0.3048)
							(mid -0.275042 -0.275042)
							(end -0.3048 -0.2032)
						)
						(arc
							(start -0.3048 0.2032)
							(mid -0.275042 0.275042)
							(end -0.2032 0.3048)
						)
						(arc
							(start 0.2032 0.3048)
							(mid 0.275042 0.275042)
							(end 0.3048 0.2032)
						)
					)
					(width 0)
					(fill yes)
				)
			)
		)
		(pad "2" smd custom
			(at 0 0.4445 90)
			(size 0.1524 0.1524)
			(layers "F.Cu" "F.Mask" "F.Paste")
			(net "GND")
			(options
				(clearance outline)
				(anchor circle)
			)
			(primitives
				(gr_poly
					(pts
						(arc
							(start 0.3048 -0.2032)
							(mid 0.275042 -0.275042)
							(end 0.2032 -0.3048)
						)
						(arc
							(start -0.2032 -0.3048)
							(mid -0.275042 -0.275042)
							(end -0.3048 -0.2032)
						)
						(arc
							(start -0.3048 0.2032)
							(mid -0.275042 0.275042)
							(end -0.2032 0.3048)
						)
						(arc
							(start 0.2032 0.3048)
							(mid 0.275042 0.275042)
							(end 0.3048 0.2032)
						)
					)
					(width 0)
					(fill yes)
				)
			)
		)
	)
	(footprint ""
		(layer "F.Cu")
		(at 181.3052 -372.6942 -90)
		(property "Reference" "R990"
			(at 0 0 270)
			(layer "F.SilkS")
			(hide yes)
			(effects
				(font
					(size 1.27 1.27)
				)
			)
		)
		(property "Value" "10KR2J-3-GP"
			(at 0.064008 -3.993896 270)
			(unlocked yes)
			(layer "F.Fab")
			(hide yes)
			(effects
				(font
					(size 1.016 1.016)
					(thickness 0.1524)
				)
			)
		)
		(property "Device Type" "R402H16"
			(at 0.064008 -5.517896 270)
			(unlocked yes)
			(layer "F.Fab")
			(hide yes)
			(effects
				(font
					(size 1.016 1.016)
					(thickness 0.1524)
				)
			)
		)
		(duplicate_pad_numbers_are_jumpers no)
		(fp_line
			(start -0.508 -0.9398)
			(end -0.508 0.9398)
			(stroke
				(width 0.1524)
				(type default)
			)
			(layer "F.SilkS")
		)
		(fp_line
			(start 0.508 -0.9398)
			(end -0.508 -0.9398)
			(stroke
				(width 0.1524)
				(type default)
			)
			(layer "F.SilkS")
		)
		(fp_rect
			(start -0.508 0.9398)
			(end 0.508 -0.9398)
			(stroke
				(width 0)
				(type default)
			)
			(fill no)
			(layer "F.CrtYd")
		)
		(fp_rect
			(start -0.508 0.9398)
			(end 0.508 -0.9398)
			(stroke
				(width 0)
				(type default)
			)
			(fill no)
			(layer "F.Fab")
		)
		(pad "1" smd custom
			(at 0 -0.4445 270)
			(size 0.1397 0.1397)
			(layers "F.Cu" "F.Mask" "F.Paste")
			(net "GND")
			(options
				(clearance outline)
				(anchor circle)
			)
			(primitives
				(gr_poly
					(pts
						(arc
							(start -0.1778 -0.2794)
							(mid -0.249642 -0.249642)
							(end -0.2794 -0.1778)
						)
						(arc
							(start -0.2794 0.1778)
							(mid -0.249642 0.249642)
							(end -0.1778 0.2794)
						)
						(arc
							(start 0.1778 0.2794)
							(mid 0.249642 0.249642)
							(end 0.2794 0.1778)
						)
						(arc
							(start 0.2794 -0.1778)
							(mid 0.249642 -0.249642)
							(end 0.1778 -0.2794)
						)
					)
					(width 0)
					(fill yes)
				)
			)
		)
		(pad "2" smd custom
			(at 0 0.4445 270)
			(size 0.1397 0.1397)
			(layers "F.Cu" "F.Mask" "F.Paste")
			(net "MB0_RETRY_R")
			(options
				(clearance outline)
				(anchor circle)
			)
			(primitives
				(gr_poly
					(pts
						(arc
							(start -0.1778 -0.2794)
							(mid -0.249642 -0.249642)
							(end -0.2794 -0.1778)
						)
						(arc
							(start -0.2794 0.1778)
							(mid -0.249642 0.249642)
							(end -0.1778 0.2794)
						)
						(arc
							(start 0.1778 0.2794)
							(mid 0.249642 0.249642)
							(end 0.2794 0.1778)
						)
						(arc
							(start 0.2794 -0.1778)
							(mid 0.249642 -0.249642)
							(end 0.1778 -0.2794)
						)
					)
					(width 0)
					(fill yes)
				)
			)
		)
	)
	(footprint ""
		(layer "F.Cu")
		(at 237.363 -351.0534)
		(property "Reference" "D46"
			(at 0 0 0)
			(layer "F.SilkS")
			(hide yes)
			(effects
				(font
					(size 1.27 1.27)
				)
			)
		)
		(property "Value" "SMCJ14A-13-F-GP"
			(at -4.445 1.1684 0)
			(unlocked yes)
			(layer "F.Fab")
			(hide yes)
			(effects
				(font
					(size 1.016 1.016)
					(thickness 0.1524)
				)
			)
		)
		(property "Device Type" "D795930AKH104"
			(at -4.445 -0.3556 0)
			(unlocked yes)
			(layer "F.Fab")
			(hide yes)
			(effects
				(font
					(size 1.016 1.016)
					(thickness 0.1524)
				)
			)
		)
		(duplicate_pad_numbers_are_jumpers no)
		(fp_line
			(start -3.2004 -4.8641)
			(end -3.2004 4.8641)
			(stroke
				(width 0.1524)
				(type default)
			)
			(layer "F.SilkS")
		)
		(fp_line
			(start -3.2004 4.8641)
			(end 3.2004 4.8641)
			(stroke
				(width 0.1524)
				(type default)
			)
			(layer "F.SilkS")
		)
		(fp_line
			(start 3.2004 -4.8641)
			(end -3.2004 -4.8641)
			(stroke
				(width 0.1524)
				(type default)
			)
			(layer "F.SilkS")
		)
		(fp_line
			(start 3.2004 4.8641)
			(end 3.2004 -4.8641)
			(stroke
				(width 0.1524)
				(type default)
			)
			(layer "F.SilkS")
		)
		(fp_line
			(start 3.2004 5.0419)
			(end -3.2004 5.0419)
			(stroke
				(width 0.508)
				(type default)
			)
			(layer "F.SilkS")
		)
		(fp_poly
			(pts
				(xy -2.9464 3.429) (xy -1.4859 3.429) (xy -1.4859 3.9751) (xy 1.4859 3.9751) (xy 1.4859 3.429) (xy 2.9464 3.429)
				(xy 2.9464 -3.429) (xy 1.4859 -3.429) (xy 1.4859 -3.9751) (xy -1.4859 -3.9751) (xy -1.4859 -3.429)
				(xy -2.9464 -3.429)
			)
			(stroke
				(width 0)
				(type default)
			)
			(fill no)
			(layer "F.CrtYd")
		)
		(fp_poly
			(pts
				(xy -3.4544 4.9403) (xy -3.4544 -4.9403) (xy 3.4544 -4.9403) (xy 3.4544 -3.429) (xy 1.4859 -3.429)
				(xy 1.4859 -3.9751) (xy -1.4859 -3.9751) (xy -1.4859 -3.429) (xy -2.9464 -3.429) (xy -2.9464 3.429)
				(xy -1.4859 3.429) (xy -1.4859 3.9751) (xy 1.4859 3.9751) (xy 1.4859 3.429) (xy 2.9464 3.429) (xy 2.9464 -3.4163)
				(xy 3.4544 -3.4163) (xy 3.4544 4.9403)
			)
			(stroke
				(width 0)
				(type default)
			)
			(fill no)
			(layer "F.CrtYd")
		)
		(fp_rect
			(start -3.4544 4.9403)
			(end 3.4544 -4.9403)
			(stroke
				(width 0)
				(type default)
			)
			(fill no)
			(layer "F.Fab")
		)
		(pad "A" smd rect
			(at 0 -3.592068)
			(size 3.2258 2.032)
			(layers "F.Cu" "F.Mask" "F.Paste")
			(net "GND")
		)
		(pad "K" smd rect
			(at 0 3.592068)
			(size 3.2258 2.032)
			(layers "F.Cu" "F.Mask" "F.Paste")
			(net "P12V_IN")
		)
	)
	(footprint ""
		(layer "F.Cu")
		(at 409.194 -214.249)
		(property "Reference" "R348"
			(at 0 0 0)
			(layer "F.SilkS")
			(hide yes)
			(effects
				(font
					(size 1.27 1.27)
				)
			)
		)
		(property "Value" "130R3F-GP"
			(at -0.0254 -2.5146 0)
			(unlocked yes)
			(layer "F.Fab")
			(hide yes)
			(effects
				(font
					(size 1.016 1.016)
					(thickness 0.1524)
				)
			)
		)
		(property "Device Type" "R603H22"
			(at -0.0254 -4.0386 0)
			(unlocked yes)
			(layer "F.Fab")
			(hide yes)
			(effects
				(font
					(size 1.016 1.016)
					(thickness 0.1524)
				)
			)
		)
		(duplicate_pad_numbers_are_jumpers no)
		(fp_line
			(start -0.4826 0)
			(end -0.2032 0)
			(stroke
				(width 0.2032)
				(type default)
			)
			(layer "F.SilkS")
		)
		(fp_line
			(start 0.2032 0)
			(end 0.4826 0)
			(stroke
				(width 0.2032)
				(type default)
			)
			(layer "F.SilkS")
		)
		(fp_rect
			(start -0.5842 1.3335)
			(end 0.5842 -1.3335)
			(stroke
				(width 0)
				(type default)
			)
			(fill no)
			(layer "F.CrtYd")
		)
		(fp_rect
			(start -0.5842 1.3335)
			(end 0.5842 -1.3335)
			(stroke
				(width 0)
				(type default)
			)
			(fill no)
			(layer "F.Fab")
		)
		(pad "1" smd custom
			(at 0 -0.762)
			(size 0.2159 0.2159)
			(layers "F.Cu" "F.Mask" "F.Paste")
			(net "P5V_B_3")
			(options
				(clearance outline)
				(anchor circle)
			)
			(primitives
				(gr_poly
					(pts
						(arc
							(start -0.3302 -0.4318)
							(mid -0.402042 -0.402042)
							(end -0.4318 -0.3302)
						)
						(arc
							(start -0.4318 0.3302)
							(mid -0.402042 0.402042)
							(end -0.3302 0.4318)
						)
						(arc
							(start 0.3302 0.4318)
							(mid 0.402042 0.402042)
							(end 0.4318 0.3302)
						)
						(arc
							(start 0.4318 -0.3302)
							(mid 0.402042 -0.402042)
							(end 0.3302 -0.4318)
						)
					)
					(width 0)
					(fill yes)
				)
			)
		)
		(pad "2" smd custom
			(at 0 0.762)
			(size 0.2159 0.2159)
			(layers "F.Cu" "F.Mask" "F.Paste")
			(net "FLT_HDD9")
			(options
				(clearance outline)
				(anchor circle)
			)
			(primitives
				(gr_poly
					(pts
						(arc
							(start -0.3302 -0.4318)
							(mid -0.402042 -0.402042)
							(end -0.4318 -0.3302)
						)
						(arc
							(start -0.4318 0.3302)
							(mid -0.402042 0.402042)
							(end -0.3302 0.4318)
						)
						(arc
							(start 0.3302 0.4318)
							(mid 0.402042 0.402042)
							(end 0.4318 0.3302)
						)
						(arc
							(start 0.4318 -0.3302)
							(mid 0.402042 -0.402042)
							(end 0.3302 -0.4318)
						)
					)
					(width 0)
					(fill yes)
				)
			)
		)
	)
	(footprint ""
		(layer "F.Cu")
		(at 192.035684 -129.99085 90)
		(property "Reference" "VIA35"
			(at 0 0 90)
			(layer "F.SilkS")
			(hide yes)
			(effects
				(font
					(size 1.27 1.27)
				)
			)
		)
		(property "Value" "100OHM-8L-2D36MM-L18-GP"
			(at 3.8989 0.5715 90)
			(unlocked yes)
			(layer "F.Fab")
			(hide yes)
			(effects
				(font
					(size 1.016 1.016)
					(thickness 0.1524)
				)
			)
		)
		(property "Device Type" "VIA-PCIE-4P-414097"
			(at 3.8989 -0.9525 90)
			(unlocked yes)
			(layer "F.Fab")
			(hide yes)
			(effects
				(font
					(size 1.016 1.016)
					(thickness 0.1524)
				)
			)
		)
		(duplicate_pad_numbers_are_jumpers no)
		(fp_rect
			(start -2.0701 0.4826)
			(end 2.0701 -0.4826)
			(stroke
				(width 0)
				(type default)
			)
			(fill no)
			(layer "F.CrtYd")
		)
		(fp_rect
			(start -2.0701 0.4826)
			(end 2.0701 -0.4826)
			(stroke
				(width 0)
				(type default)
			)
			(fill no)
			(layer "F.Fab")
		)
		(pad "1" thru_hole circle
			(at -1.5875 0 90)
			(size 0.508 0.508)
			(drill 0.254)
			(layers "*.Cu" "*.Mask")
			(remove_unused_layers no)
			(net "GND")
			(clearance 0.2286)
			(thermal_gap 0.2286)
		)
		(pad "2" thru_hole circle
			(at -0.5715 0 90)
			(size 0.508 0.508)
			(drill 0.254)
			(layers "*.Cu" "*.Mask")
			(remove_unused_layers no)
			(net "PHY_SCC_B_TO_DRV_B_17_DP")
			(clearance 0.2286)
			(thermal_gap 0.2286)
		)
		(pad "3" thru_hole circle
			(at 0.5715 0 90)
			(size 0.508 0.508)
			(drill 0.254)
			(layers "*.Cu" "*.Mask")
			(remove_unused_layers no)
			(net "PHY_SCC_B_TO_DRV_B_17_DN")
			(clearance 0.2286)
			(thermal_gap 0.2286)
		)
		(pad "4" thru_hole circle
			(at 1.5875 0 90)
			(size 0.508 0.508)
			(drill 0.254)
			(layers "*.Cu" "*.Mask")
			(remove_unused_layers no)
			(net "GND")
			(clearance 0.2286)
			(thermal_gap 0.2286)
		)
	)
	(footprint ""
		(layer "F.Cu")
		(at 171.831 -362.331)
		(property "Reference" "C547"
			(at 0 0 0)
			(layer "F.SilkS")
			(hide yes)
			(effects
				(font
					(size 1.27 1.27)
				)
			)
		)
		(property "Value" "SC1U16V3KX-5GP"
			(at 0 -2.8194 0)
			(unlocked yes)
			(layer "F.Fab")
			(hide yes)
			(effects
				(font
					(size 1.016 1.016)
					(thickness 0.1524)
				)
			)
		)
		(property "Device Type" "C603H36"
			(at 0 -4.3434 0)
			(unlocked yes)
			(layer "F.Fab")
			(hide yes)
			(effects
				(font
					(size 1.016 1.016)
					(thickness 0.1524)
				)
			)
		)
		(duplicate_pad_numbers_are_jumpers no)
		(fp_line
			(start 0.508 0)
			(end -0.508 0)
			(stroke
				(width 0.2032)
				(type default)
			)
			(layer "F.SilkS")
		)
		(fp_rect
			(start -0.5842 1.3335)
			(end 0.5842 -1.3335)
			(stroke
				(width 0)
				(type default)
			)
			(fill no)
			(layer "F.CrtYd")
		)
		(fp_rect
			(start -0.5842 1.3335)
			(end 0.5842 -1.3335)
			(stroke
				(width 0)
				(type default)
			)
			(fill no)
			(layer "F.Fab")
		)
		(pad "1" smd custom
			(at 0 -0.762)
			(size 0.2159 0.2159)
			(layers "F.Cu" "F.Mask" "F.Paste")
			(net "MB0_VCAP_R")
			(options
				(clearance outline)
				(anchor circle)
			)
			(primitives
				(gr_poly
					(pts
						(arc
							(start -0.3302 -0.4318)
							(mid -0.402042 -0.402042)
							(end -0.4318 -0.3302)
						)
						(arc
							(start -0.4318 0.3302)
							(mid -0.402042 0.402042)
							(end -0.3302 0.4318)
						)
						(arc
							(start 0.3302 0.4318)
							(mid 0.402042 0.402042)
							(end 0.4318 0.3302)
						)
						(arc
							(start 0.4318 -0.3302)
							(mid 0.402042 -0.402042)
							(end 0.3302 -0.4318)
						)
					)
					(width 0)
					(fill yes)
				)
			)
		)
		(pad "2" smd custom
			(at 0 0.762)
			(size 0.2159 0.2159)
			(layers "F.Cu" "F.Mask" "F.Paste")
			(net "AGND_CURRENT_MON")
			(options
				(clearance outline)
				(anchor circle)
			)
			(primitives
				(gr_poly
					(pts
						(arc
							(start -0.3302 -0.4318)
							(mid -0.402042 -0.402042)
							(end -0.4318 -0.3302)
						)
						(arc
							(start -0.4318 0.3302)
							(mid -0.402042 0.402042)
							(end -0.3302 0.4318)
						)
						(arc
							(start 0.3302 0.4318)
							(mid 0.402042 0.402042)
							(end 0.4318 0.3302)
						)
						(arc
							(start 0.4318 -0.3302)
							(mid 0.402042 -0.402042)
							(end 0.3302 -0.4318)
						)
					)
					(width 0)
					(fill yes)
				)
			)
		)
	)
	(footprint ""
		(layer "F.Cu")
		(at 242.062 -215.265 180)
		(property "Reference" "R85"
			(at 0 0 180)
			(layer "F.SilkS")
			(hide yes)
			(effects
				(font
					(size 1.27 1.27)
				)
			)
		)
		(property "Value" "4K7R2F-GP"
			(at 0.064008 -3.993896 180)
			(unlocked yes)
			(layer "F.Fab")
			(hide yes)
			(effects
				(font
					(size 1.016 1.016)
					(thickness 0.1524)
				)
			)
		)
		(property "Device Type" "R402H16"
			(at 0.064008 -5.517896 180)
			(unlocked yes)
			(layer "F.Fab")
			(hide yes)
			(effects
				(font
					(size 1.016 1.016)
					(thickness 0.1524)
				)
			)
		)
		(duplicate_pad_numbers_are_jumpers no)
		(fp_line
			(start 0.508 -0.9398)
			(end -0.508 -0.9398)
			(stroke
				(width 0.1524)
				(type default)
			)
			(layer "F.SilkS")
		)
		(fp_line
			(start -0.508 -0.9398)
			(end -0.508 0.9398)
			(stroke
				(width 0.1524)
				(type default)
			)
			(layer "F.SilkS")
		)
		(fp_rect
			(start -0.508 0.9398)
			(end 0.508 -0.9398)
			(stroke
				(width 0)
				(type default)
			)
			(fill no)
			(layer "F.CrtYd")
		)
		(fp_rect
			(start -0.508 0.9398)
			(end 0.508 -0.9398)
			(stroke
				(width 0)
				(type default)
			)
			(fill no)
			(layer "F.Fab")
		)
		(pad "1" smd custom
			(at 0 -0.4445 180)
			(size 0.1397 0.1397)
			(layers "F.Cu" "F.Mask" "F.Paste")
			(net "P3V3_STBY_B")
			(options
				(clearance outline)
				(anchor circle)
			)
			(primitives
				(gr_poly
					(pts
						(arc
							(start -0.1778 -0.2794)
							(mid -0.249642 -0.249642)
							(end -0.2794 -0.1778)
						)
						(arc
							(start -0.2794 0.1778)
							(mid -0.249642 0.249642)
							(end -0.1778 0.2794)
						)
						(arc
							(start 0.1778 0.2794)
							(mid 0.249642 0.249642)
							(end 0.2794 0.1778)
						)
						(arc
							(start 0.2794 -0.1778)
							(mid 0.249642 -0.249642)
							(end 0.1778 -0.2794)
						)
					)
					(width 0)
					(fill yes)
				)
			)
		)
		(pad "2" smd custom
			(at 0 0.4445 180)
			(size 0.1397 0.1397)
			(layers "F.Cu" "F.Mask" "F.Paste")
			(net "IO_EXP3_A1")
			(options
				(clearance outline)
				(anchor circle)
			)
			(primitives
				(gr_poly
					(pts
						(arc
							(start -0.1778 -0.2794)
							(mid -0.249642 -0.249642)
							(end -0.2794 -0.1778)
						)
						(arc
							(start -0.2794 0.1778)
							(mid -0.249642 0.249642)
							(end -0.1778 0.2794)
						)
						(arc
							(start 0.1778 0.2794)
							(mid 0.249642 0.249642)
							(end 0.2794 0.1778)
						)
						(arc
							(start 0.2794 -0.1778)
							(mid 0.249642 -0.249642)
							(end 0.1778 -0.2794)
						)
					)
					(width 0)
					(fill yes)
				)
			)
		)
	)
	(footprint ""
		(layer "F.Cu")
		(at 426.72 -16.256 -90)
		(property "Reference" "Q173"
			(at 0 0 270)
			(layer "F.SilkS")
			(hide yes)
			(effects
				(font
					(size 1.27 1.27)
				)
			)
		)
		(property "Value" "2N7002KDW-GP"
			(at -2.3622 -8.2042 270)
			(unlocked yes)
			(layer "F.Fab")
			(hide yes)
			(effects
				(font
					(size 1.016 1.016)
					(thickness 0.1524)
				)
			)
		)
		(property "Device Type" "SOT-363H44"
			(at -2.3622 -10.1092 270)
			(unlocked yes)
			(layer "F.Fab")
			(hide yes)
			(effects
				(font
					(size 1.016 1.016)
					(thickness 0.1524)
				)
			)
		)
		(duplicate_pad_numbers_are_jumpers no)
		(fp_line
			(start -1.4478 1.7018)
			(end 1.4478 1.7018)
			(stroke
				(width 0.1524)
				(type default)
			)
			(layer "F.SilkS")
		)
		(fp_line
			(start 1.4478 1.7018)
			(end 1.4478 -1.7018)
			(stroke
				(width 0.1524)
				(type default)
			)
			(layer "F.SilkS")
		)
		(fp_line
			(start -1.27 1.524)
			(end -1.27 0.6604)
			(stroke
				(width 0.4826)
				(type default)
			)
			(layer "F.SilkS")
		)
		(fp_line
			(start -1.4478 -1.7018)
			(end -1.4478 1.7018)
			(stroke
				(width 0.1524)
				(type default)
			)
			(layer "F.SilkS")
		)
		(fp_line
			(start 1.4478 -1.7018)
			(end -1.4478 -1.7018)
			(stroke
				(width 0.1524)
				(type default)
			)
			(layer "F.SilkS")
		)
		(fp_poly
			(pts
				(xy -1.524 -1.778) (xy 1.524 -1.778) (xy 1.524 1.778) (xy -1.524 1.778)
			)
			(stroke
				(width 0)
				(type default)
			)
			(fill no)
			(layer "F.CrtYd")
		)
		(fp_poly
			(pts
				(xy -1.524 -1.778) (xy 1.524 -1.778) (xy 1.524 1.778) (xy -1.524 1.778)
			)
			(stroke
				(width 0)
				(type default)
			)
			(fill no)
			(layer "F.Fab")
		)
		(pad "1" smd rect
			(at -0.65024 0.9398 270)
			(size 0.4064 1.016)
			(layers "F.Cu" "F.Mask" "F.Paste")
			(net "GND")
		)
		(pad "2" smd rect
			(at 0 0.9398 270)
			(size 0.4064 1.016)
			(layers "F.Cu" "F.Mask" "F.Paste")
			(net "SW_PWR_R_HDD33")
		)
		(pad "3" smd rect
			(at 0.65024 0.9398 270)
			(size 0.4064 1.016)
			(layers "F.Cu" "F.Mask" "F.Paste")
			(net "SW_HDD_P33")
		)
		(pad "4" smd rect
			(at 0.65024 -0.9398 270)
			(size 0.4064 1.016)
			(layers "F.Cu" "F.Mask" "F.Paste")
			(net "GND")
		)
		(pad "5" smd rect
			(at 0 -0.9398 270)
			(size 0.4064 1.016)
			(layers "F.Cu" "F.Mask" "F.Paste")
			(net "SW_HDD_G33")
		)
		(pad "6" smd rect
			(at -0.65024 -0.9398 270)
			(size 0.4064 1.016)
			(layers "F.Cu" "F.Mask" "F.Paste")
			(net "SW_HDD_R33")
		)
	)
	(footprint ""
		(layer "F.Cu")
		(at 16.764 -254.127 -90)
		(property "Reference" "C506"
			(at 0 0 270)
			(layer "F.SilkS")
			(hide yes)
			(effects
				(font
					(size 1.27 1.27)
				)
			)
		)
		(property "Value" "SCD033U25V2KX-GP"
			(at 1.1811 -2.7051 270)
			(unlocked yes)
			(layer "F.Fab")
			(hide yes)
			(effects
				(font
					(size 1.016 1.016)
					(thickness 0.1524)
				)
			)
		)
		(property "Device Type" "C402H22"
			(at 1.1811 -4.2291 270)
			(unlocked yes)
			(layer "F.Fab")
			(hide yes)
			(effects
				(font
					(size 1.016 1.016)
					(thickness 0.1524)
				)
			)
		)
		(duplicate_pad_numbers_are_jumpers no)
		(fp_rect
			(start -0.4318 0.9525)
			(end 0.4318 -0.9525)
			(stroke
				(width 0)
				(type default)
			)
			(fill no)
			(layer "F.CrtYd")
		)
		(fp_rect
			(start -0.4318 0.9525)
			(end 0.4318 -0.9525)
			(stroke
				(width 0)
				(type default)
			)
			(fill no)
			(layer "F.Fab")
		)
		(pad "1" smd custom
			(at 0 -0.4445 270)
			(size 0.1524 0.1524)
			(layers "F.Cu" "F.Mask" "F.Paste")
			(net "SW_HDD_P0")
			(options
				(clearance outline)
				(anchor circle)
			)
			(primitives
				(gr_poly
					(pts
						(arc
							(start 0.3048 -0.2032)
							(mid 0.275042 -0.275042)
							(end 0.2032 -0.3048)
						)
						(arc
							(start -0.2032 -0.3048)
							(mid -0.275042 -0.275042)
							(end -0.3048 -0.2032)
						)
						(arc
							(start -0.3048 0.2032)
							(mid -0.275042 0.275042)
							(end -0.2032 0.3048)
						)
						(arc
							(start 0.2032 0.3048)
							(mid 0.275042 0.275042)
							(end 0.3048 0.2032)
						)
					)
					(width 0)
					(fill yes)
				)
			)
		)
		(pad "2" smd custom
			(at 0 0.4445 270)
			(size 0.1524 0.1524)
			(layers "F.Cu" "F.Mask" "F.Paste")
			(net "GND")
			(options
				(clearance outline)
				(anchor circle)
			)
			(primitives
				(gr_poly
					(pts
						(arc
							(start 0.3048 -0.2032)
							(mid 0.275042 -0.275042)
							(end 0.2032 -0.3048)
						)
						(arc
							(start -0.2032 -0.3048)
							(mid -0.275042 -0.275042)
							(end -0.3048 -0.2032)
						)
						(arc
							(start -0.3048 0.2032)
							(mid -0.275042 0.275042)
							(end -0.2032 0.3048)
						)
						(arc
							(start 0.2032 0.3048)
							(mid 0.275042 0.275042)
							(end 0.3048 0.2032)
						)
					)
					(width 0)
					(fill yes)
				)
			)
		)
	)
	(footprint ""
		(layer "F.Cu")
		(at 186.7281 -379.5395 90)
		(property "Reference" "R970"
			(at 0 0 90)
			(layer "F.SilkS")
			(hide yes)
			(effects
				(font
					(size 1.27 1.27)
				)
			)
		)
		(property "Value" "270R5J-2-GP"
			(at 0 -8.9535 90)
			(unlocked yes)
			(layer "F.Fab")
			(hide yes)
			(effects
				(font
					(size 1.27 1.016)
					(thickness 0.1524)
				)
			)
		)
		(property "Device Type" "R805H24"
			(at 0 -10.6299 90)
			(unlocked yes)
			(layer "F.Fab")
			(hide yes)
			(effects
				(font
					(size 1.27 1.016)
					(thickness 0.1524)
				)
			)
		)
		(duplicate_pad_numbers_are_jumpers no)
		(fp_line
			(start 0.889 -1.7018)
			(end -0.889 -1.7018)
			(stroke
				(width 0.1524)
				(type default)
			)
			(layer "F.SilkS")
		)
		(fp_line
			(start 0.889 -1.7018)
			(end 0.889 -0.381)
			(stroke
				(width 0.1524)
				(type default)
			)
			(layer "F.SilkS")
		)
		(fp_line
			(start -0.889 -1.7018)
			(end -0.889 0.2794)
			(stroke
				(width 0.1524)
				(type default)
			)
			(layer "F.SilkS")
		)
		(fp_line
			(start -0.889 0.0762)
			(end -0.889 1.7018)
			(stroke
				(width 0.1524)
				(type default)
			)
			(layer "F.SilkS")
		)
		(fp_line
			(start 0.889 1.7018)
			(end 0.889 -0.508)
			(stroke
				(width 0.1524)
				(type default)
			)
			(layer "F.SilkS")
		)
		(fp_line
			(start -0.889 1.7018)
			(end 0.889 1.7018)
			(stroke
				(width 0.1524)
				(type default)
			)
			(layer "F.SilkS")
		)
		(fp_poly
			(pts
				(xy 0.9652 -1.778) (xy 0.9652 1.778) (xy -0.9652 1.778) (xy -0.9652 -1.778)
			)
			(stroke
				(width 0)
				(type default)
			)
			(fill no)
			(layer "F.CrtYd")
		)
		(fp_rect
			(start -0.9652 1.778)
			(end 0.9652 -1.778)
			(stroke
				(width 0)
				(type default)
			)
			(fill no)
			(layer "F.Fab")
		)
		(pad "1" smd rect
			(at 0 -0.9652 90)
			(size 1.397 1.143)
			(layers "F.Cu" "F.Mask" "F.Paste")
			(net "FAN_LED_BLUE1")
		)
		(pad "2" smd rect
			(at 0 0.9652 90)
			(size 1.397 1.143)
			(layers "F.Cu" "F.Mask" "F.Paste")
			(net "FAN_BLUE1")
		)
	)
	(footprint ""
		(layer "F.Cu")
		(at 470.281 -248.92 -90)
		(property "Reference" "R347"
			(at 0 0 270)
			(layer "F.SilkS")
			(hide yes)
			(effects
				(font
					(size 1.27 1.27)
				)
			)
		)
		(property "Value" "0R2J-2-GP"
			(at 0.064008 -3.993896 270)
			(unlocked yes)
			(layer "F.Fab")
			(hide yes)
			(effects
				(font
					(size 1.016 1.016)
					(thickness 0.1524)
				)
			)
		)
		(property "Device Type" "R402H16"
			(at 0.064008 -5.517896 270)
			(unlocked yes)
			(layer "F.Fab")
			(hide yes)
			(effects
				(font
					(size 1.016 1.016)
					(thickness 0.1524)
				)
			)
		)
		(duplicate_pad_numbers_are_jumpers no)
		(fp_line
			(start -0.508 -0.9398)
			(end -0.508 0.9398)
			(stroke
				(width 0.1524)
				(type default)
			)
			(layer "F.SilkS")
		)
		(fp_line
			(start 0.508 -0.9398)
			(end -0.508 -0.9398)
			(stroke
				(width 0.1524)
				(type default)
			)
			(layer "F.SilkS")
		)
		(fp_rect
			(start -0.508 0.9398)
			(end 0.508 -0.9398)
			(stroke
				(width 0)
				(type default)
			)
			(fill no)
			(layer "F.CrtYd")
		)
		(fp_rect
			(start -0.508 0.9398)
			(end 0.508 -0.9398)
			(stroke
				(width 0)
				(type default)
			)
			(fill no)
			(layer "F.Fab")
		)
		(pad "1" smd custom
			(at 0 -0.4445 270)
			(size 0.1397 0.1397)
			(layers "F.Cu" "F.Mask" "F.Paste")
			(net "SW_HDD_G11")
			(options
				(clearance outline)
				(anchor circle)
			)
			(primitives
				(gr_poly
					(pts
						(arc
							(start -0.1778 -0.2794)
							(mid -0.249642 -0.249642)
							(end -0.2794 -0.1778)
						)
						(arc
							(start -0.2794 0.1778)
							(mid -0.249642 0.249642)
							(end -0.1778 0.2794)
						)
						(arc
							(start 0.1778 0.2794)
							(mid 0.249642 0.249642)
							(end 0.2794 0.1778)
						)
						(arc
							(start 0.2794 -0.1778)
							(mid 0.249642 -0.249642)
							(end 0.1778 -0.2794)
						)
					)
					(width 0)
					(fill yes)
				)
			)
		)
		(pad "2" smd custom
			(at 0 0.4445 270)
			(size 0.1397 0.1397)
			(layers "F.Cu" "F.Mask" "F.Paste")
			(net "SW_HDD_R11")
			(options
				(clearance outline)
				(anchor circle)
			)
			(primitives
				(gr_poly
					(pts
						(arc
							(start -0.1778 -0.2794)
							(mid -0.249642 -0.249642)
							(end -0.2794 -0.1778)
						)
						(arc
							(start -0.2794 0.1778)
							(mid -0.249642 0.249642)
							(end -0.1778 0.2794)
						)
						(arc
							(start 0.1778 0.2794)
							(mid 0.249642 0.249642)
							(end 0.2794 0.1778)
						)
						(arc
							(start 0.2794 -0.1778)
							(mid 0.249642 -0.249642)
							(end 0.1778 -0.2794)
						)
					)
					(width 0)
					(fill yes)
				)
			)
		)
	)
	(footprint ""
		(layer "F.Cu")
		(at 209.03946 -164.38626 -90)
		(property "Reference" "R60"
			(at 0 0 270)
			(layer "F.SilkS")
			(hide yes)
			(effects
				(font
					(size 1.27 1.27)
				)
			)
		)
		(property "Value" "0R2J-2-GP"
			(at 0.064008 -3.993896 270)
			(unlocked yes)
			(layer "F.Fab")
			(hide yes)
			(effects
				(font
					(size 1.016 1.016)
					(thickness 0.1524)
				)
			)
		)
		(property "Device Type" "R402H16"
			(at 0.064008 -5.517896 270)
			(unlocked yes)
			(layer "F.Fab")
			(hide yes)
			(effects
				(font
					(size 1.016 1.016)
					(thickness 0.1524)
				)
			)
		)
		(duplicate_pad_numbers_are_jumpers no)
		(fp_line
			(start -0.508 -0.9398)
			(end -0.508 0.9398)
			(stroke
				(width 0.1524)
				(type default)
			)
			(layer "F.SilkS")
		)
		(fp_line
			(start 0.508 -0.9398)
			(end -0.508 -0.9398)
			(stroke
				(width 0.1524)
				(type default)
			)
			(layer "F.SilkS")
		)
		(fp_rect
			(start -0.508 0.9398)
			(end 0.508 -0.9398)
			(stroke
				(width 0)
				(type default)
			)
			(fill no)
			(layer "F.CrtYd")
		)
		(fp_rect
			(start -0.508 0.9398)
			(end 0.508 -0.9398)
			(stroke
				(width 0)
				(type default)
			)
			(fill no)
			(layer "F.Fab")
		)
		(pad "1" smd custom
			(at 0 -0.4445 270)
			(size 0.1397 0.1397)
			(layers "F.Cu" "F.Mask" "F.Paste")
			(net "IO_EXP6_SDA")
			(options
				(clearance outline)
				(anchor circle)
			)
			(primitives
				(gr_poly
					(pts
						(arc
							(start -0.1778 -0.2794)
							(mid -0.249642 -0.249642)
							(end -0.2794 -0.1778)
						)
						(arc
							(start -0.2794 0.1778)
							(mid -0.249642 0.249642)
							(end -0.1778 0.2794)
						)
						(arc
							(start 0.1778 0.2794)
							(mid 0.249642 0.249642)
							(end 0.2794 0.1778)
						)
						(arc
							(start 0.2794 -0.1778)
							(mid 0.249642 -0.249642)
							(end 0.1778 -0.2794)
						)
					)
					(width 0)
					(fill yes)
				)
			)
		)
		(pad "2" smd custom
			(at 0 0.4445 270)
			(size 0.1397 0.1397)
			(layers "F.Cu" "F.Mask" "F.Paste")
			(net "I2C_DRIVE_B_INS_SDA")
			(options
				(clearance outline)
				(anchor circle)
			)
			(primitives
				(gr_poly
					(pts
						(arc
							(start -0.1778 -0.2794)
							(mid -0.249642 -0.249642)
							(end -0.2794 -0.1778)
						)
						(arc
							(start -0.2794 0.1778)
							(mid -0.249642 0.249642)
							(end -0.1778 0.2794)
						)
						(arc
							(start 0.1778 0.2794)
							(mid 0.249642 0.249642)
							(end 0.2794 0.1778)
						)
						(arc
							(start 0.2794 -0.1778)
							(mid 0.249642 -0.249642)
							(end 0.1778 -0.2794)
						)
					)
					(width 0)
					(fill yes)
				)
			)
		)
	)
	(footprint ""
		(layer "F.Cu")
		(at 17.670018 -99.782884 180)
		(property "Reference" "Q231"
			(at 0 0 180)
			(layer "F.SilkS")
			(hide yes)
			(effects
				(font
					(size 1.27 1.27)
				)
			)
		)
		(property "Value" "2N7002K-2-GP"
			(at 0.127 -8.9662 180)
			(unlocked yes)
			(layer "F.Fab")
			(hide yes)
			(effects
				(font
					(size 1.016 1.016)
					(thickness 0.1524)
				)
			)
		)
		(property "Device Type" "SOT23DGS2D4H44"
			(at 0.127 -10.4902 180)
			(unlocked yes)
			(layer "F.Fab")
			(hide yes)
			(effects
				(font
					(size 1.016 1.016)
					(thickness 0.1524)
				)
			)
		)
		(duplicate_pad_numbers_are_jumpers no)
		(fp_line
			(start 1.651 1.778)
			(end 1.651 -1.778)
			(stroke
				(width 0.1524)
				(type default)
			)
			(layer "F.SilkS")
		)
		(fp_line
			(start 1.651 -1.778)
			(end -1.651 -1.778)
			(stroke
				(width 0.1524)
				(type default)
			)
			(layer "F.SilkS")
		)
		(fp_line
			(start -1.651 1.778)
			(end 1.651 1.778)
			(stroke
				(width 0.1524)
				(type default)
			)
			(layer "F.SilkS")
		)
		(fp_line
			(start -1.651 -1.778)
			(end -1.651 1.778)
			(stroke
				(width 0.1524)
				(type default)
			)
			(layer "F.SilkS")
		)
		(fp_poly
			(pts
				(xy -1.778 1.8796) (xy -1.778 -1.8796) (xy 1.778 -1.8796) (xy 1.778 1.8796)
			)
			(stroke
				(width 0)
				(type default)
			)
			(fill no)
			(layer "F.CrtYd")
		)
		(fp_poly
			(pts
				(xy -1.778 1.8796) (xy -1.778 -1.8796) (xy 1.778 -1.8796) (xy 1.778 1.8796)
			)
			(stroke
				(width 0)
				(type default)
			)
			(fill no)
			(layer "F.Fab")
		)
		(pad "D" smd custom
			(at 0 -0.9525 180)
			(size 0.1905 0.1905)
			(layers "F.Cu" "F.Mask" "F.Paste")
			(net "FLT_HDD12_N")
			(options
				(clearance outline)
				(anchor circle)
			)
			(primitives
				(gr_poly
					(pts
						(arc
							(start -0.1778 0.5715)
							(mid -0.321484 0.511984)
							(end -0.381 0.3683)
						)
						(arc
							(start -0.381 -0.3683)
							(mid -0.321484 -0.511984)
							(end -0.1778 -0.5715)
						)
						(arc
							(start 0.1778 -0.5715)
							(mid 0.321484 -0.511984)
							(end 0.381 -0.3683)
						)
						(arc
							(start 0.381 0.3683)
							(mid 0.321484 0.511984)
							(end 0.1778 0.5715)
						)
					)
					(width 0)
					(fill yes)
				)
			)
		)
		(pad "G" smd custom
			(at -0.98425 0.9525 180)
			(size 0.1905 0.1905)
			(layers "F.Cu" "F.Mask" "F.Paste")
			(net "DRIVE_B_12_FLT_LED")
			(options
				(clearance outline)
				(anchor circle)
			)
			(primitives
				(gr_poly
					(pts
						(arc
							(start -0.1778 0.5715)
							(mid -0.321484 0.511984)
							(end -0.381 0.3683)
						)
						(arc
							(start -0.381 -0.3683)
							(mid -0.321484 -0.511984)
							(end -0.1778 -0.5715)
						)
						(arc
							(start 0.1778 -0.5715)
							(mid 0.321484 -0.511984)
							(end 0.381 -0.3683)
						)
						(arc
							(start 0.381 0.3683)
							(mid 0.321484 0.511984)
							(end 0.1778 0.5715)
						)
					)
					(width 0)
					(fill yes)
				)
			)
		)
		(pad "S" smd custom
			(at 0.98425 0.9525 180)
			(size 0.1905 0.1905)
			(layers "F.Cu" "F.Mask" "F.Paste")
			(net "GND")
			(options
				(clearance outline)
				(anchor circle)
			)
			(primitives
				(gr_poly
					(pts
						(arc
							(start -0.1778 0.5715)
							(mid -0.321484 0.511984)
							(end -0.381 0.3683)
						)
						(arc
							(start -0.381 -0.3683)
							(mid -0.321484 -0.511984)
							(end -0.1778 -0.5715)
						)
						(arc
							(start 0.1778 -0.5715)
							(mid 0.321484 -0.511984)
							(end 0.381 -0.3683)
						)
						(arc
							(start 0.381 0.3683)
							(mid 0.321484 0.511984)
							(end 0.1778 0.5715)
						)
					)
					(width 0)
					(fill yes)
				)
			)
		)
	)
	(footprint ""
		(layer "F.Cu")
		(at 447.834512 -130.21945 -90)
		(property "Reference" "C314"
			(at 0 0 270)
			(layer "F.SilkS")
			(hide yes)
			(effects
				(font
					(size 1.27 1.27)
				)
			)
		)
		(property "Value" "SCD01U16V1KX-GP"
			(at -2.8321 -1.7399 270)
			(unlocked yes)
			(layer "F.Fab")
			(hide yes)
			(effects
				(font
					(size 1.016 1.016)
					(thickness 0.1524)
				)
			)
		)
		(property "Device Type" "C0201H13"
			(at -2.8321 -3.2639 270)
			(unlocked yes)
			(layer "F.Fab")
			(hide yes)
			(effects
				(font
					(size 1.016 1.016)
					(thickness 0.1524)
				)
			)
		)
		(duplicate_pad_numbers_are_jumpers no)
		(fp_rect
			(start -0.2794 0.6477)
			(end 0.2794 -0.6477)
			(stroke
				(width 0)
				(type default)
			)
			(fill no)
			(layer "F.CrtYd")
		)
		(fp_rect
			(start -0.2794 0.6477)
			(end 0.2794 -0.6477)
			(stroke
				(width 0)
				(type default)
			)
			(fill no)
			(layer "F.Fab")
		)
		(pad "1" smd custom
			(at 0 -0.2794 270)
			(size 0.0762 0.0762)
			(layers "F.Cu" "F.Mask" "F.Paste")
			(net "SAS_HDD_RX_N22")
			(options
				(clearance outline)
				(anchor circle)
			)
			(primitives
				(gr_poly
					(pts
						(arc
							(start 0.1524 -0.127)
							(mid 0.137521 -0.162921)
							(end 0.1016 -0.1778)
						)
						(arc
							(start -0.1016 -0.1778)
							(mid -0.137521 -0.162921)
							(end -0.1524 -0.127)
						)
						(arc
							(start -0.1524 0.127)
							(mid -0.137521 0.162921)
							(end -0.1016 0.1778)
						)
						(arc
							(start 0.1016 0.1778)
							(mid 0.137521 0.162921)
							(end 0.1524 0.127)
						)
					)
					(width 0)
					(fill yes)
				)
			)
		)
		(pad "2" smd custom
			(at 0 0.2794 270)
			(size 0.0762 0.0762)
			(layers "F.Cu" "F.Mask" "F.Paste")
			(net "PHY_SCC_B_TO_DRV_B_22_DN")
			(options
				(clearance outline)
				(anchor circle)
			)
			(primitives
				(gr_poly
					(pts
						(arc
							(start 0.1524 -0.127)
							(mid 0.137521 -0.162921)
							(end 0.1016 -0.1778)
						)
						(arc
							(start -0.1016 -0.1778)
							(mid -0.137521 -0.162921)
							(end -0.1524 -0.127)
						)
						(arc
							(start -0.1524 0.127)
							(mid -0.137521 0.162921)
							(end -0.1016 0.1778)
						)
						(arc
							(start 0.1016 0.1778)
							(mid 0.137521 0.162921)
							(end 0.1524 0.127)
						)
					)
					(width 0)
					(fill yes)
				)
			)
		)
	)
	(footprint ""
		(layer "F.Cu")
		(at 333.248 -243.586 180)
		(property "Reference" "R260"
			(at 0 0 180)
			(layer "F.SilkS")
			(hide yes)
			(effects
				(font
					(size 1.27 1.27)
				)
			)
		)
		(property "Value" "1KR2F-3-GP"
			(at 0.064008 -3.993896 180)
			(unlocked yes)
			(layer "F.Fab")
			(hide yes)
			(effects
				(font
					(size 1.016 1.016)
					(thickness 0.1524)
				)
			)
		)
		(property "Device Type" "R402H16"
			(at 0.064008 -5.517896 180)
			(unlocked yes)
			(layer "F.Fab")
			(hide yes)
			(effects
				(font
					(size 1.016 1.016)
					(thickness 0.1524)
				)
			)
		)
		(duplicate_pad_numbers_are_jumpers no)
		(fp_line
			(start 0.508 -0.9398)
			(end -0.508 -0.9398)
			(stroke
				(width 0.1524)
				(type default)
			)
			(layer "F.SilkS")
		)
		(fp_line
			(start -0.508 -0.9398)
			(end -0.508 0.9398)
			(stroke
				(width 0.1524)
				(type default)
			)
			(layer "F.SilkS")
		)
		(fp_rect
			(start -0.508 0.9398)
			(end 0.508 -0.9398)
			(stroke
				(width 0)
				(type default)
			)
			(fill no)
			(layer "F.CrtYd")
		)
		(fp_rect
			(start -0.508 0.9398)
			(end 0.508 -0.9398)
			(stroke
				(width 0)
				(type default)
			)
			(fill no)
			(layer "F.Fab")
		)
		(pad "1" smd custom
			(at 0 -0.4445 180)
			(size 0.1397 0.1397)
			(layers "F.Cu" "F.Mask" "F.Paste")
			(net "P3V3_STBY_B")
			(options
				(clearance outline)
				(anchor circle)
			)
			(primitives
				(gr_poly
					(pts
						(arc
							(start -0.1778 -0.2794)
							(mid -0.249642 -0.249642)
							(end -0.2794 -0.1778)
						)
						(arc
							(start -0.2794 0.1778)
							(mid -0.249642 0.249642)
							(end -0.1778 0.2794)
						)
						(arc
							(start 0.1778 0.2794)
							(mid 0.249642 0.249642)
							(end 0.2794 0.1778)
						)
						(arc
							(start 0.2794 -0.1778)
							(mid 0.249642 -0.249642)
							(end 0.1778 -0.2794)
						)
					)
					(width 0)
					(fill yes)
				)
			)
		)
		(pad "2" smd custom
			(at 0 0.4445 180)
			(size 0.1397 0.1397)
			(layers "F.Cu" "F.Mask" "F.Paste")
			(net "SW_PWR_R_HDD6")
			(options
				(clearance outline)
				(anchor circle)
			)
			(primitives
				(gr_poly
					(pts
						(arc
							(start -0.1778 -0.2794)
							(mid -0.249642 -0.249642)
							(end -0.2794 -0.1778)
						)
						(arc
							(start -0.2794 0.1778)
							(mid -0.249642 0.249642)
							(end -0.1778 0.2794)
						)
						(arc
							(start 0.1778 0.2794)
							(mid 0.249642 0.249642)
							(end 0.2794 0.1778)
						)
						(arc
							(start 0.2794 -0.1778)
							(mid 0.249642 -0.249642)
							(end 0.1778 -0.2794)
						)
					)
					(width 0)
					(fill yes)
				)
			)
		)
	)
	(footprint ""
		(layer "F.Cu")
		(at 255.934972 -373.09171 180)
		(property "Reference" "C558"
			(at 0 0 180)
			(layer "F.SilkS")
			(hide yes)
			(effects
				(font
					(size 1.27 1.27)
				)
			)
		)
		(property "Value" "SC2D2U25V5KX-2-GP"
			(at -0.0762 -6.1214 180)
			(unlocked yes)
			(layer "F.Fab")
			(hide yes)
			(effects
				(font
					(size 1.016 1.016)
					(thickness 0.1524)
				)
			)
		)
		(property "Device Type" "C805H54"
			(at -0.0762 -8.1534 180)
			(unlocked yes)
			(layer "F.Fab")
			(hide yes)
			(effects
				(font
					(size 1.016 1.016)
					(thickness 0.1524)
				)
			)
		)
		(duplicate_pad_numbers_are_jumpers no)
		(fp_line
			(start 0.635 0)
			(end -0.635 0)
			(stroke
				(width 0.508)
				(type default)
			)
			(layer "F.SilkS")
		)
		(fp_rect
			(start -0.9652 1.778)
			(end 0.9652 -1.778)
			(stroke
				(width 0)
				(type default)
			)
			(fill no)
			(layer "F.CrtYd")
		)
		(fp_poly
			(pts
				(xy -0.9652 -1.778) (xy 0.9652 -1.778) (xy 0.9652 1.778) (xy -0.9652 1.778)
			)
			(stroke
				(width 0)
				(type default)
			)
			(fill no)
			(layer "F.Fab")
		)
		(pad "1" smd rect
			(at 0 -0.9652 180)
			(size 1.397 1.143)
			(layers "F.Cu" "F.Mask" "F.Paste")
			(net "P12V_B_PGOOD")
		)
		(pad "2" smd rect
			(at 0 0.9652 180)
			(size 1.397 1.143)
			(layers "F.Cu" "F.Mask" "F.Paste")
			(net "GND")
		)
	)
	(footprint ""
		(layer "F.Cu")
		(at 324.085712 -102.373684 -90)
		(property "Reference" "R466"
			(at 0 0 270)
			(layer "F.SilkS")
			(hide yes)
			(effects
				(font
					(size 1.27 1.27)
				)
			)
		)
		(property "Value" "4K7R2F-GP"
			(at 0.064008 -3.993896 270)
			(unlocked yes)
			(layer "F.Fab")
			(hide yes)
			(effects
				(font
					(size 1.016 1.016)
					(thickness 0.1524)
				)
			)
		)
		(property "Device Type" "R402H16"
			(at 0.064008 -5.517896 270)
			(unlocked yes)
			(layer "F.Fab")
			(hide yes)
			(effects
				(font
					(size 1.016 1.016)
					(thickness 0.1524)
				)
			)
		)
		(duplicate_pad_numbers_are_jumpers no)
		(fp_line
			(start -0.508 -0.9398)
			(end -0.508 0.9398)
			(stroke
				(width 0.1524)
				(type default)
			)
			(layer "F.SilkS")
		)
		(fp_line
			(start 0.508 -0.9398)
			(end -0.508 -0.9398)
			(stroke
				(width 0.1524)
				(type default)
			)
			(layer "F.SilkS")
		)
		(fp_rect
			(start -0.508 0.9398)
			(end 0.508 -0.9398)
			(stroke
				(width 0)
				(type default)
			)
			(fill no)
			(layer "F.CrtYd")
		)
		(fp_rect
			(start -0.508 0.9398)
			(end 0.508 -0.9398)
			(stroke
				(width 0)
				(type default)
			)
			(fill no)
			(layer "F.Fab")
		)
		(pad "1" smd custom
			(at 0 -0.4445 270)
			(size 0.1397 0.1397)
			(layers "F.Cu" "F.Mask" "F.Paste")
			(net "DRIVE_B_18_FLT_LED")
			(options
				(clearance outline)
				(anchor circle)
			)
			(primitives
				(gr_poly
					(pts
						(arc
							(start -0.1778 -0.2794)
							(mid -0.249642 -0.249642)
							(end -0.2794 -0.1778)
						)
						(arc
							(start -0.2794 0.1778)
							(mid -0.249642 0.249642)
							(end -0.1778 0.2794)
						)
						(arc
							(start 0.1778 0.2794)
							(mid 0.249642 0.249642)
							(end 0.2794 0.1778)
						)
						(arc
							(start 0.2794 -0.1778)
							(mid 0.249642 -0.249642)
							(end 0.1778 -0.2794)
						)
					)
					(width 0)
					(fill yes)
				)
			)
		)
		(pad "2" smd custom
			(at 0 0.4445 270)
			(size 0.1397 0.1397)
			(layers "F.Cu" "F.Mask" "F.Paste")
			(net "GND")
			(options
				(clearance outline)
				(anchor circle)
			)
			(primitives
				(gr_poly
					(pts
						(arc
							(start -0.1778 -0.2794)
							(mid -0.249642 -0.249642)
							(end -0.2794 -0.1778)
						)
						(arc
							(start -0.2794 0.1778)
							(mid -0.249642 0.249642)
							(end -0.1778 0.2794)
						)
						(arc
							(start 0.1778 0.2794)
							(mid 0.249642 0.249642)
							(end 0.2794 0.1778)
						)
						(arc
							(start 0.2794 -0.1778)
							(mid 0.249642 -0.249642)
							(end 0.1778 -0.2794)
						)
					)
					(width 0)
					(fill yes)
				)
			)
		)
	)
	(footprint ""
		(layer "F.Cu")
		(at 86.868 -33.274)
		(property "Reference" "R667"
			(at 0 0 0)
			(layer "F.SilkS")
			(hide yes)
			(effects
				(font
					(size 1.27 1.27)
				)
			)
		)
		(property "Value" "2R6F-GP"
			(at -0.0508 -4.8514 0)
			(unlocked yes)
			(layer "F.Fab")
			(hide yes)
			(effects
				(font
					(size 1.016 1.016)
					(thickness 0.1524)
				)
			)
		)
		(property "Device Type" "R1206H26"
			(at 0 -6.3754 0)
			(unlocked yes)
			(layer "F.Fab")
			(hide yes)
			(effects
				(font
					(size 1.016 1.016)
					(thickness 0.1524)
				)
			)
		)
		(duplicate_pad_numbers_are_jumpers no)
		(fp_line
			(start -1.016 -2.2352)
			(end 1.016 -2.2352)
			(stroke
				(width 0.1524)
				(type default)
			)
			(layer "F.SilkS")
		)
		(fp_line
			(start -1.016 2.2352)
			(end -1.016 -2.2352)
			(stroke
				(width 0.1524)
				(type default)
			)
			(layer "F.SilkS")
		)
		(fp_line
			(start 1.016 -2.2352)
			(end 1.016 2.2352)
			(stroke
				(width 0.1524)
				(type default)
			)
			(layer "F.SilkS")
		)
		(fp_line
			(start 1.016 2.2352)
			(end -1.016 2.2352)
			(stroke
				(width 0.1524)
				(type default)
			)
			(layer "F.SilkS")
		)
		(fp_rect
			(start -1.0922 2.3114)
			(end 1.0922 -2.3114)
			(stroke
				(width 0)
				(type default)
			)
			(fill no)
			(layer "F.CrtYd")
		)
		(fp_poly
			(pts
				(xy -1.0922 -2.3114) (xy 1.0922 -2.3114) (xy 1.0922 2.3114) (xy -1.0922 2.3114)
			)
			(stroke
				(width 0)
				(type default)
			)
			(fill no)
			(layer "F.Fab")
		)
		(pad "1" smd rect
			(at 0 -1.397)
			(size 1.651 1.27)
			(layers "F.Cu" "F.Mask" "F.Paste")
			(net "P5V_HDD26")
		)
		(pad "2" smd rect
			(at 0 1.397)
			(size 1.651 1.27)
			(layers "F.Cu" "F.Mask" "F.Paste")
			(net "5V_PRE_26")
		)
	)
	(footprint ""
		(layer "F.Cu")
		(at 233.1212 -194.2592 -90)
		(property "Reference" "R75"
			(at 0 0 270)
			(layer "F.SilkS")
			(hide yes)
			(effects
				(font
					(size 1.27 1.27)
				)
			)
		)
		(property "Value" "0R2J-2-GP"
			(at 0.064008 -3.993896 270)
			(unlocked yes)
			(layer "F.Fab")
			(hide yes)
			(effects
				(font
					(size 1.016 1.016)
					(thickness 0.1524)
				)
			)
		)
		(property "Device Type" "R402H16"
			(at 0.064008 -5.517896 270)
			(unlocked yes)
			(layer "F.Fab")
			(hide yes)
			(effects
				(font
					(size 1.016 1.016)
					(thickness 0.1524)
				)
			)
		)
		(duplicate_pad_numbers_are_jumpers no)
		(fp_line
			(start -0.508 -0.9398)
			(end -0.508 0.9398)
			(stroke
				(width 0.1524)
				(type default)
			)
			(layer "F.SilkS")
		)
		(fp_line
			(start 0.508 -0.9398)
			(end -0.508 -0.9398)
			(stroke
				(width 0.1524)
				(type default)
			)
			(layer "F.SilkS")
		)
		(fp_rect
			(start -0.508 0.9398)
			(end 0.508 -0.9398)
			(stroke
				(width 0)
				(type default)
			)
			(fill no)
			(layer "F.CrtYd")
		)
		(fp_rect
			(start -0.508 0.9398)
			(end 0.508 -0.9398)
			(stroke
				(width 0)
				(type default)
			)
			(fill no)
			(layer "F.Fab")
		)
		(pad "1" smd custom
			(at 0 -0.4445 270)
			(size 0.1397 0.1397)
			(layers "F.Cu" "F.Mask" "F.Paste")
			(net "IO_EXP2_SDA")
			(options
				(clearance outline)
				(anchor circle)
			)
			(primitives
				(gr_poly
					(pts
						(arc
							(start -0.1778 -0.2794)
							(mid -0.249642 -0.249642)
							(end -0.2794 -0.1778)
						)
						(arc
							(start -0.2794 0.1778)
							(mid -0.249642 0.249642)
							(end -0.1778 0.2794)
						)
						(arc
							(start 0.1778 0.2794)
							(mid 0.249642 0.249642)
							(end 0.2794 0.1778)
						)
						(arc
							(start 0.2794 -0.1778)
							(mid 0.249642 -0.249642)
							(end 0.1778 -0.2794)
						)
					)
					(width 0)
					(fill yes)
				)
			)
		)
		(pad "2" smd custom
			(at 0 0.4445 270)
			(size 0.1397 0.1397)
			(layers "F.Cu" "F.Mask" "F.Paste")
			(net "I2C_DRIVE_B_PWR_SDA")
			(options
				(clearance outline)
				(anchor circle)
			)
			(primitives
				(gr_poly
					(pts
						(arc
							(start -0.1778 -0.2794)
							(mid -0.249642 -0.249642)
							(end -0.2794 -0.1778)
						)
						(arc
							(start -0.2794 0.1778)
							(mid -0.249642 0.249642)
							(end -0.1778 0.2794)
						)
						(arc
							(start 0.1778 0.2794)
							(mid 0.249642 0.249642)
							(end 0.2794 0.1778)
						)
						(arc
							(start 0.2794 -0.1778)
							(mid 0.249642 -0.249642)
							(end 0.1778 -0.2794)
						)
					)
					(width 0)
					(fill yes)
				)
			)
		)
	)
	(footprint ""
		(layer "F.Cu")
		(at 431.927 -133.858 90)
		(property "Reference" "D21"
			(at 0 0 90)
			(layer "F.SilkS")
			(hide yes)
			(effects
				(font
					(size 1.27 1.27)
				)
			)
		)
		(property "Value" "RB551V30-GP"
			(at 0 -6.7818 90)
			(unlocked yes)
			(layer "F.Fab")
			(hide yes)
			(effects
				(font
					(size 1.016 1.016)
					(thickness 0.1524)
				)
			)
		)
		(property "Device Type" "SOD323AKH38"
			(at 0 -8.6868 90)
			(unlocked yes)
			(layer "F.Fab")
			(hide yes)
			(effects
				(font
					(size 1.016 1.016)
					(thickness 0.1524)
				)
			)
		)
		(duplicate_pad_numbers_are_jumpers no)
		(fp_line
			(start 0.889 -1.9304)
			(end 0.889 2.159)
			(stroke
				(width 0.1524)
				(type default)
			)
			(layer "F.SilkS")
		)
		(fp_line
			(start -0.889 -1.9304)
			(end 0.889 -1.9304)
			(stroke
				(width 0.1524)
				(type default)
			)
			(layer "F.SilkS")
		)
		(fp_line
			(start 0.762 2.0574)
			(end -0.762 2.0574)
			(stroke
				(width 0.508)
				(type default)
			)
			(layer "F.SilkS")
		)
		(fp_line
			(start 0.889 2.159)
			(end -0.889 2.159)
			(stroke
				(width 0.1524)
				(type default)
			)
			(layer "F.SilkS")
		)
		(fp_line
			(start -0.889 2.159)
			(end -0.889 -1.9304)
			(stroke
				(width 0.1524)
				(type default)
			)
			(layer "F.SilkS")
		)
		(fp_rect
			(start -1.016 2.3114)
			(end 1.016 -2.0066)
			(stroke
				(width 0)
				(type default)
			)
			(fill no)
			(layer "F.CrtYd")
		)
		(fp_poly
			(pts
				(xy -1.016 -2.0066) (xy 1.016 -2.0066) (xy 1.016 2.3114) (xy -1.016 2.3114)
			)
			(stroke
				(width 0)
				(type default)
			)
			(fill no)
			(layer "F.Fab")
		)
		(pad "A" smd rect
			(at 0 -1.143 90)
			(size 0.5588 1.016)
			(layers "F.Cu" "F.Mask" "F.Paste")
			(net "SW_HDD_R21")
		)
		(pad "K" smd rect
			(at 0 1.143 90)
			(size 0.5588 1.016)
			(layers "F.Cu" "F.Mask" "F.Paste")
			(net "SW_HDD_N21")
		)
	)
	(footprint ""
		(layer "F.Cu")
		(at 29.177996 -373.888 -90)
		(property "Reference" "Q215"
			(at 0 0 270)
			(layer "F.SilkS")
			(hide yes)
			(effects
				(font
					(size 1.27 1.27)
				)
			)
		)
		(property "Value" "2N7002KDW-GP"
			(at -2.3622 -8.2042 270)
			(unlocked yes)
			(layer "F.Fab")
			(hide yes)
			(effects
				(font
					(size 1.016 1.016)
					(thickness 0.1524)
				)
			)
		)
		(property "Device Type" "SOT-363H44"
			(at -2.3622 -10.1092 270)
			(unlocked yes)
			(layer "F.Fab")
			(hide yes)
			(effects
				(font
					(size 1.016 1.016)
					(thickness 0.1524)
				)
			)
		)
		(duplicate_pad_numbers_are_jumpers no)
		(fp_line
			(start -1.4478 1.7018)
			(end 1.4478 1.7018)
			(stroke
				(width 0.1524)
				(type default)
			)
			(layer "F.SilkS")
		)
		(fp_line
			(start 1.4478 1.7018)
			(end 1.4478 -1.7018)
			(stroke
				(width 0.1524)
				(type default)
			)
			(layer "F.SilkS")
		)
		(fp_line
			(start -1.27 1.524)
			(end -1.27 0.6604)
			(stroke
				(width 0.4826)
				(type default)
			)
			(layer "F.SilkS")
		)
		(fp_line
			(start -1.4478 -1.7018)
			(end -1.4478 1.7018)
			(stroke
				(width 0.1524)
				(type default)
			)
			(layer "F.SilkS")
		)
		(fp_line
			(start 1.4478 -1.7018)
			(end -1.4478 -1.7018)
			(stroke
				(width 0.1524)
				(type default)
			)
			(layer "F.SilkS")
		)
		(fp_poly
			(pts
				(xy -1.524 -1.778) (xy 1.524 -1.778) (xy 1.524 1.778) (xy -1.524 1.778)
			)
			(stroke
				(width 0)
				(type default)
			)
			(fill no)
			(layer "F.CrtYd")
		)
		(fp_poly
			(pts
				(xy -1.524 -1.778) (xy 1.524 -1.778) (xy 1.524 1.778) (xy -1.524 1.778)
			)
			(stroke
				(width 0)
				(type default)
			)
			(fill no)
			(layer "F.Fab")
		)
		(pad "1" smd rect
			(at -0.65024 0.9398 270)
			(size 0.4064 1.016)
			(layers "F.Cu" "F.Mask" "F.Paste")
			(net "GND")
		)
		(pad "2" smd rect
			(at 0 0.9398 270)
			(size 0.4064 1.016)
			(layers "F.Cu" "F.Mask" "F.Paste")
			(net "FAN_LED0_D")
		)
		(pad "3" smd rect
			(at 0.65024 0.9398 270)
			(size 0.4064 1.016)
			(layers "F.Cu" "F.Mask" "F.Paste")
			(net "FAN_LED0_D")
		)
		(pad "4" smd rect
			(at 0.65024 -0.9398 270)
			(size 0.4064 1.016)
			(layers "F.Cu" "F.Mask" "F.Paste")
			(net "GND")
		)
		(pad "5" smd rect
			(at 0 -0.9398 270)
			(size 0.4064 1.016)
			(layers "F.Cu" "F.Mask" "F.Paste")
			(net "FAN_LED0")
		)
		(pad "6" smd rect
			(at -0.65024 -0.9398 270)
			(size 0.4064 1.016)
			(layers "F.Cu" "F.Mask" "F.Paste")
			(net "FAN_LED0_D2")
		)
	)
	(footprint ""
		(layer "F.Cu")
		(at 20.066 -262.001 -90)
		(property "Reference" "C499"
			(at 0 0 270)
			(layer "F.SilkS")
			(hide yes)
			(effects
				(font
					(size 1.27 1.27)
				)
			)
		)
		(property "Value" "SC10U16V6KX-2GP"
			(at -0.0762 -5.1308 270)
			(unlocked yes)
			(layer "F.Fab")
			(hide yes)
			(effects
				(font
					(size 1.016 1.016)
					(thickness 0.1524)
				)
			)
		)
		(property "Device Type" "C1206H71"
			(at -0.127 -6.6548 270)
			(unlocked yes)
			(layer "F.Fab")
			(hide yes)
			(effects
				(font
					(size 1.016 1.016)
					(thickness 0.1524)
				)
			)
		)
		(duplicate_pad_numbers_are_jumpers no)
		(fp_line
			(start -1.016 2.2352)
			(end -1.016 0.8382)
			(stroke
				(width 0.1524)
				(type default)
			)
			(layer "F.SilkS")
		)
		(fp_line
			(start 1.016 2.2352)
			(end -1.016 2.2352)
			(stroke
				(width 0.1524)
				(type default)
			)
			(layer "F.SilkS")
		)
		(fp_line
			(start 1.016 0.8382)
			(end 1.016 2.2352)
			(stroke
				(width 0.1524)
				(type default)
			)
			(layer "F.SilkS")
		)
		(fp_line
			(start -1.016 -0.8382)
			(end -1.016 -2.2352)
			(stroke
				(width 0.1524)
				(type default)
			)
			(layer "F.SilkS")
		)
		(fp_line
			(start -1.016 -2.2352)
			(end 1.016 -2.2352)
			(stroke
				(width 0.1524)
				(type default)
			)
			(layer "F.SilkS")
		)
		(fp_line
			(start 1.016 -2.2352)
			(end 1.016 -0.8382)
			(stroke
				(width 0.1524)
				(type default)
			)
			(layer "F.SilkS")
		)
		(fp_rect
			(start -1.0922 2.3114)
			(end 1.0922 -2.3114)
			(stroke
				(width 0)
				(type default)
			)
			(fill no)
			(layer "F.CrtYd")
		)
		(fp_poly
			(pts
				(xy 1.0922 -2.3114) (xy 1.0922 2.3114) (xy -1.0922 2.3114) (xy -1.0922 -2.3114)
			)
			(stroke
				(width 0)
				(type default)
			)
			(fill no)
			(layer "F.Fab")
		)
		(pad "1" smd rect
			(at 0 -1.397 270)
			(size 1.651 1.27)
			(layers "F.Cu" "F.Mask" "F.Paste")
			(net "P5V_HDD0")
		)
		(pad "2" smd rect
			(at 0 1.397 270)
			(size 1.651 1.27)
			(layers "F.Cu" "F.Mask" "F.Paste")
			(net "GND")
		)
	)
	(footprint ""
		(layer "F.Cu")
		(at 44.290996 -357.2256)
		(property "Reference" "D49"
			(at 0 0 0)
			(layer "F.SilkS")
			(hide yes)
			(effects
				(font
					(size 1.27 1.27)
				)
			)
		)
		(property "Value" "RB551V30-GP"
			(at 0 -6.7818 0)
			(unlocked yes)
			(layer "F.Fab")
			(hide yes)
			(effects
				(font
					(size 1.016 1.016)
					(thickness 0.1524)
				)
			)
		)
		(property "Device Type" "SOD323AKH38"
			(at 0 -8.6868 0)
			(unlocked yes)
			(layer "F.Fab")
			(hide yes)
			(effects
				(font
					(size 1.016 1.016)
					(thickness 0.1524)
				)
			)
		)
		(duplicate_pad_numbers_are_jumpers no)
		(fp_line
			(start -0.889 -1.9304)
			(end 0.889 -1.9304)
			(stroke
				(width 0.1524)
				(type default)
			)
			(layer "F.SilkS")
		)
		(fp_line
			(start -0.889 2.159)
			(end -0.889 -1.9304)
			(stroke
				(width 0.1524)
				(type default)
			)
			(layer "F.SilkS")
		)
		(fp_line
			(start 0.762 2.0574)
			(end -0.762 2.0574)
			(stroke
				(width 0.508)
				(type default)
			)
			(layer "F.SilkS")
		)
		(fp_line
			(start 0.889 -1.9304)
			(end 0.889 2.159)
			(stroke
				(width 0.1524)
				(type default)
			)
			(layer "F.SilkS")
		)
		(fp_line
			(start 0.889 2.159)
			(end -0.889 2.159)
			(stroke
				(width 0.1524)
				(type default)
			)
			(layer "F.SilkS")
		)
		(fp_rect
			(start -1.016 2.3114)
			(end 1.016 -2.0066)
			(stroke
				(width 0)
				(type default)
			)
			(fill no)
			(layer "F.CrtYd")
		)
		(fp_poly
			(pts
				(xy -1.016 -2.0066) (xy 1.016 -2.0066) (xy 1.016 2.3114) (xy -1.016 2.3114)
			)
			(stroke
				(width 0)
				(type default)
			)
			(fill no)
			(layer "F.Fab")
		)
		(pad "A" smd rect
			(at 0 -1.143)
			(size 0.5588 1.016)
			(layers "F.Cu" "F.Mask" "F.Paste")
			(net "GATE_FAN0")
		)
		(pad "K" smd rect
			(at 0 1.143)
			(size 0.5588 1.016)
			(layers "F.Cu" "F.Mask" "F.Paste")
			(net "GATE_FAN0_R")
		)
	)
	(footprint ""
		(layer "F.Cu")
		(at 368.3 -148.082)
		(property "Reference" "Q90"
			(at 0 0 0)
			(layer "F.SilkS")
			(hide yes)
			(effects
				(font
					(size 1.27 1.27)
				)
			)
		)
		(property "Value" "AO4407AL-GP"
			(at -3.707384 -1.5367 0)
			(unlocked yes)
			(layer "F.Fab")
			(hide yes)
			(effects
				(font
					(size 1.016 1.016)
					(thickness 0.1524)
				)
			)
		)
		(property "Device Type" "SOIC8H69"
			(at -3.707384 -3.0607 0)
			(unlocked yes)
			(layer "F.Fab")
			(hide yes)
			(effects
				(font
					(size 1.016 1.016)
					(thickness 0.1524)
				)
			)
		)
		(duplicate_pad_numbers_are_jumpers no)
		(fp_line
			(start -2.7432 -1.4224)
			(end -2.7432 1.4224)
			(stroke
				(width 0.1524)
				(type default)
			)
			(layer "F.SilkS")
		)
		(fp_line
			(start -2.7432 1.4224)
			(end -2.6416 1.4224)
			(stroke
				(width 0.1524)
				(type default)
			)
			(layer "F.SilkS")
		)
		(fp_line
			(start -2.7432 1.4224)
			(end 2.1336 1.4224)
			(stroke
				(width 0.1524)
				(type default)
			)
			(layer "F.SilkS")
		)
		(fp_line
			(start -2.7178 -0.508)
			(end -2.1844 -0.0508)
			(stroke
				(width 0.1524)
				(type default)
			)
			(layer "F.SilkS")
		)
		(fp_line
			(start -2.6289 3.4417)
			(end -2.6289 1.4732)
			(stroke
				(width 0.381)
				(type default)
			)
			(layer "F.SilkS")
		)
		(fp_line
			(start -2.1844 -0.0508)
			(end -2.7178 0.508)
			(stroke
				(width 0.1524)
				(type default)
			)
			(layer "F.SilkS")
		)
		(fp_line
			(start 2.1336 -1.4224)
			(end -2.7432 -1.4224)
			(stroke
				(width 0.1524)
				(type default)
			)
			(layer "F.SilkS")
		)
		(fp_line
			(start 2.1336 1.4224)
			(end 2.1336 -1.4224)
			(stroke
				(width 0.1524)
				(type default)
			)
			(layer "F.SilkS")
		)
		(fp_poly
			(pts
				(xy -2.2098 -1.4224) (xy -2.2098 1.4224) (xy 2.2098 1.4224) (xy 2.2098 -1.4224)
			)
			(stroke
				(width 0)
				(type default)
			)
			(fill yes)
			(layer "F.SilkS")
		)
		(fp_rect
			(start -2.450084 2.999994)
			(end 2.450084 -2.999994)
			(stroke
				(width 0)
				(type default)
			)
			(fill no)
			(layer "F.CrtYd")
		)
		(fp_poly
			(pts
				(xy -2.8194 3.6322) (xy -2.8194 -3.6322) (xy 2.8194 -3.6322) (xy 2.8194 1.18364) (xy 2.450084 1.18364)
				(xy 2.450084 -2.999994) (xy -2.450084 -2.999994) (xy -2.450084 2.999994) (xy 2.450084 2.999994)
				(xy 2.450084 1.18618) (xy 2.8194 1.18618) (xy 2.8194 3.6322)
			)
			(stroke
				(width 0)
				(type default)
			)
			(fill no)
			(layer "F.CrtYd")
		)
		(fp_rect
			(start -2.8194 3.6322)
			(end 2.8194 -3.6322)
			(stroke
				(width 0)
				(type default)
			)
			(fill no)
			(layer "F.Fab")
		)
		(pad "1" smd rect
			(at -1.905 2.54)
			(size 0.635 1.651)
			(layers "F.Cu" "F.Mask" "F.Paste")
			(net "P12V_B")
		)
		(pad "2" smd rect
			(at -0.635 2.54)
			(size 0.635 1.651)
			(layers "F.Cu" "F.Mask" "F.Paste")
			(net "P12V_B")
		)
		(pad "3" smd rect
			(at 0.635 2.54)
			(size 0.635 1.651)
			(layers "F.Cu" "F.Mask" "F.Paste")
			(net "P12V_B")
		)
		(pad "4" smd rect
			(at 1.905 2.54)
			(size 0.635 1.651)
			(layers "F.Cu" "F.Mask" "F.Paste")
			(net "SW_HDD_N19")
		)
		(pad "5" smd rect
			(at 1.905 -2.54)
			(size 0.635 1.651)
			(layers "F.Cu" "F.Mask" "F.Paste")
			(net "P12V_HDD19")
		)
		(pad "6" smd rect
			(at 0.635 -2.54)
			(size 0.635 1.651)
			(layers "F.Cu" "F.Mask" "F.Paste")
			(net "P12V_HDD19")
		)
		(pad "7" smd rect
			(at -0.635 -2.54)
			(size 0.635 1.651)
			(layers "F.Cu" "F.Mask" "F.Paste")
			(net "P12V_HDD19")
		)
		(pad "8" smd rect
			(at -1.905 -2.54)
			(size 0.635 1.651)
			(layers "F.Cu" "F.Mask" "F.Paste")
			(net "P12V_HDD19")
		)
	)
	(footprint ""
		(layer "F.Cu")
		(at 331.47 -274.955 180)
		(property "Reference" "C112"
			(at 0 0 180)
			(layer "F.SilkS")
			(hide yes)
			(effects
				(font
					(size 1.27 1.27)
				)
			)
		)
		(property "Value" "SC4D7U25V5KX-1-GP"
			(at -0.0762 -6.1214 180)
			(unlocked yes)
			(layer "F.Fab")
			(hide yes)
			(effects
				(font
					(size 1.016 1.016)
					(thickness 0.1524)
				)
			)
		)
		(property "Device Type" "C805H58"
			(at -0.0762 -8.1534 180)
			(unlocked yes)
			(layer "F.Fab")
			(hide yes)
			(effects
				(font
					(size 1.016 1.016)
					(thickness 0.1524)
				)
			)
		)
		(duplicate_pad_numbers_are_jumpers no)
		(fp_line
			(start 0.635 0)
			(end -0.635 0)
			(stroke
				(width 0.508)
				(type default)
			)
			(layer "F.SilkS")
		)
		(fp_rect
			(start -0.9652 1.778)
			(end 0.9652 -1.778)
			(stroke
				(width 0)
				(type default)
			)
			(fill no)
			(layer "F.CrtYd")
		)
		(fp_poly
			(pts
				(xy -0.9652 -1.778) (xy 0.9652 -1.778) (xy 0.9652 1.778) (xy -0.9652 1.778)
			)
			(stroke
				(width 0)
				(type default)
			)
			(fill no)
			(layer "F.Fab")
		)
		(pad "1" smd rect
			(at 0 -0.9652 180)
			(size 1.397 1.143)
			(layers "F.Cu" "F.Mask" "F.Paste")
			(net "P12V_HDD6")
		)
		(pad "2" smd rect
			(at 0 0.9652 180)
			(size 1.397 1.143)
			(layers "F.Cu" "F.Mask" "F.Paste")
			(net "GND")
		)
	)
	(footprint ""
		(layer "F.Cu")
		(at 447.834512 -245.219474 -90)
		(property "Reference" "C158"
			(at 0 0 270)
			(layer "F.SilkS")
			(hide yes)
			(effects
				(font
					(size 1.27 1.27)
				)
			)
		)
		(property "Value" "SCD01U16V1KX-GP"
			(at -2.8321 -1.7399 270)
			(unlocked yes)
			(layer "F.Fab")
			(hide yes)
			(effects
				(font
					(size 1.016 1.016)
					(thickness 0.1524)
				)
			)
		)
		(property "Device Type" "C0201H13"
			(at -2.8321 -3.2639 270)
			(unlocked yes)
			(layer "F.Fab")
			(hide yes)
			(effects
				(font
					(size 1.016 1.016)
					(thickness 0.1524)
				)
			)
		)
		(duplicate_pad_numbers_are_jumpers no)
		(fp_rect
			(start -0.2794 0.6477)
			(end 0.2794 -0.6477)
			(stroke
				(width 0)
				(type default)
			)
			(fill no)
			(layer "F.CrtYd")
		)
		(fp_rect
			(start -0.2794 0.6477)
			(end 0.2794 -0.6477)
			(stroke
				(width 0)
				(type default)
			)
			(fill no)
			(layer "F.Fab")
		)
		(pad "1" smd custom
			(at 0 -0.2794 270)
			(size 0.0762 0.0762)
			(layers "F.Cu" "F.Mask" "F.Paste")
			(net "SAS_HDD_RX_N10")
			(options
				(clearance outline)
				(anchor circle)
			)
			(primitives
				(gr_poly
					(pts
						(arc
							(start 0.1524 -0.127)
							(mid 0.137521 -0.162921)
							(end 0.1016 -0.1778)
						)
						(arc
							(start -0.1016 -0.1778)
							(mid -0.137521 -0.162921)
							(end -0.1524 -0.127)
						)
						(arc
							(start -0.1524 0.127)
							(mid -0.137521 0.162921)
							(end -0.1016 0.1778)
						)
						(arc
							(start 0.1016 0.1778)
							(mid 0.137521 0.162921)
							(end 0.1524 0.127)
						)
					)
					(width 0)
					(fill yes)
				)
			)
		)
		(pad "2" smd custom
			(at 0 0.2794 270)
			(size 0.0762 0.0762)
			(layers "F.Cu" "F.Mask" "F.Paste")
			(net "PHY_SCC_B_TO_DRV_B_10_DN")
			(options
				(clearance outline)
				(anchor circle)
			)
			(primitives
				(gr_poly
					(pts
						(arc
							(start 0.1524 -0.127)
							(mid 0.137521 -0.162921)
							(end 0.1016 -0.1778)
						)
						(arc
							(start -0.1016 -0.1778)
							(mid -0.137521 -0.162921)
							(end -0.1524 -0.127)
						)
						(arc
							(start -0.1524 0.127)
							(mid -0.137521 0.162921)
							(end -0.1016 0.1778)
						)
						(arc
							(start 0.1016 0.1778)
							(mid 0.137521 0.162921)
							(end 0.1524 0.127)
						)
					)
					(width 0)
					(fill yes)
				)
			)
		)
	)
	(footprint ""
		(layer "F.Cu")
		(at 158.708852 -18.750026 -90)
		(property "Reference" "VIA58"
			(at 0 0 270)
			(layer "F.SilkS")
			(hide yes)
			(effects
				(font
					(size 1.27 1.27)
				)
			)
		)
		(property "Value" "100OHM-8L-2D36MM-L16-GP"
			(at -3.4036 -0.4572 270)
			(unlocked yes)
			(layer "F.Fab")
			(hide yes)
			(effects
				(font
					(size 1.016 1.016)
					(thickness 0.1524)
				)
			)
		)
		(property "Device Type" "VIA-PCIE-4P-427097"
			(at -3.4036 -1.9812 270)
			(unlocked yes)
			(layer "F.Fab")
			(hide yes)
			(effects
				(font
					(size 1.016 1.016)
					(thickness 0.1524)
				)
			)
		)
		(duplicate_pad_numbers_are_jumpers no)
		(fp_rect
			(start -2.1336 0.4826)
			(end 2.1336 -0.4826)
			(stroke
				(width 0)
				(type default)
			)
			(fill no)
			(layer "F.CrtYd")
		)
		(fp_rect
			(start -2.1336 0.4826)
			(end 2.1336 -0.4826)
			(stroke
				(width 0)
				(type default)
			)
			(fill no)
			(layer "F.Fab")
		)
		(pad "1" thru_hole circle
			(at -1.651 0 270)
			(size 0.508 0.508)
			(drill 0.254)
			(layers "*.Cu" "*.Mask")
			(remove_unused_layers no)
			(net "GND")
			(clearance 0.2286)
			(thermal_gap 0.2286)
		)
		(pad "2" thru_hole circle
			(at -0.635 0 270)
			(size 0.508 0.508)
			(drill 0.254)
			(layers "*.Cu" "*.Mask")
			(remove_unused_layers no)
			(net "PHY_DRV_B_TO_SCC_B_28_DP")
			(clearance 0.2286)
			(thermal_gap 0.2286)
		)
		(pad "3" thru_hole circle
			(at 0.635 0 270)
			(size 0.508 0.508)
			(drill 0.254)
			(layers "*.Cu" "*.Mask")
			(remove_unused_layers no)
			(net "PHY_DRV_B_TO_SCC_B_28_DN")
			(clearance 0.2286)
			(thermal_gap 0.2286)
		)
		(pad "4" thru_hole circle
			(at 1.651 0 270)
			(size 0.508 0.508)
			(drill 0.254)
			(layers "*.Cu" "*.Mask")
			(remove_unused_layers no)
			(net "GND")
			(clearance 0.2286)
			(thermal_gap 0.2286)
		)
	)
	(footprint ""
		(layer "F.Cu")
		(at 34.763964 -269.705074)
		(property "Reference" "TP201"
			(at 0 0 0)
			(layer "F.SilkS")
			(hide yes)
			(effects
				(font
					(size 1.27 1.27)
				)
			)
		)
		(property "Value" "*"
			(at -0.0508 -1.6764 0)
			(unlocked yes)
			(layer "F.Fab")
			(hide yes)
			(effects
				(font
					(size 1.016 1.016)
					(thickness 0.1524)
				)
			)
		)
		(property "Device Type" "TPAD32"
			(at -0.0508 -3.2004 0)
			(unlocked yes)
			(layer "F.Fab")
			(hide yes)
			(effects
				(font
					(size 1.016 1.016)
					(thickness 0.1524)
				)
			)
		)
		(duplicate_pad_numbers_are_jumpers no)
		(fp_poly
			(pts
				(arc
					(start 0.4064 0)
					(mid -0.4064 0)
					(end 0.4064 0)
				)
			)
			(stroke
				(width 0)
				(type default)
			)
			(fill no)
			(layer "F.CrtYd")
		)
		(fp_poly
			(pts
				(arc
					(start 0.7112 0)
					(mid -0.7112 0)
					(end 0.7112 0)
				)
			)
			(stroke
				(width 0)
				(type default)
			)
			(fill no)
			(layer "F.Fab")
		)
		(pad "1" smd circle
			(at 0 0)
			(size 0.8128 0.8128)
			(layers "F.Cu" "F.Mask" "F.Paste")
			(net "ACT_HDD_0")
		)
	)
	(footprint ""
		(layer "F.Cu")
		(at 209.03946 -165.40226 -90)
		(property "Reference" "R61"
			(at 0 0 270)
			(layer "F.SilkS")
			(hide yes)
			(effects
				(font
					(size 1.27 1.27)
				)
			)
		)
		(property "Value" "0R2J-2-GP"
			(at 0.064008 -3.993896 270)
			(unlocked yes)
			(layer "F.Fab")
			(hide yes)
			(effects
				(font
					(size 1.016 1.016)
					(thickness 0.1524)
				)
			)
		)
		(property "Device Type" "R402H16"
			(at 0.064008 -5.517896 270)
			(unlocked yes)
			(layer "F.Fab")
			(hide yes)
			(effects
				(font
					(size 1.016 1.016)
					(thickness 0.1524)
				)
			)
		)
		(duplicate_pad_numbers_are_jumpers no)
		(fp_line
			(start -0.508 -0.9398)
			(end -0.508 0.9398)
			(stroke
				(width 0.1524)
				(type default)
			)
			(layer "F.SilkS")
		)
		(fp_line
			(start 0.508 -0.9398)
			(end -0.508 -0.9398)
			(stroke
				(width 0.1524)
				(type default)
			)
			(layer "F.SilkS")
		)
		(fp_rect
			(start -0.508 0.9398)
			(end 0.508 -0.9398)
			(stroke
				(width 0)
				(type default)
			)
			(fill no)
			(layer "F.CrtYd")
		)
		(fp_rect
			(start -0.508 0.9398)
			(end 0.508 -0.9398)
			(stroke
				(width 0)
				(type default)
			)
			(fill no)
			(layer "F.Fab")
		)
		(pad "1" smd custom
			(at 0 -0.4445 270)
			(size 0.1397 0.1397)
			(layers "F.Cu" "F.Mask" "F.Paste")
			(net "IO_EXP6_SCL")
			(options
				(clearance outline)
				(anchor circle)
			)
			(primitives
				(gr_poly
					(pts
						(arc
							(start -0.1778 -0.2794)
							(mid -0.249642 -0.249642)
							(end -0.2794 -0.1778)
						)
						(arc
							(start -0.2794 0.1778)
							(mid -0.249642 0.249642)
							(end -0.1778 0.2794)
						)
						(arc
							(start 0.1778 0.2794)
							(mid 0.249642 0.249642)
							(end 0.2794 0.1778)
						)
						(arc
							(start 0.2794 -0.1778)
							(mid 0.249642 -0.249642)
							(end 0.1778 -0.2794)
						)
					)
					(width 0)
					(fill yes)
				)
			)
		)
		(pad "2" smd custom
			(at 0 0.4445 270)
			(size 0.1397 0.1397)
			(layers "F.Cu" "F.Mask" "F.Paste")
			(net "I2C_DRIVE_B_INS_SCL")
			(options
				(clearance outline)
				(anchor circle)
			)
			(primitives
				(gr_poly
					(pts
						(arc
							(start -0.1778 -0.2794)
							(mid -0.249642 -0.249642)
							(end -0.2794 -0.1778)
						)
						(arc
							(start -0.2794 0.1778)
							(mid -0.249642 0.249642)
							(end -0.1778 0.2794)
						)
						(arc
							(start 0.1778 0.2794)
							(mid 0.249642 0.249642)
							(end 0.2794 0.1778)
						)
						(arc
							(start 0.2794 -0.1778)
							(mid 0.249642 -0.249642)
							(end 0.1778 -0.2794)
						)
					)
					(width 0)
					(fill yes)
				)
			)
		)
	)
	(footprint ""
		(layer "F.Cu")
		(at 264.033 -224.79)
		(property "Reference" "R3"
			(at 0 0 0)
			(layer "F.SilkS")
			(hide yes)
			(effects
				(font
					(size 1.27 1.27)
				)
			)
		)
		(property "Value" "100KR2F-L1-GP"
			(at 0.064008 -3.993896 0)
			(unlocked yes)
			(layer "F.Fab")
			(hide yes)
			(effects
				(font
					(size 1.016 1.016)
					(thickness 0.1524)
				)
			)
		)
		(property "Device Type" "R402H16"
			(at 0.064008 -5.517896 0)
			(unlocked yes)
			(layer "F.Fab")
			(hide yes)
			(effects
				(font
					(size 1.016 1.016)
					(thickness 0.1524)
				)
			)
		)
		(duplicate_pad_numbers_are_jumpers no)
		(fp_line
			(start -0.508 -0.9398)
			(end -0.508 0.9398)
			(stroke
				(width 0.1524)
				(type default)
			)
			(layer "F.SilkS")
		)
		(fp_line
			(start 0.508 -0.9398)
			(end -0.508 -0.9398)
			(stroke
				(width 0.1524)
				(type default)
			)
			(layer "F.SilkS")
		)
		(fp_rect
			(start -0.508 0.9398)
			(end 0.508 -0.9398)
			(stroke
				(width 0)
				(type default)
			)
			(fill no)
			(layer "F.CrtYd")
		)
		(fp_rect
			(start -0.508 0.9398)
			(end 0.508 -0.9398)
			(stroke
				(width 0)
				(type default)
			)
			(fill no)
			(layer "F.Fab")
		)
		(pad "1" smd custom
			(at 0 -0.4445)
			(size 0.1397 0.1397)
			(layers "F.Cu" "F.Mask" "F.Paste")
			(net "P3V3_STBY_B")
			(options
				(clearance outline)
				(anchor circle)
			)
			(primitives
				(gr_poly
					(pts
						(arc
							(start -0.1778 -0.2794)
							(mid -0.249642 -0.249642)
							(end -0.2794 -0.1778)
						)
						(arc
							(start -0.2794 0.1778)
							(mid -0.249642 0.249642)
							(end -0.1778 0.2794)
						)
						(arc
							(start 0.1778 0.2794)
							(mid 0.249642 0.249642)
							(end 0.2794 0.1778)
						)
						(arc
							(start 0.2794 -0.1778)
							(mid 0.249642 -0.249642)
							(end 0.1778 -0.2794)
						)
					)
					(width 0)
					(fill yes)
				)
			)
		)
		(pad "2" smd custom
			(at 0 0.4445)
			(size 0.1397 0.1397)
			(layers "F.Cu" "F.Mask" "F.Paste")
			(net "SCC_B_INS_N")
			(options
				(clearance outline)
				(anchor circle)
			)
			(primitives
				(gr_poly
					(pts
						(arc
							(start -0.1778 -0.2794)
							(mid -0.249642 -0.249642)
							(end -0.2794 -0.1778)
						)
						(arc
							(start -0.2794 0.1778)
							(mid -0.249642 0.249642)
							(end -0.1778 0.2794)
						)
						(arc
							(start 0.1778 0.2794)
							(mid 0.249642 0.249642)
							(end 0.2794 0.1778)
						)
						(arc
							(start 0.2794 -0.1778)
							(mid 0.249642 -0.249642)
							(end 0.1778 -0.2794)
						)
					)
					(width 0)
					(fill yes)
				)
			)
		)
	)
	(footprint ""
		(layer "F.Cu")
		(at 457.0476 -16.0528 90)
		(property "Reference" "R860"
			(at 0 0 90)
			(layer "F.SilkS")
			(hide yes)
			(effects
				(font
					(size 1.27 1.27)
				)
			)
		)
		(property "Value" "1KR2F-3-GP"
			(at 0.064008 -3.993896 90)
			(unlocked yes)
			(layer "F.Fab")
			(hide yes)
			(effects
				(font
					(size 1.016 1.016)
					(thickness 0.1524)
				)
			)
		)
		(property "Device Type" "R402H16"
			(at 0.064008 -5.517896 90)
			(unlocked yes)
			(layer "F.Fab")
			(hide yes)
			(effects
				(font
					(size 1.016 1.016)
					(thickness 0.1524)
				)
			)
		)
		(duplicate_pad_numbers_are_jumpers no)
		(fp_line
			(start 0.508 -0.9398)
			(end -0.508 -0.9398)
			(stroke
				(width 0.1524)
				(type default)
			)
			(layer "F.SilkS")
		)
		(fp_line
			(start -0.508 -0.9398)
			(end -0.508 0.9398)
			(stroke
				(width 0.1524)
				(type default)
			)
			(layer "F.SilkS")
		)
		(fp_rect
			(start -0.508 0.9398)
			(end 0.508 -0.9398)
			(stroke
				(width 0)
				(type default)
			)
			(fill no)
			(layer "F.CrtYd")
		)
		(fp_rect
			(start -0.508 0.9398)
			(end 0.508 -0.9398)
			(stroke
				(width 0)
				(type default)
			)
			(fill no)
			(layer "F.Fab")
		)
		(pad "1" smd custom
			(at 0 -0.4445 90)
			(size 0.1397 0.1397)
			(layers "F.Cu" "F.Mask" "F.Paste")
			(net "P3V3_STBY_B")
			(options
				(clearance outline)
				(anchor circle)
			)
			(primitives
				(gr_poly
					(pts
						(arc
							(start -0.1778 -0.2794)
							(mid -0.249642 -0.249642)
							(end -0.2794 -0.1778)
						)
						(arc
							(start -0.2794 0.1778)
							(mid -0.249642 0.249642)
							(end -0.1778 0.2794)
						)
						(arc
							(start 0.1778 0.2794)
							(mid 0.249642 0.249642)
							(end 0.2794 0.1778)
						)
						(arc
							(start 0.2794 -0.1778)
							(mid 0.249642 -0.249642)
							(end 0.1778 -0.2794)
						)
					)
					(width 0)
					(fill yes)
				)
			)
		)
		(pad "2" smd custom
			(at 0 0.4445 90)
			(size 0.1397 0.1397)
			(layers "F.Cu" "F.Mask" "F.Paste")
			(net "SW_PWR_R_HDD34")
			(options
				(clearance outline)
				(anchor circle)
			)
			(primitives
				(gr_poly
					(pts
						(arc
							(start -0.1778 -0.2794)
							(mid -0.249642 -0.249642)
							(end -0.2794 -0.1778)
						)
						(arc
							(start -0.2794 0.1778)
							(mid -0.249642 0.249642)
							(end -0.1778 0.2794)
						)
						(arc
							(start 0.1778 0.2794)
							(mid 0.249642 0.249642)
							(end 0.2794 0.1778)
						)
						(arc
							(start 0.2794 -0.1778)
							(mid 0.249642 -0.249642)
							(end 0.1778 -0.2794)
						)
					)
					(width 0)
					(fill yes)
				)
			)
		)
	)
	(footprint ""
		(layer "F.Cu")
		(at 64.013334 -129.66065 90)
		(property "Reference" "C198"
			(at 0 0 90)
			(layer "F.SilkS")
			(hide yes)
			(effects
				(font
					(size 1.27 1.27)
				)
			)
		)
		(property "Value" "SCD01U16V1KX-GP"
			(at -2.8321 -1.7399 90)
			(unlocked yes)
			(layer "F.Fab")
			(hide yes)
			(effects
				(font
					(size 1.016 1.016)
					(thickness 0.1524)
				)
			)
		)
		(property "Device Type" "C0201H13"
			(at -2.8321 -3.2639 90)
			(unlocked yes)
			(layer "F.Fab")
			(hide yes)
			(effects
				(font
					(size 1.016 1.016)
					(thickness 0.1524)
				)
			)
		)
		(duplicate_pad_numbers_are_jumpers no)
		(fp_rect
			(start -0.2794 0.6477)
			(end 0.2794 -0.6477)
			(stroke
				(width 0)
				(type default)
			)
			(fill no)
			(layer "F.CrtYd")
		)
		(fp_rect
			(start -0.2794 0.6477)
			(end 0.2794 -0.6477)
			(stroke
				(width 0)
				(type default)
			)
			(fill no)
			(layer "F.Fab")
		)
		(pad "1" smd custom
			(at 0 -0.2794 90)
			(size 0.0762 0.0762)
			(layers "F.Cu" "F.Mask" "F.Paste")
			(net "SAS_HDD_RX_P13")
			(options
				(clearance outline)
				(anchor circle)
			)
			(primitives
				(gr_poly
					(pts
						(arc
							(start 0.1524 -0.127)
							(mid 0.137521 -0.162921)
							(end 0.1016 -0.1778)
						)
						(arc
							(start -0.1016 -0.1778)
							(mid -0.137521 -0.162921)
							(end -0.1524 -0.127)
						)
						(arc
							(start -0.1524 0.127)
							(mid -0.137521 0.162921)
							(end -0.1016 0.1778)
						)
						(arc
							(start 0.1016 0.1778)
							(mid 0.137521 0.162921)
							(end 0.1524 0.127)
						)
					)
					(width 0)
					(fill yes)
				)
			)
		)
		(pad "2" smd custom
			(at 0 0.2794 90)
			(size 0.0762 0.0762)
			(layers "F.Cu" "F.Mask" "F.Paste")
			(net "PHY_SCC_B_TO_DRV_B_13_DP")
			(options
				(clearance outline)
				(anchor circle)
			)
			(primitives
				(gr_poly
					(pts
						(arc
							(start 0.1524 -0.127)
							(mid 0.137521 -0.162921)
							(end 0.1016 -0.1778)
						)
						(arc
							(start -0.1016 -0.1778)
							(mid -0.137521 -0.162921)
							(end -0.1524 -0.127)
						)
						(arc
							(start -0.1524 0.127)
							(mid -0.137521 0.162921)
							(end -0.1016 0.1778)
						)
						(arc
							(start 0.1016 0.1778)
							(mid 0.137521 0.162921)
							(end 0.1524 0.127)
						)
					)
					(width 0)
					(fill yes)
				)
			)
		)
	)
	(footprint ""
		(layer "F.Cu")
		(at 117.221 -13.081 -90)
		(property "Reference" "D27"
			(at 0 0 270)
			(layer "F.SilkS")
			(hide yes)
			(effects
				(font
					(size 1.27 1.27)
				)
			)
		)
		(property "Value" "RB551V30-GP"
			(at 0 -6.7818 270)
			(unlocked yes)
			(layer "F.Fab")
			(hide yes)
			(effects
				(font
					(size 1.016 1.016)
					(thickness 0.1524)
				)
			)
		)
		(property "Device Type" "SOD323AKH38"
			(at 0 -8.6868 270)
			(unlocked yes)
			(layer "F.Fab")
			(hide yes)
			(effects
				(font
					(size 1.016 1.016)
					(thickness 0.1524)
				)
			)
		)
		(duplicate_pad_numbers_are_jumpers no)
		(fp_line
			(start -0.889 2.159)
			(end -0.889 -1.9304)
			(stroke
				(width 0.1524)
				(type default)
			)
			(layer "F.SilkS")
		)
		(fp_line
			(start 0.889 2.159)
			(end -0.889 2.159)
			(stroke
				(width 0.1524)
				(type default)
			)
			(layer "F.SilkS")
		)
		(fp_line
			(start 0.762 2.0574)
			(end -0.762 2.0574)
			(stroke
				(width 0.508)
				(type default)
			)
			(layer "F.SilkS")
		)
		(fp_line
			(start -0.889 -1.9304)
			(end 0.889 -1.9304)
			(stroke
				(width 0.1524)
				(type default)
			)
			(layer "F.SilkS")
		)
		(fp_line
			(start 0.889 -1.9304)
			(end 0.889 2.159)
			(stroke
				(width 0.1524)
				(type default)
			)
			(layer "F.SilkS")
		)
		(fp_rect
			(start -1.016 2.3114)
			(end 1.016 -2.0066)
			(stroke
				(width 0)
				(type default)
			)
			(fill no)
			(layer "F.CrtYd")
		)
		(fp_poly
			(pts
				(xy -1.016 -2.0066) (xy 1.016 -2.0066) (xy 1.016 2.3114) (xy -1.016 2.3114)
			)
			(stroke
				(width 0)
				(type default)
			)
			(fill no)
			(layer "F.Fab")
		)
		(pad "A" smd rect
			(at 0 -1.143 270)
			(size 0.5588 1.016)
			(layers "F.Cu" "F.Mask" "F.Paste")
			(net "SW_HDD_R27")
		)
		(pad "K" smd rect
			(at 0 1.143 270)
			(size 0.5588 1.016)
			(layers "F.Cu" "F.Mask" "F.Paste")
			(net "SW_HDD_N27")
		)
	)
	(footprint ""
		(layer "F.Cu")
		(at 179.8828 -37.8206)
		(property "Reference" "TP166"
			(at 0 0 0)
			(layer "F.SilkS")
			(hide yes)
			(effects
				(font
					(size 1.27 1.27)
				)
			)
		)
		(property "Value" "*"
			(at -0.0508 -1.6764 0)
			(unlocked yes)
			(layer "F.Fab")
			(hide yes)
			(effects
				(font
					(size 1.016 1.016)
					(thickness 0.1524)
				)
			)
		)
		(property "Device Type" "TPAD32"
			(at -0.0508 -3.2004 0)
			(unlocked yes)
			(layer "F.Fab")
			(hide yes)
			(effects
				(font
					(size 1.016 1.016)
					(thickness 0.1524)
				)
			)
		)
		(duplicate_pad_numbers_are_jumpers no)
		(fp_poly
			(pts
				(arc
					(start 0.4064 0)
					(mid -0.4064 0)
					(end 0.4064 0)
				)
			)
			(stroke
				(width 0)
				(type default)
			)
			(fill no)
			(layer "F.CrtYd")
		)
		(fp_poly
			(pts
				(arc
					(start 0.7112 0)
					(mid -0.7112 0)
					(end 0.7112 0)
				)
			)
			(stroke
				(width 0)
				(type default)
			)
			(fill no)
			(layer "F.Fab")
		)
		(pad "1" smd circle
			(at 0 0)
			(size 0.8128 0.8128)
			(layers "F.Cu" "F.Mask" "F.Paste")
			(net "ACT_HDD_29")
		)
	)
	(footprint ""
		(layer "F.Cu")
		(at 337.312 -248.793 90)
		(property "Reference" "D6"
			(at 0 0 90)
			(layer "F.SilkS")
			(hide yes)
			(effects
				(font
					(size 1.27 1.27)
				)
			)
		)
		(property "Value" "RB551V30-GP"
			(at 0 -6.7818 90)
			(unlocked yes)
			(layer "F.Fab")
			(hide yes)
			(effects
				(font
					(size 1.016 1.016)
					(thickness 0.1524)
				)
			)
		)
		(property "Device Type" "SOD323AKH38"
			(at 0 -8.6868 90)
			(unlocked yes)
			(layer "F.Fab")
			(hide yes)
			(effects
				(font
					(size 1.016 1.016)
					(thickness 0.1524)
				)
			)
		)
		(duplicate_pad_numbers_are_jumpers no)
		(fp_line
			(start 0.889 -1.9304)
			(end 0.889 2.159)
			(stroke
				(width 0.1524)
				(type default)
			)
			(layer "F.SilkS")
		)
		(fp_line
			(start -0.889 -1.9304)
			(end 0.889 -1.9304)
			(stroke
				(width 0.1524)
				(type default)
			)
			(layer "F.SilkS")
		)
		(fp_line
			(start 0.762 2.0574)
			(end -0.762 2.0574)
			(stroke
				(width 0.508)
				(type default)
			)
			(layer "F.SilkS")
		)
		(fp_line
			(start 0.889 2.159)
			(end -0.889 2.159)
			(stroke
				(width 0.1524)
				(type default)
			)
			(layer "F.SilkS")
		)
		(fp_line
			(start -0.889 2.159)
			(end -0.889 -1.9304)
			(stroke
				(width 0.1524)
				(type default)
			)
			(layer "F.SilkS")
		)
		(fp_rect
			(start -1.016 2.3114)
			(end 1.016 -2.0066)
			(stroke
				(width 0)
				(type default)
			)
			(fill no)
			(layer "F.CrtYd")
		)
		(fp_poly
			(pts
				(xy -1.016 -2.0066) (xy 1.016 -2.0066) (xy 1.016 2.3114) (xy -1.016 2.3114)
			)
			(stroke
				(width 0)
				(type default)
			)
			(fill no)
			(layer "F.Fab")
		)
		(pad "A" smd rect
			(at 0 -1.143 90)
			(size 0.5588 1.016)
			(layers "F.Cu" "F.Mask" "F.Paste")
			(net "SW_HDD_R6")
		)
		(pad "K" smd rect
			(at 0 1.143 90)
			(size 0.5588 1.016)
			(layers "F.Cu" "F.Mask" "F.Paste")
			(net "SW_HDD_N6")
		)
	)
	(footprint ""
		(layer "F.Cu")
		(at 447.421 -148.209 90)
		(property "Reference" "R576"
			(at 0 0 90)
			(layer "F.SilkS")
			(hide yes)
			(effects
				(font
					(size 1.27 1.27)
				)
			)
		)
		(property "Value" "10KR2F-2-GP"
			(at 0.064008 -3.993896 90)
			(unlocked yes)
			(layer "F.Fab")
			(hide yes)
			(effects
				(font
					(size 1.016 1.016)
					(thickness 0.1524)
				)
			)
		)
		(property "Device Type" "R402H16"
			(at 0.064008 -5.517896 90)
			(unlocked yes)
			(layer "F.Fab")
			(hide yes)
			(effects
				(font
					(size 1.016 1.016)
					(thickness 0.1524)
				)
			)
		)
		(duplicate_pad_numbers_are_jumpers no)
		(fp_line
			(start 0.508 -0.9398)
			(end -0.508 -0.9398)
			(stroke
				(width 0.1524)
				(type default)
			)
			(layer "F.SilkS")
		)
		(fp_line
			(start -0.508 -0.9398)
			(end -0.508 0.9398)
			(stroke
				(width 0.1524)
				(type default)
			)
			(layer "F.SilkS")
		)
		(fp_rect
			(start -0.508 0.9398)
			(end 0.508 -0.9398)
			(stroke
				(width 0)
				(type default)
			)
			(fill no)
			(layer "F.CrtYd")
		)
		(fp_rect
			(start -0.508 0.9398)
			(end 0.508 -0.9398)
			(stroke
				(width 0)
				(type default)
			)
			(fill no)
			(layer "F.Fab")
		)
		(pad "1" smd custom
			(at 0 -0.4445 90)
			(size 0.1397 0.1397)
			(layers "F.Cu" "F.Mask" "F.Paste")
			(net "P3V3_STBY_B")
			(options
				(clearance outline)
				(anchor circle)
			)
			(primitives
				(gr_poly
					(pts
						(arc
							(start -0.1778 -0.2794)
							(mid -0.249642 -0.249642)
							(end -0.2794 -0.1778)
						)
						(arc
							(start -0.2794 0.1778)
							(mid -0.249642 0.249642)
							(end -0.1778 0.2794)
						)
						(arc
							(start 0.1778 0.2794)
							(mid 0.249642 0.249642)
							(end 0.2794 0.1778)
						)
						(arc
							(start 0.2794 -0.1778)
							(mid 0.249642 -0.249642)
							(end 0.1778 -0.2794)
						)
					)
					(width 0)
					(fill yes)
				)
			)
		)
		(pad "2" smd custom
			(at 0 0.4445 90)
			(size 0.1397 0.1397)
			(layers "F.Cu" "F.Mask" "F.Paste")
			(net "HDD_PRSNT_22")
			(options
				(clearance outline)
				(anchor circle)
			)
			(primitives
				(gr_poly
					(pts
						(arc
							(start -0.1778 -0.2794)
							(mid -0.249642 -0.249642)
							(end -0.2794 -0.1778)
						)
						(arc
							(start -0.2794 0.1778)
							(mid -0.249642 0.249642)
							(end -0.1778 0.2794)
						)
						(arc
							(start 0.1778 0.2794)
							(mid 0.249642 0.249642)
							(end 0.2794 0.1778)
						)
						(arc
							(start 0.2794 -0.1778)
							(mid 0.249642 -0.249642)
							(end 0.1778 -0.2794)
						)
					)
					(width 0)
					(fill yes)
				)
			)
		)
	)
	(footprint ""
		(layer "F.Cu")
		(at 54.4576 -133.4008 -90)
		(property "Reference" "R377"
			(at 0 0 270)
			(layer "F.SilkS")
			(hide yes)
			(effects
				(font
					(size 1.27 1.27)
				)
			)
		)
		(property "Value" "1KR2F-3-GP"
			(at 0.064008 -3.993896 270)
			(unlocked yes)
			(layer "F.Fab")
			(hide yes)
			(effects
				(font
					(size 1.016 1.016)
					(thickness 0.1524)
				)
			)
		)
		(property "Device Type" "R402H16"
			(at 0.064008 -5.517896 270)
			(unlocked yes)
			(layer "F.Fab")
			(hide yes)
			(effects
				(font
					(size 1.016 1.016)
					(thickness 0.1524)
				)
			)
		)
		(duplicate_pad_numbers_are_jumpers no)
		(fp_line
			(start -0.508 -0.9398)
			(end -0.508 0.9398)
			(stroke
				(width 0.1524)
				(type default)
			)
			(layer "F.SilkS")
		)
		(fp_line
			(start 0.508 -0.9398)
			(end -0.508 -0.9398)
			(stroke
				(width 0.1524)
				(type default)
			)
			(layer "F.SilkS")
		)
		(fp_rect
			(start -0.508 0.9398)
			(end 0.508 -0.9398)
			(stroke
				(width 0)
				(type default)
			)
			(fill no)
			(layer "F.CrtYd")
		)
		(fp_rect
			(start -0.508 0.9398)
			(end 0.508 -0.9398)
			(stroke
				(width 0)
				(type default)
			)
			(fill no)
			(layer "F.Fab")
		)
		(pad "1" smd custom
			(at 0 -0.4445 270)
			(size 0.1397 0.1397)
			(layers "F.Cu" "F.Mask" "F.Paste")
			(net "P3V3_STBY_B")
			(options
				(clearance outline)
				(anchor circle)
			)
			(primitives
				(gr_poly
					(pts
						(arc
							(start -0.1778 -0.2794)
							(mid -0.249642 -0.249642)
							(end -0.2794 -0.1778)
						)
						(arc
							(start -0.2794 0.1778)
							(mid -0.249642 0.249642)
							(end -0.1778 0.2794)
						)
						(arc
							(start 0.1778 0.2794)
							(mid 0.249642 0.249642)
							(end 0.2794 0.1778)
						)
						(arc
							(start 0.2794 -0.1778)
							(mid 0.249642 -0.249642)
							(end 0.1778 -0.2794)
						)
					)
					(width 0)
					(fill yes)
				)
			)
		)
		(pad "2" smd custom
			(at 0 0.4445 270)
			(size 0.1397 0.1397)
			(layers "F.Cu" "F.Mask" "F.Paste")
			(net "SW_PWR_R_HDD13")
			(options
				(clearance outline)
				(anchor circle)
			)
			(primitives
				(gr_poly
					(pts
						(arc
							(start -0.1778 -0.2794)
							(mid -0.249642 -0.249642)
							(end -0.2794 -0.1778)
						)
						(arc
							(start -0.2794 0.1778)
							(mid -0.249642 0.249642)
							(end -0.1778 0.2794)
						)
						(arc
							(start 0.1778 0.2794)
							(mid 0.249642 0.249642)
							(end 0.2794 0.1778)
						)
						(arc
							(start 0.2794 -0.1778)
							(mid 0.249642 -0.249642)
							(end 0.1778 -0.2794)
						)
					)
					(width 0)
					(fill yes)
				)
			)
		)
	)
	(footprint ""
		(layer "F.Cu")
		(at 32.508952 -248.750074 -90)
		(property "Reference" "VIA2"
			(at 0 0 270)
			(layer "F.SilkS")
			(hide yes)
			(effects
				(font
					(size 1.27 1.27)
				)
			)
		)
		(property "Value" "100OHM-8L-2D36MM-L16-GP"
			(at -3.4036 -0.4572 270)
			(unlocked yes)
			(layer "F.Fab")
			(hide yes)
			(effects
				(font
					(size 1.016 1.016)
					(thickness 0.1524)
				)
			)
		)
		(property "Device Type" "VIA-PCIE-4P-427097"
			(at -3.4036 -1.9812 270)
			(unlocked yes)
			(layer "F.Fab")
			(hide yes)
			(effects
				(font
					(size 1.016 1.016)
					(thickness 0.1524)
				)
			)
		)
		(duplicate_pad_numbers_are_jumpers no)
		(fp_rect
			(start -2.1336 0.4826)
			(end 2.1336 -0.4826)
			(stroke
				(width 0)
				(type default)
			)
			(fill no)
			(layer "F.CrtYd")
		)
		(fp_rect
			(start -2.1336 0.4826)
			(end 2.1336 -0.4826)
			(stroke
				(width 0)
				(type default)
			)
			(fill no)
			(layer "F.Fab")
		)
		(pad "1" thru_hole circle
			(at -1.651 0 270)
			(size 0.508 0.508)
			(drill 0.254)
			(layers "*.Cu" "*.Mask")
			(remove_unused_layers no)
			(net "GND")
			(clearance 0.2286)
			(thermal_gap 0.2286)
		)
		(pad "2" thru_hole circle
			(at -0.635 0 270)
			(size 0.508 0.508)
			(drill 0.254)
			(layers "*.Cu" "*.Mask")
			(remove_unused_layers no)
			(net "PHY_DRV_B_TO_SCC_B_0_DP")
			(clearance 0.2286)
			(thermal_gap 0.2286)
		)
		(pad "3" thru_hole circle
			(at 0.635 0 270)
			(size 0.508 0.508)
			(drill 0.254)
			(layers "*.Cu" "*.Mask")
			(remove_unused_layers no)
			(net "PHY_DRV_B_TO_SCC_B_0_DN")
			(clearance 0.2286)
			(thermal_gap 0.2286)
		)
		(pad "4" thru_hole circle
			(at 1.651 0 270)
			(size 0.508 0.508)
			(drill 0.254)
			(layers "*.Cu" "*.Mask")
			(remove_unused_layers no)
			(net "GND")
			(clearance 0.2286)
			(thermal_gap 0.2286)
		)
	)
	(footprint ""
		(layer "F.Cu")
		(at 82.042 -35.687 90)
		(property "Reference" "R669"
			(at 0 0 90)
			(layer "F.SilkS")
			(hide yes)
			(effects
				(font
					(size 1.27 1.27)
				)
			)
		)
		(property "Value" "2R6F-GP"
			(at -0.0508 -4.8514 90)
			(unlocked yes)
			(layer "F.Fab")
			(hide yes)
			(effects
				(font
					(size 1.016 1.016)
					(thickness 0.1524)
				)
			)
		)
		(property "Device Type" "R1206H26"
			(at 0 -6.3754 90)
			(unlocked yes)
			(layer "F.Fab")
			(hide yes)
			(effects
				(font
					(size 1.016 1.016)
					(thickness 0.1524)
				)
			)
		)
		(duplicate_pad_numbers_are_jumpers no)
		(fp_line
			(start 1.016 -2.2352)
			(end 1.016 2.2352)
			(stroke
				(width 0.1524)
				(type default)
			)
			(layer "F.SilkS")
		)
		(fp_line
			(start -1.016 -2.2352)
			(end 1.016 -2.2352)
			(stroke
				(width 0.1524)
				(type default)
			)
			(layer "F.SilkS")
		)
		(fp_line
			(start 1.016 2.2352)
			(end -1.016 2.2352)
			(stroke
				(width 0.1524)
				(type default)
			)
			(layer "F.SilkS")
		)
		(fp_line
			(start -1.016 2.2352)
			(end -1.016 -2.2352)
			(stroke
				(width 0.1524)
				(type default)
			)
			(layer "F.SilkS")
		)
		(fp_rect
			(start -1.0922 2.3114)
			(end 1.0922 -2.3114)
			(stroke
				(width 0)
				(type default)
			)
			(fill no)
			(layer "F.CrtYd")
		)
		(fp_poly
			(pts
				(xy -1.0922 -2.3114) (xy 1.0922 -2.3114) (xy 1.0922 2.3114) (xy -1.0922 2.3114)
			)
			(stroke
				(width 0)
				(type default)
			)
			(fill no)
			(layer "F.Fab")
		)
		(pad "1" smd rect
			(at 0 -1.397 90)
			(size 1.651 1.27)
			(layers "F.Cu" "F.Mask" "F.Paste")
			(net "P12V_HDD26")
		)
		(pad "2" smd rect
			(at 0 1.397 90)
			(size 1.651 1.27)
			(layers "F.Cu" "F.Mask" "F.Paste")
			(net "12V_PRE_26")
		)
	)
	(footprint ""
		(layer "F.Cu")
		(at 170.84675 -217.337386 -90)
		(property "Reference" "R226"
			(at 0 0 270)
			(layer "F.SilkS")
			(hide yes)
			(effects
				(font
					(size 1.27 1.27)
				)
			)
		)
		(property "Value" "4K7R2F-GP"
			(at 0.064008 -3.993896 270)
			(unlocked yes)
			(layer "F.Fab")
			(hide yes)
			(effects
				(font
					(size 1.016 1.016)
					(thickness 0.1524)
				)
			)
		)
		(property "Device Type" "R402H16"
			(at 0.064008 -5.517896 270)
			(unlocked yes)
			(layer "F.Fab")
			(hide yes)
			(effects
				(font
					(size 1.016 1.016)
					(thickness 0.1524)
				)
			)
		)
		(duplicate_pad_numbers_are_jumpers no)
		(fp_line
			(start -0.508 -0.9398)
			(end -0.508 0.9398)
			(stroke
				(width 0.1524)
				(type default)
			)
			(layer "F.SilkS")
		)
		(fp_line
			(start 0.508 -0.9398)
			(end -0.508 -0.9398)
			(stroke
				(width 0.1524)
				(type default)
			)
			(layer "F.SilkS")
		)
		(fp_rect
			(start -0.508 0.9398)
			(end 0.508 -0.9398)
			(stroke
				(width 0)
				(type default)
			)
			(fill no)
			(layer "F.CrtYd")
		)
		(fp_rect
			(start -0.508 0.9398)
			(end 0.508 -0.9398)
			(stroke
				(width 0)
				(type default)
			)
			(fill no)
			(layer "F.Fab")
		)
		(pad "1" smd custom
			(at 0 -0.4445 270)
			(size 0.1397 0.1397)
			(layers "F.Cu" "F.Mask" "F.Paste")
			(net "DRIVE_B_5_FLT_LED")
			(options
				(clearance outline)
				(anchor circle)
			)
			(primitives
				(gr_poly
					(pts
						(arc
							(start -0.1778 -0.2794)
							(mid -0.249642 -0.249642)
							(end -0.2794 -0.1778)
						)
						(arc
							(start -0.2794 0.1778)
							(mid -0.249642 0.249642)
							(end -0.1778 0.2794)
						)
						(arc
							(start 0.1778 0.2794)
							(mid 0.249642 0.249642)
							(end 0.2794 0.1778)
						)
						(arc
							(start 0.2794 -0.1778)
							(mid 0.249642 -0.249642)
							(end 0.1778 -0.2794)
						)
					)
					(width 0)
					(fill yes)
				)
			)
		)
		(pad "2" smd custom
			(at 0 0.4445 270)
			(size 0.1397 0.1397)
			(layers "F.Cu" "F.Mask" "F.Paste")
			(net "GND")
			(options
				(clearance outline)
				(anchor circle)
			)
			(primitives
				(gr_poly
					(pts
						(arc
							(start -0.1778 -0.2794)
							(mid -0.249642 -0.249642)
							(end -0.2794 -0.1778)
						)
						(arc
							(start -0.2794 0.1778)
							(mid -0.249642 0.249642)
							(end -0.1778 0.2794)
						)
						(arc
							(start 0.1778 0.2794)
							(mid 0.249642 0.249642)
							(end 0.2794 0.1778)
						)
						(arc
							(start 0.2794 -0.1778)
							(mid 0.249642 -0.249642)
							(end 0.1778 -0.2794)
						)
					)
					(width 0)
					(fill yes)
				)
			)
		)
	)
	(footprint ""
		(layer "F.Cu")
		(at 368.427 -16.764 180)
		(property "Reference" "R796"
			(at 0 0 180)
			(layer "F.SilkS")
			(hide yes)
			(effects
				(font
					(size 1.27 1.27)
				)
			)
		)
		(property "Value" "4K7R2J-2-GP"
			(at 0.064008 -3.993896 180)
			(unlocked yes)
			(layer "F.Fab")
			(hide yes)
			(effects
				(font
					(size 1.016 1.016)
					(thickness 0.1524)
				)
			)
		)
		(property "Device Type" "R402H16"
			(at 0.064008 -5.517896 180)
			(unlocked yes)
			(layer "F.Fab")
			(hide yes)
			(effects
				(font
					(size 1.016 1.016)
					(thickness 0.1524)
				)
			)
		)
		(duplicate_pad_numbers_are_jumpers no)
		(fp_line
			(start 0.508 -0.9398)
			(end -0.508 -0.9398)
			(stroke
				(width 0.1524)
				(type default)
			)
			(layer "F.SilkS")
		)
		(fp_line
			(start -0.508 -0.9398)
			(end -0.508 0.9398)
			(stroke
				(width 0.1524)
				(type default)
			)
			(layer "F.SilkS")
		)
		(fp_rect
			(start -0.508 0.9398)
			(end 0.508 -0.9398)
			(stroke
				(width 0)
				(type default)
			)
			(fill no)
			(layer "F.CrtYd")
		)
		(fp_rect
			(start -0.508 0.9398)
			(end 0.508 -0.9398)
			(stroke
				(width 0)
				(type default)
			)
			(fill no)
			(layer "F.Fab")
		)
		(pad "1" smd custom
			(at 0 -0.4445 180)
			(size 0.1397 0.1397)
			(layers "F.Cu" "F.Mask" "F.Paste")
			(net "P12V_B")
			(options
				(clearance outline)
				(anchor circle)
			)
			(primitives
				(gr_poly
					(pts
						(arc
							(start -0.1778 -0.2794)
							(mid -0.249642 -0.249642)
							(end -0.2794 -0.1778)
						)
						(arc
							(start -0.2794 0.1778)
							(mid -0.249642 0.249642)
							(end -0.1778 0.2794)
						)
						(arc
							(start 0.1778 0.2794)
							(mid 0.249642 0.249642)
							(end 0.2794 0.1778)
						)
						(arc
							(start 0.2794 -0.1778)
							(mid 0.249642 -0.249642)
							(end 0.1778 -0.2794)
						)
					)
					(width 0)
					(fill yes)
				)
			)
		)
		(pad "2" smd custom
			(at 0 0.4445 180)
			(size 0.1397 0.1397)
			(layers "F.Cu" "F.Mask" "F.Paste")
			(net "SW_HDD_R31")
			(options
				(clearance outline)
				(anchor circle)
			)
			(primitives
				(gr_poly
					(pts
						(arc
							(start -0.1778 -0.2794)
							(mid -0.249642 -0.249642)
							(end -0.2794 -0.1778)
						)
						(arc
							(start -0.2794 0.1778)
							(mid -0.249642 0.249642)
							(end -0.1778 0.2794)
						)
						(arc
							(start 0.1778 0.2794)
							(mid 0.249642 0.249642)
							(end 0.2794 0.1778)
						)
						(arc
							(start 0.2794 -0.1778)
							(mid 0.249642 -0.249642)
							(end 0.1778 -0.2794)
						)
					)
					(width 0)
					(fill yes)
				)
			)
		)
	)
	(footprint ""
		(layer "F.Cu")
		(at 253.492 -283.718)
		(property "Reference" "C689"
			(at 0 0 0)
			(layer "F.SilkS")
			(hide yes)
			(effects
				(font
					(size 1.27 1.27)
				)
			)
		)
		(property "Value" "SC1U16V3KX-5GP"
			(at 0 -2.8194 0)
			(unlocked yes)
			(layer "F.Fab")
			(hide yes)
			(effects
				(font
					(size 1.016 1.016)
					(thickness 0.1524)
				)
			)
		)
		(property "Device Type" "C603H36"
			(at 0 -4.3434 0)
			(unlocked yes)
			(layer "F.Fab")
			(hide yes)
			(effects
				(font
					(size 1.016 1.016)
					(thickness 0.1524)
				)
			)
		)
		(duplicate_pad_numbers_are_jumpers no)
		(fp_line
			(start 0.508 0)
			(end -0.508 0)
			(stroke
				(width 0.2032)
				(type default)
			)
			(layer "F.SilkS")
		)
		(fp_rect
			(start -0.5842 1.3335)
			(end 0.5842 -1.3335)
			(stroke
				(width 0)
				(type default)
			)
			(fill no)
			(layer "F.CrtYd")
		)
		(fp_rect
			(start -0.5842 1.3335)
			(end 0.5842 -1.3335)
			(stroke
				(width 0)
				(type default)
			)
			(fill no)
			(layer "F.Fab")
		)
		(pad "1" smd custom
			(at 0 -0.762)
			(size 0.2159 0.2159)
			(layers "F.Cu" "F.Mask" "F.Paste")
			(net "P3V3_STBY_VCC")
			(options
				(clearance outline)
				(anchor circle)
			)
			(primitives
				(gr_poly
					(pts
						(arc
							(start -0.3302 -0.4318)
							(mid -0.402042 -0.402042)
							(end -0.4318 -0.3302)
						)
						(arc
							(start -0.4318 0.3302)
							(mid -0.402042 0.402042)
							(end -0.3302 0.4318)
						)
						(arc
							(start 0.3302 0.4318)
							(mid 0.402042 0.402042)
							(end 0.4318 0.3302)
						)
						(arc
							(start 0.4318 -0.3302)
							(mid 0.402042 -0.402042)
							(end 0.3302 -0.4318)
						)
					)
					(width 0)
					(fill yes)
				)
			)
		)
		(pad "2" smd custom
			(at 0 0.762)
			(size 0.2159 0.2159)
			(layers "F.Cu" "F.Mask" "F.Paste")
			(net "GND")
			(options
				(clearance outline)
				(anchor circle)
			)
			(primitives
				(gr_poly
					(pts
						(arc
							(start -0.3302 -0.4318)
							(mid -0.402042 -0.402042)
							(end -0.4318 -0.3302)
						)
						(arc
							(start -0.4318 0.3302)
							(mid -0.402042 0.402042)
							(end -0.3302 0.4318)
						)
						(arc
							(start 0.3302 0.4318)
							(mid 0.402042 0.402042)
							(end 0.4318 0.3302)
						)
						(arc
							(start 0.4318 -0.3302)
							(mid 0.402042 -0.402042)
							(end 0.3302 -0.4318)
						)
					)
					(width 0)
					(fill yes)
				)
			)
		)
	)
	(footprint ""
		(layer "F.Cu")
		(at 146.685 -134.493 180)
		(property "Reference" "Q71"
			(at 0 0 180)
			(layer "F.SilkS")
			(hide yes)
			(effects
				(font
					(size 1.27 1.27)
				)
			)
		)
		(property "Value" "2N7002KDW-GP"
			(at -2.3622 -8.2042 180)
			(unlocked yes)
			(layer "F.Fab")
			(hide yes)
			(effects
				(font
					(size 1.016 1.016)
					(thickness 0.1524)
				)
			)
		)
		(property "Device Type" "SOT-363H44"
			(at -2.3622 -10.1092 180)
			(unlocked yes)
			(layer "F.Fab")
			(hide yes)
			(effects
				(font
					(size 1.016 1.016)
					(thickness 0.1524)
				)
			)
		)
		(duplicate_pad_numbers_are_jumpers no)
		(fp_line
			(start 1.4478 1.7018)
			(end 1.4478 -1.7018)
			(stroke
				(width 0.1524)
				(type default)
			)
			(layer "F.SilkS")
		)
		(fp_line
			(start 1.4478 -1.7018)
			(end -1.4478 -1.7018)
			(stroke
				(width 0.1524)
				(type default)
			)
			(layer "F.SilkS")
		)
		(fp_line
			(start -1.27 1.524)
			(end -1.27 0.6604)
			(stroke
				(width 0.4826)
				(type default)
			)
			(layer "F.SilkS")
		)
		(fp_line
			(start -1.4478 1.7018)
			(end 1.4478 1.7018)
			(stroke
				(width 0.1524)
				(type default)
			)
			(layer "F.SilkS")
		)
		(fp_line
			(start -1.4478 -1.7018)
			(end -1.4478 1.7018)
			(stroke
				(width 0.1524)
				(type default)
			)
			(layer "F.SilkS")
		)
		(fp_poly
			(pts
				(xy -1.524 -1.778) (xy 1.524 -1.778) (xy 1.524 1.778) (xy -1.524 1.778)
			)
			(stroke
				(width 0)
				(type default)
			)
			(fill no)
			(layer "F.CrtYd")
		)
		(fp_poly
			(pts
				(xy -1.524 -1.778) (xy 1.524 -1.778) (xy 1.524 1.778) (xy -1.524 1.778)
			)
			(stroke
				(width 0)
				(type default)
			)
			(fill no)
			(layer "F.Fab")
		)
		(pad "1" smd rect
			(at -0.65024 0.9398 180)
			(size 0.4064 1.016)
			(layers "F.Cu" "F.Mask" "F.Paste")
			(net "GND")
		)
		(pad "2" smd rect
			(at 0 0.9398 180)
			(size 0.4064 1.016)
			(layers "F.Cu" "F.Mask" "F.Paste")
			(net "SW_PWR_R_HDD16")
		)
		(pad "3" smd rect
			(at 0.65024 0.9398 180)
			(size 0.4064 1.016)
			(layers "F.Cu" "F.Mask" "F.Paste")
			(net "SW_HDD_P16")
		)
		(pad "4" smd rect
			(at 0.65024 -0.9398 180)
			(size 0.4064 1.016)
			(layers "F.Cu" "F.Mask" "F.Paste")
			(net "GND")
		)
		(pad "5" smd rect
			(at 0 -0.9398 180)
			(size 0.4064 1.016)
			(layers "F.Cu" "F.Mask" "F.Paste")
			(net "SW_HDD_G16")
		)
		(pad "6" smd rect
			(at -0.65024 -0.9398 180)
			(size 0.4064 1.016)
			(layers "F.Cu" "F.Mask" "F.Paste")
			(net "SW_HDD_R16")
		)
	)
	(footprint ""
		(layer "F.Cu")
		(at 338.709 -258.826 90)
		(property "Reference" "C117"
			(at 0 0 90)
			(layer "F.SilkS")
			(hide yes)
			(effects
				(font
					(size 1.27 1.27)
				)
			)
		)
		(property "Value" "SCD033U25V2KX-GP"
			(at 1.1811 -2.7051 90)
			(unlocked yes)
			(layer "F.Fab")
			(hide yes)
			(effects
				(font
					(size 1.016 1.016)
					(thickness 0.1524)
				)
			)
		)
		(property "Device Type" "C402H22"
			(at 1.1811 -4.2291 90)
			(unlocked yes)
			(layer "F.Fab")
			(hide yes)
			(effects
				(font
					(size 1.016 1.016)
					(thickness 0.1524)
				)
			)
		)
		(duplicate_pad_numbers_are_jumpers no)
		(fp_rect
			(start -0.4318 0.9525)
			(end 0.4318 -0.9525)
			(stroke
				(width 0)
				(type default)
			)
			(fill no)
			(layer "F.CrtYd")
		)
		(fp_rect
			(start -0.4318 0.9525)
			(end 0.4318 -0.9525)
			(stroke
				(width 0)
				(type default)
			)
			(fill no)
			(layer "F.Fab")
		)
		(pad "1" smd custom
			(at 0 -0.4445 90)
			(size 0.1524 0.1524)
			(layers "F.Cu" "F.Mask" "F.Paste")
			(net "P12V_B")
			(options
				(clearance outline)
				(anchor circle)
			)
			(primitives
				(gr_poly
					(pts
						(arc
							(start 0.3048 -0.2032)
							(mid 0.275042 -0.275042)
							(end 0.2032 -0.3048)
						)
						(arc
							(start -0.2032 -0.3048)
							(mid -0.275042 -0.275042)
							(end -0.3048 -0.2032)
						)
						(arc
							(start -0.3048 0.2032)
							(mid -0.275042 0.275042)
							(end -0.2032 0.3048)
						)
						(arc
							(start 0.2032 0.3048)
							(mid 0.275042 0.275042)
							(end 0.3048 0.2032)
						)
					)
					(width 0)
					(fill yes)
				)
			)
		)
		(pad "2" smd custom
			(at 0 0.4445 90)
			(size 0.1524 0.1524)
			(layers "F.Cu" "F.Mask" "F.Paste")
			(net "SW_HDD_N6")
			(options
				(clearance outline)
				(anchor circle)
			)
			(primitives
				(gr_poly
					(pts
						(arc
							(start 0.3048 -0.2032)
							(mid 0.275042 -0.275042)
							(end 0.2032 -0.3048)
						)
						(arc
							(start -0.2032 -0.3048)
							(mid -0.275042 -0.275042)
							(end -0.3048 -0.2032)
						)
						(arc
							(start -0.3048 0.2032)
							(mid -0.275042 0.275042)
							(end -0.2032 0.3048)
						)
						(arc
							(start 0.2032 0.3048)
							(mid 0.275042 0.275042)
							(end 0.3048 0.2032)
						)
					)
					(width 0)
					(fill yes)
				)
			)
		)
	)
	(footprint ""
		(layer "F.Cu")
		(at 169.47515 -102.351586 -90)
		(property "Reference" "R395"
			(at 0 0 270)
			(layer "F.SilkS")
			(hide yes)
			(effects
				(font
					(size 1.27 1.27)
				)
			)
		)
		(property "Value" "4K7R2F-GP"
			(at 0.064008 -3.993896 270)
			(unlocked yes)
			(layer "F.Fab")
			(hide yes)
			(effects
				(font
					(size 1.016 1.016)
					(thickness 0.1524)
				)
			)
		)
		(property "Device Type" "R402H16"
			(at 0.064008 -5.517896 270)
			(unlocked yes)
			(layer "F.Fab")
			(hide yes)
			(effects
				(font
					(size 1.016 1.016)
					(thickness 0.1524)
				)
			)
		)
		(duplicate_pad_numbers_are_jumpers no)
		(fp_line
			(start -0.508 -0.9398)
			(end -0.508 0.9398)
			(stroke
				(width 0.1524)
				(type default)
			)
			(layer "F.SilkS")
		)
		(fp_line
			(start 0.508 -0.9398)
			(end -0.508 -0.9398)
			(stroke
				(width 0.1524)
				(type default)
			)
			(layer "F.SilkS")
		)
		(fp_rect
			(start -0.508 0.9398)
			(end 0.508 -0.9398)
			(stroke
				(width 0)
				(type default)
			)
			(fill no)
			(layer "F.CrtYd")
		)
		(fp_rect
			(start -0.508 0.9398)
			(end 0.508 -0.9398)
			(stroke
				(width 0)
				(type default)
			)
			(fill no)
			(layer "F.Fab")
		)
		(pad "1" smd custom
			(at 0 -0.4445 270)
			(size 0.1397 0.1397)
			(layers "F.Cu" "F.Mask" "F.Paste")
			(net "DRIVE_B_17_FLT_LED")
			(options
				(clearance outline)
				(anchor circle)
			)
			(primitives
				(gr_poly
					(pts
						(arc
							(start -0.1778 -0.2794)
							(mid -0.249642 -0.249642)
							(end -0.2794 -0.1778)
						)
						(arc
							(start -0.2794 0.1778)
							(mid -0.249642 0.249642)
							(end -0.1778 0.2794)
						)
						(arc
							(start 0.1778 0.2794)
							(mid 0.249642 0.249642)
							(end 0.2794 0.1778)
						)
						(arc
							(start 0.2794 -0.1778)
							(mid 0.249642 -0.249642)
							(end 0.1778 -0.2794)
						)
					)
					(width 0)
					(fill yes)
				)
			)
		)
		(pad "2" smd custom
			(at 0 0.4445 270)
			(size 0.1397 0.1397)
			(layers "F.Cu" "F.Mask" "F.Paste")
			(net "GND")
			(options
				(clearance outline)
				(anchor circle)
			)
			(primitives
				(gr_poly
					(pts
						(arc
							(start -0.1778 -0.2794)
							(mid -0.249642 -0.249642)
							(end -0.2794 -0.1778)
						)
						(arc
							(start -0.2794 0.1778)
							(mid -0.249642 0.249642)
							(end -0.1778 0.2794)
						)
						(arc
							(start 0.1778 0.2794)
							(mid 0.249642 0.249642)
							(end 0.2794 0.1778)
						)
						(arc
							(start 0.2794 -0.1778)
							(mid 0.249642 -0.249642)
							(end 0.1778 -0.2794)
						)
					)
					(width 0)
					(fill yes)
				)
			)
		)
	)
	(footprint ""
		(layer "F.Cu")
		(at 20.1422 -263.7536 -90)
		(property "Reference" "C498"
			(at 0 0 270)
			(layer "F.SilkS")
			(hide yes)
			(effects
				(font
					(size 1.27 1.27)
				)
			)
		)
		(property "Value" "SC1U16V3KX-5GP"
			(at 0 -2.8194 270)
			(unlocked yes)
			(layer "F.Fab")
			(hide yes)
			(effects
				(font
					(size 1.016 1.016)
					(thickness 0.1524)
				)
			)
		)
		(property "Device Type" "C603H36"
			(at 0 -4.3434 270)
			(unlocked yes)
			(layer "F.Fab")
			(hide yes)
			(effects
				(font
					(size 1.016 1.016)
					(thickness 0.1524)
				)
			)
		)
		(duplicate_pad_numbers_are_jumpers no)
		(fp_line
			(start 0.508 0)
			(end -0.508 0)
			(stroke
				(width 0.2032)
				(type default)
			)
			(layer "F.SilkS")
		)
		(fp_rect
			(start -0.5842 1.3335)
			(end 0.5842 -1.3335)
			(stroke
				(width 0)
				(type default)
			)
			(fill no)
			(layer "F.CrtYd")
		)
		(fp_rect
			(start -0.5842 1.3335)
			(end 0.5842 -1.3335)
			(stroke
				(width 0)
				(type default)
			)
			(fill no)
			(layer "F.Fab")
		)
		(pad "1" smd custom
			(at 0 -0.762 270)
			(size 0.2159 0.2159)
			(layers "F.Cu" "F.Mask" "F.Paste")
			(net "P5V_HDD0")
			(options
				(clearance outline)
				(anchor circle)
			)
			(primitives
				(gr_poly
					(pts
						(arc
							(start -0.3302 -0.4318)
							(mid -0.402042 -0.402042)
							(end -0.4318 -0.3302)
						)
						(arc
							(start -0.4318 0.3302)
							(mid -0.402042 0.402042)
							(end -0.3302 0.4318)
						)
						(arc
							(start 0.3302 0.4318)
							(mid 0.402042 0.402042)
							(end 0.4318 0.3302)
						)
						(arc
							(start 0.4318 -0.3302)
							(mid 0.402042 -0.402042)
							(end 0.3302 -0.4318)
						)
					)
					(width 0)
					(fill yes)
				)
			)
		)
		(pad "2" smd custom
			(at 0 0.762 270)
			(size 0.2159 0.2159)
			(layers "F.Cu" "F.Mask" "F.Paste")
			(net "GND")
			(options
				(clearance outline)
				(anchor circle)
			)
			(primitives
				(gr_poly
					(pts
						(arc
							(start -0.3302 -0.4318)
							(mid -0.402042 -0.402042)
							(end -0.4318 -0.3302)
						)
						(arc
							(start -0.4318 0.3302)
							(mid -0.402042 0.402042)
							(end -0.3302 0.4318)
						)
						(arc
							(start 0.3302 0.4318)
							(mid 0.402042 0.402042)
							(end 0.4318 0.3302)
						)
						(arc
							(start 0.4318 -0.3302)
							(mid 0.402042 -0.402042)
							(end 0.3302 -0.4318)
						)
					)
					(width 0)
					(fill yes)
				)
			)
		)
	)
	(footprint ""
		(layer "F.Cu")
		(at 475.7166 -11.176)
		(property "Reference" "R885"
			(at 0 0 0)
			(layer "F.SilkS")
			(hide yes)
			(effects
				(font
					(size 1.27 1.27)
				)
			)
		)
		(property "Value" "0R2J-2-GP"
			(at 0.064008 -3.993896 0)
			(unlocked yes)
			(layer "F.Fab")
			(hide yes)
			(effects
				(font
					(size 1.016 1.016)
					(thickness 0.1524)
				)
			)
		)
		(property "Device Type" "R402H16"
			(at 0.064008 -5.517896 0)
			(unlocked yes)
			(layer "F.Fab")
			(hide yes)
			(effects
				(font
					(size 1.016 1.016)
					(thickness 0.1524)
				)
			)
		)
		(duplicate_pad_numbers_are_jumpers no)
		(fp_line
			(start -0.508 -0.9398)
			(end -0.508 0.9398)
			(stroke
				(width 0.1524)
				(type default)
			)
			(layer "F.SilkS")
		)
		(fp_line
			(start 0.508 -0.9398)
			(end -0.508 -0.9398)
			(stroke
				(width 0.1524)
				(type default)
			)
			(layer "F.SilkS")
		)
		(fp_rect
			(start -0.508 0.9398)
			(end 0.508 -0.9398)
			(stroke
				(width 0)
				(type default)
			)
			(fill no)
			(layer "F.CrtYd")
		)
		(fp_rect
			(start -0.508 0.9398)
			(end 0.508 -0.9398)
			(stroke
				(width 0)
				(type default)
			)
			(fill no)
			(layer "F.Fab")
		)
		(pad "1" smd custom
			(at 0 -0.4445)
			(size 0.1397 0.1397)
			(layers "F.Cu" "F.Mask" "F.Paste")
			(net "DRIVE_B_35_PWR")
			(options
				(clearance outline)
				(anchor circle)
			)
			(primitives
				(gr_poly
					(pts
						(arc
							(start -0.1778 -0.2794)
							(mid -0.249642 -0.249642)
							(end -0.2794 -0.1778)
						)
						(arc
							(start -0.2794 0.1778)
							(mid -0.249642 0.249642)
							(end -0.1778 0.2794)
						)
						(arc
							(start 0.1778 0.2794)
							(mid 0.249642 0.249642)
							(end 0.2794 0.1778)
						)
						(arc
							(start 0.2794 -0.1778)
							(mid 0.249642 -0.249642)
							(end 0.1778 -0.2794)
						)
					)
					(width 0)
					(fill yes)
				)
			)
		)
		(pad "2" smd custom
			(at 0 0.4445)
			(size 0.1397 0.1397)
			(layers "F.Cu" "F.Mask" "F.Paste")
			(net "SW_PWR_R_HDD35")
			(options
				(clearance outline)
				(anchor circle)
			)
			(primitives
				(gr_poly
					(pts
						(arc
							(start -0.1778 -0.2794)
							(mid -0.249642 -0.249642)
							(end -0.2794 -0.1778)
						)
						(arc
							(start -0.2794 0.1778)
							(mid -0.249642 0.249642)
							(end -0.1778 0.2794)
						)
						(arc
							(start 0.1778 0.2794)
							(mid 0.249642 0.249642)
							(end 0.2794 0.1778)
						)
						(arc
							(start 0.2794 -0.1778)
							(mid 0.249642 -0.249642)
							(end 0.1778 -0.2794)
						)
					)
					(width 0)
					(fill yes)
				)
			)
		)
	)
	(footprint ""
		(layer "F.Cu")
		(at 154.399996 -28.910026 -90)
		(property "Reference" "HDDSAS28"
			(at 0 0 270)
			(layer "F.SilkS")
			(hide yes)
			(effects
				(font
					(size 1.27 1.27)
				)
			)
		)
		(property "Value" "SKT-SAS15P-14P-45-GP"
			(at -20.7645 -8.9789 270)
			(unlocked yes)
			(layer "F.Fab")
			(hide yes)
			(effects
				(font
					(size 1.016 1.016)
					(thickness 0.1524)
				)
			)
		)
		(property "Device Type" "10120818-001C-TRLF"
			(at -20.7645 -10.5029 270)
			(unlocked yes)
			(layer "F.Fab")
			(hide yes)
			(effects
				(font
					(size 1.016 1.016)
					(thickness 0.1524)
				)
			)
		)
		(duplicate_pad_numbers_are_jumpers no)
		(fp_line
			(start 1.651 4.2926)
			(end 1.651 3.0099)
			(stroke
				(width 0.1524)
				(type default)
			)
			(layer "F.SilkS")
		)
		(fp_line
			(start 8.509 4.2926)
			(end 1.651 4.2926)
			(stroke
				(width 0.1524)
				(type default)
			)
			(layer "F.SilkS")
		)
		(fp_line
			(start -23.4188 3.0099)
			(end -23.4188 -3.2512)
			(stroke
				(width 0.1524)
				(type default)
			)
			(layer "F.SilkS")
		)
		(fp_line
			(start 1.651 3.0099)
			(end -23.4188 3.0099)
			(stroke
				(width 0.1524)
				(type default)
			)
			(layer "F.SilkS")
		)
		(fp_line
			(start 8.509 3.0099)
			(end 8.509 4.2926)
			(stroke
				(width 0.1524)
				(type default)
			)
			(layer "F.SilkS")
		)
		(fp_line
			(start 23.4188 3.0099)
			(end 8.509 3.0099)
			(stroke
				(width 0.1524)
				(type default)
			)
			(layer "F.SilkS")
		)
		(fp_line
			(start -23.4188 -3.2512)
			(end 23.4188 -3.2512)
			(stroke
				(width 0.1524)
				(type default)
			)
			(layer "F.SilkS")
		)
		(fp_line
			(start 23.4188 -3.2512)
			(end 23.4188 3.0099)
			(stroke
				(width 0.1524)
				(type default)
			)
			(layer "F.SilkS")
		)
		(fp_line
			(start 15.5067 -3.3401)
			(end 16.2687 -3.3401)
			(stroke
				(width 0.3302)
				(type default)
			)
			(layer "F.SilkS")
		)
		(fp_poly
			(pts
				(xy 15.868904 -3.230372) (xy 16.503904 -3.865372) (xy 15.233904 -3.865372)
			)
			(stroke
				(width 0)
				(type default)
			)
			(fill yes)
			(layer "F.SilkS")
		)
		(fp_poly
			(pts
				(xy -22.8727 -2.7559) (xy 22.8727 -2.7559) (xy 22.8727 2.7559) (xy 8.255 2.7559) (xy 8.255 3.5179)
				(xy 1.905 3.5179) (xy 1.905 2.7559) (xy -22.8727 2.7559)
			)
			(stroke
				(width 0)
				(type default)
			)
			(fill no)
			(layer "F.CrtYd")
		)
		(fp_poly
			(pts
				(xy 1.397 4.5466) (xy 1.397 3.2639) (xy -23.6728 3.2639) (xy -23.6728 -3.5052) (xy 23.6728 -3.5052)
				(xy 23.6728 -0.00635) (xy 22.8727 -0.00635) (xy 22.8727 -2.7559) (xy -22.8727 -2.7559) (xy -22.8727 2.7559)
				(xy 1.905 2.7559) (xy 1.905 3.5179) (xy 8.255 3.5179) (xy 8.255 2.7559) (xy 22.8727 2.7559) (xy 22.8727 0.00635)
				(xy 23.6728 0.00635) (xy 23.6728 3.2639) (xy 8.763 3.2639) (xy 8.763 4.5466)
			)
			(stroke
				(width 0)
				(type default)
			)
			(fill no)
			(layer "F.CrtYd")
		)
		(fp_poly
			(pts
				(xy 1.397 4.5466) (xy 1.397 3.2639) (xy -23.6728 3.2639) (xy -23.6728 -3.5052) (xy 23.6728 -3.5052)
				(xy 23.6728 3.2639) (xy 8.763 3.2639) (xy 8.763 4.5466)
			)
			(stroke
				(width 0)
				(type default)
			)
			(fill no)
			(layer "F.Fab")
		)
		(pad "" np_thru_hole circle
			(at -18.874994 0 270)
			(size 0.254 0.254)
			(drill 1.3462)
			(layers "*.Cu" "*.Mask")
			(clearance 0.9017)
			(thermal_gap 0.9017)
		)
		(pad "" np_thru_hole circle
			(at 18.874994 0 270)
			(size 0.254 0.254)
			(drill 0.9398)
			(layers "*.Cu" "*.Mask")
			(clearance 0.6985)
			(thermal_gap 0.6985)
		)
		(pad "G1" smd rect
			(at 21.874988 0 270)
			(size 2.5908 2.5908)
			(layers "F.Cu" "F.Mask" "F.Paste")
			(net "GND")
		)
		(pad "G2" smd rect
			(at -21.874988 0 270)
			(size 2.5908 2.5908)
			(layers "F.Cu" "F.Mask" "F.Paste")
			(net "GND")
		)
		(pad "P1" smd rect
			(at 1.905 -1.82499 270)
			(size 0.6096 2.3622)
			(layers "F.Cu" "F.Mask" "F.Paste")
			(net "Net_1659")
		)
		(pad "P2" smd rect
			(at 0.635 -1.82499 270)
			(size 0.6096 2.3622)
			(layers "F.Cu" "F.Mask" "F.Paste")
			(net "Net_1660")
		)
		(pad "P3" smd rect
			(at -0.635 -1.82499 270)
			(size 0.6096 2.3622)
			(layers "F.Cu" "F.Mask" "F.Paste")
			(net "Net_1661")
		)
		(pad "P4" smd rect
			(at -1.905 -1.82499 270)
			(size 0.6096 2.3622)
			(layers "F.Cu" "F.Mask" "F.Paste")
			(net "GND")
		)
		(pad "P5" smd rect
			(at -3.175 -1.82499 270)
			(size 0.6096 2.3622)
			(layers "F.Cu" "F.Mask" "F.Paste")
			(net "HDD_PRSNT_28")
		)
		(pad "P6" smd rect
			(at -4.445 -1.82499 270)
			(size 0.6096 2.3622)
			(layers "F.Cu" "F.Mask" "F.Paste")
			(net "GND")
		)
		(pad "P7" smd rect
			(at -5.715 -1.82499 270)
			(size 0.6096 2.3622)
			(layers "F.Cu" "F.Mask" "F.Paste")
			(net "5V_PRE_28")
		)
		(pad "P8" smd rect
			(at -6.985 -1.82499 270)
			(size 0.6096 2.3622)
			(layers "F.Cu" "F.Mask" "F.Paste")
			(net "P5V_HDD28")
		)
		(pad "P9" smd rect
			(at -8.255 -1.82499 270)
			(size 0.6096 2.3622)
			(layers "F.Cu" "F.Mask" "F.Paste")
			(net "P5V_HDD28")
		)
		(pad "P10" smd rect
			(at -9.525 -1.82499 270)
			(size 0.6096 2.3622)
			(layers "F.Cu" "F.Mask" "F.Paste")
			(net "GND")
		)
		(pad "P11" smd rect
			(at -10.795 -1.82499 270)
			(size 0.6096 2.3622)
			(layers "F.Cu" "F.Mask" "F.Paste")
			(net "ACT_HDD_28")
		)
		(pad "P12" smd rect
			(at -12.065 -1.82499 270)
			(size 0.6096 2.3622)
			(layers "F.Cu" "F.Mask" "F.Paste")
			(net "GND")
		)
		(pad "P13" smd rect
			(at -13.335 -1.82499 270)
			(size 0.6096 2.3622)
			(layers "F.Cu" "F.Mask" "F.Paste")
			(net "12V_PRE_28")
		)
		(pad "P14" smd rect
			(at -14.605 -1.82499 270)
			(size 0.6096 2.3622)
			(layers "F.Cu" "F.Mask" "F.Paste")
			(net "P12V_HDD28")
		)
		(pad "P15" smd rect
			(at -15.875 -1.82499 270)
			(size 0.6096 2.3622)
			(layers "F.Cu" "F.Mask" "F.Paste")
			(net "P12V_HDD28")
		)
		(pad "S1" smd rect
			(at 15.875 -1.82499 270)
			(size 0.6096 2.3622)
			(layers "F.Cu" "F.Mask" "F.Paste")
			(net "GND")
		)
		(pad "S2" smd rect
			(at 14.605 -1.82499 270)
			(size 0.6096 2.3622)
			(layers "F.Cu" "F.Mask" "F.Paste")
			(net "SAS_HDD_RX_P28")
		)
		(pad "S3" smd rect
			(at 13.335 -1.82499 270)
			(size 0.6096 2.3622)
			(layers "F.Cu" "F.Mask" "F.Paste")
			(net "SAS_HDD_RX_N28")
		)
		(pad "S4" smd rect
			(at 12.065 -1.82499 270)
			(size 0.6096 2.3622)
			(layers "F.Cu" "F.Mask" "F.Paste")
			(net "GND")
		)
		(pad "S5" smd rect
			(at 10.795 -1.82499 270)
			(size 0.6096 2.3622)
			(layers "F.Cu" "F.Mask" "F.Paste")
			(net "PHY_DRV_B_TO_SCC_B_28_DN")
		)
		(pad "S6" smd rect
			(at 9.525 -1.82499 270)
			(size 0.6096 2.3622)
			(layers "F.Cu" "F.Mask" "F.Paste")
			(net "PHY_DRV_B_TO_SCC_B_28_DP")
		)
		(pad "S7" smd rect
			(at 8.255 -1.82499 270)
			(size 0.6096 2.3622)
			(layers "F.Cu" "F.Mask" "F.Paste")
			(net "GND")
		)
		(pad "S8" smd rect
			(at 7.480046 2.845054 270)
			(size 0.508 2.3622)
			(layers "F.Cu" "F.Mask" "F.Paste")
			(net "GND")
		)
		(pad "S9" smd rect
			(at 6.679946 2.845054 270)
			(size 0.508 2.3622)
			(layers "F.Cu" "F.Mask" "F.Paste")
			(net "Net_452")
		)
		(pad "S10" smd rect
			(at 5.8801 2.845054 270)
			(size 0.508 2.3622)
			(layers "F.Cu" "F.Mask" "F.Paste")
			(net "Net_344")
		)
		(pad "S11" smd rect
			(at 5.08 2.845054 270)
			(size 0.508 2.3622)
			(layers "F.Cu" "F.Mask" "F.Paste")
			(net "GND")
		)
		(pad "S12" smd rect
			(at 4.2799 2.845054 270)
			(size 0.508 2.3622)
			(layers "F.Cu" "F.Mask" "F.Paste")
			(net "Net_380")
		)
		(pad "S13" smd rect
			(at 3.480054 2.845054 270)
			(size 0.508 2.3622)
			(layers "F.Cu" "F.Mask" "F.Paste")
			(net "Net_416")
		)
		(pad "S14" smd rect
			(at 2.679954 2.845054 270)
			(size 0.508 2.3622)
			(layers "F.Cu" "F.Mask" "F.Paste")
			(net "GND")
		)
		(zone
			(layer "F.Cu")
			(hatch none 0.5)
			(connect_pads
				(clearance 0)
			)
			(min_thickness 0.25)
			(keepout
				(tracks not_allowed)
				(vias allowed)
				(pads allowed)
				(copperpour not_allowed)
				(footprints allowed)
			)
			(placement
				(enabled no)
				(sheetname "")
			)
			(fill
				(thermal_gap 0.5)
				(thermal_bridge_width 0.5)
				(island_removal_mode 0)
			)
			(polygon
				(pts
					(xy 158.057596 -45.648626) (xy 150.983696 -45.648626) (xy 150.983696 -52.582826) (xy 152.088596 -52.582826)
					(xy 152.088596 -48.468026) (xy 156.711396 -48.468026) (xy 156.711396 -52.582826) (xy 158.057596 -52.582826)
				)
			)
		)
		(zone
			(layer "F.Cu")
			(hatch none 0.5)
			(connect_pads
				(clearance 0)
			)
			(min_thickness 0.25)
			(keepout
				(tracks allowed)
				(vias not_allowed)
				(pads allowed)
				(copperpour not_allowed)
				(footprints allowed)
			)
			(placement
				(enabled no)
				(sheetname "")
			)
			(fill
				(thermal_gap 0.5)
				(thermal_bridge_width 0.5)
				(island_removal_mode 0)
			)
			(polygon
				(pts
					(xy 158.057596 -45.648626) (xy 150.983696 -45.648626) (xy 150.983696 -52.582826) (xy 152.088596 -52.582826)
					(xy 152.088596 -48.468026) (xy 156.711396 -48.468026) (xy 156.711396 -52.582826) (xy 158.057596 -52.582826)
				)
			)
		)
		(zone
			(layer "F.Cu")
			(hatch none 0.5)
			(connect_pads
				(clearance 0)
			)
			(min_thickness 0.25)
			(keepout
				(tracks allowed)
				(vias not_allowed)
				(pads allowed)
				(copperpour not_allowed)
				(footprints allowed)
			)
			(placement
				(enabled no)
				(sheetname "")
			)
			(fill
				(thermal_gap 0.5)
				(thermal_bridge_width 0.5)
				(island_removal_mode 0)
			)
			(polygon
				(pts
					(xy 158.057596 -12.171426) (xy 150.983696 -12.171426) (xy 150.983696 -5.237226) (xy 152.088596 -5.237226)
					(xy 152.088596 -9.352026) (xy 156.711396 -9.352026) (xy 156.711396 -5.237226) (xy 158.057596 -5.237226)
				)
			)
		)
		(zone
			(layer "F.Cu")
			(hatch none 0.5)
			(connect_pads
				(clearance 0)
			)
			(min_thickness 0.25)
			(keepout
				(tracks not_allowed)
				(vias allowed)
				(pads allowed)
				(copperpour not_allowed)
				(footprints allowed)
			)
			(placement
				(enabled no)
				(sheetname "")
			)
			(fill
				(thermal_gap 0.5)
				(thermal_bridge_width 0.5)
				(island_removal_mode 0)
			)
			(polygon
				(pts
					(xy 158.057596 -12.171426) (xy 150.983696 -12.171426) (xy 150.983696 -5.237226) (xy 152.088596 -5.237226)
					(xy 152.088596 -9.352026) (xy 156.711396 -9.352026) (xy 156.711396 -5.237226) (xy 158.057596 -5.237226)
				)
			)
		)
		(zone
			(layers "F.Cu" "B.Cu" "In1.Cu" "In2.Cu" "In3.Cu" "In4.Cu" "In5.Cu" "In6.Cu")
			(hatch none 0.5)
			(connect_pads
				(clearance 0)
			)
			(min_thickness 0.25)
			(keepout
				(tracks not_allowed)
				(vias allowed)
				(pads allowed)
				(copperpour not_allowed)
				(footprints allowed)
			)
			(placement
				(enabled no)
				(sheetname "")
			)
			(fill
				(thermal_gap 0.5)
				(thermal_bridge_width 0.5)
				(island_removal_mode 0)
			)
			(polygon
				(pts
					(arc
						(start 155.174696 -10.035032)
						(mid 153.625296 -10.035032)
						(end 155.174696 -10.035032)
					)
				)
			)
		)
		(zone
			(layers "F.Cu" "B.Cu" "In1.Cu" "In2.Cu" "In3.Cu" "In4.Cu" "In5.Cu" "In6.Cu")
			(hatch none 0.5)
			(connect_pads
				(clearance 0)
			)
			(min_thickness 0.25)
			(keepout
				(tracks not_allowed)
				(vias allowed)
				(pads allowed)
				(copperpour not_allowed)
				(footprints allowed)
			)
			(placement
				(enabled no)
				(sheetname "")
			)
			(fill
				(thermal_gap 0.5)
				(thermal_bridge_width 0.5)
				(island_removal_mode 0)
			)
			(polygon
				(pts
					(arc
						(start 155.377896 -47.78502)
						(mid 153.422096 -47.78502)
						(end 155.377896 -47.78502)
					)
				)
			)
		)
	)
	(footprint ""
		(layer "F.Cu")
		(at 436.089044 -113.677446 90)
		(property "Reference" "C675"
			(at 0 0 90)
			(layer "F.SilkS")
			(hide yes)
			(effects
				(font
					(size 1.27 1.27)
				)
			)
		)
		(property "Value" "SC10U16V5KX-7-GP-U"
			(at -0.0762 -6.1214 90)
			(unlocked yes)
			(layer "F.Fab")
			(hide yes)
			(effects
				(font
					(size 1.016 1.016)
					(thickness 0.1524)
				)
			)
		)
		(property "Device Type" "C805H58"
			(at -0.0762 -8.1534 90)
			(unlocked yes)
			(layer "F.Fab")
			(hide yes)
			(effects
				(font
					(size 1.016 1.016)
					(thickness 0.1524)
				)
			)
		)
		(duplicate_pad_numbers_are_jumpers no)
		(fp_line
			(start 0.635 0)
			(end -0.635 0)
			(stroke
				(width 0.508)
				(type default)
			)
			(layer "F.SilkS")
		)
		(fp_rect
			(start -0.9652 1.778)
			(end 0.9652 -1.778)
			(stroke
				(width 0)
				(type default)
			)
			(fill no)
			(layer "F.CrtYd")
		)
		(fp_poly
			(pts
				(xy -0.9652 -1.778) (xy 0.9652 -1.778) (xy 0.9652 1.778) (xy -0.9652 1.778)
			)
			(stroke
				(width 0)
				(type default)
			)
			(fill no)
			(layer "F.Fab")
		)
		(pad "1" smd rect
			(at 0 -0.9652 90)
			(size 1.397 1.143)
			(layers "F.Cu" "F.Mask" "F.Paste")
			(net "P12V_B_4_VIN_U34")
		)
		(pad "2" smd rect
			(at 0 0.9652 90)
			(size 1.397 1.143)
			(layers "F.Cu" "F.Mask" "F.Paste")
			(net "GND")
		)
	)
	(footprint ""
		(layer "F.Cu")
		(at 81.534 -246.634)
		(property "Reference" "R203"
			(at 0 0 0)
			(layer "F.SilkS")
			(hide yes)
			(effects
				(font
					(size 1.27 1.27)
				)
			)
		)
		(property "Value" "0R2J-2-GP"
			(at 0.064008 -3.993896 0)
			(unlocked yes)
			(layer "F.Fab")
			(hide yes)
			(effects
				(font
					(size 1.016 1.016)
					(thickness 0.1524)
				)
			)
		)
		(property "Device Type" "R402H16"
			(at 0.064008 -5.517896 0)
			(unlocked yes)
			(layer "F.Fab")
			(hide yes)
			(effects
				(font
					(size 1.016 1.016)
					(thickness 0.1524)
				)
			)
		)
		(duplicate_pad_numbers_are_jumpers no)
		(fp_line
			(start -0.508 -0.9398)
			(end -0.508 0.9398)
			(stroke
				(width 0.1524)
				(type default)
			)
			(layer "F.SilkS")
		)
		(fp_line
			(start 0.508 -0.9398)
			(end -0.508 -0.9398)
			(stroke
				(width 0.1524)
				(type default)
			)
			(layer "F.SilkS")
		)
		(fp_rect
			(start -0.508 0.9398)
			(end 0.508 -0.9398)
			(stroke
				(width 0)
				(type default)
			)
			(fill no)
			(layer "F.CrtYd")
		)
		(fp_rect
			(start -0.508 0.9398)
			(end 0.508 -0.9398)
			(stroke
				(width 0)
				(type default)
			)
			(fill no)
			(layer "F.Fab")
		)
		(pad "1" smd custom
			(at 0 -0.4445)
			(size 0.1397 0.1397)
			(layers "F.Cu" "F.Mask" "F.Paste")
			(net "SW_HDD_G2")
			(options
				(clearance outline)
				(anchor circle)
			)
			(primitives
				(gr_poly
					(pts
						(arc
							(start -0.1778 -0.2794)
							(mid -0.249642 -0.249642)
							(end -0.2794 -0.1778)
						)
						(arc
							(start -0.2794 0.1778)
							(mid -0.249642 0.249642)
							(end -0.1778 0.2794)
						)
						(arc
							(start 0.1778 0.2794)
							(mid 0.249642 0.249642)
							(end 0.2794 0.1778)
						)
						(arc
							(start 0.2794 -0.1778)
							(mid 0.249642 -0.249642)
							(end 0.1778 -0.2794)
						)
					)
					(width 0)
					(fill yes)
				)
			)
		)
		(pad "2" smd custom
			(at 0 0.4445)
			(size 0.1397 0.1397)
			(layers "F.Cu" "F.Mask" "F.Paste")
			(net "SW_HDD_R2")
			(options
				(clearance outline)
				(anchor circle)
			)
			(primitives
				(gr_poly
					(pts
						(arc
							(start -0.1778 -0.2794)
							(mid -0.249642 -0.249642)
							(end -0.2794 -0.1778)
						)
						(arc
							(start -0.2794 0.1778)
							(mid -0.249642 0.249642)
							(end -0.1778 0.2794)
						)
						(arc
							(start 0.1778 0.2794)
							(mid 0.249642 0.249642)
							(end 0.2794 0.1778)
						)
						(arc
							(start 0.2794 -0.1778)
							(mid 0.249642 -0.249642)
							(end 0.1778 -0.2794)
						)
					)
					(width 0)
					(fill yes)
				)
			)
		)
	)
	(footprint ""
		(layer "F.Cu")
		(at 222.669862 -204.978 90)
		(property "Reference" "R46"
			(at 0 0 90)
			(layer "F.SilkS")
			(hide yes)
			(effects
				(font
					(size 1.27 1.27)
				)
			)
		)
		(property "Value" "4K7R2F-GP"
			(at 0.064008 -3.993896 90)
			(unlocked yes)
			(layer "F.Fab")
			(hide yes)
			(effects
				(font
					(size 1.016 1.016)
					(thickness 0.1524)
				)
			)
		)
		(property "Device Type" "R402H16"
			(at 0.064008 -5.517896 90)
			(unlocked yes)
			(layer "F.Fab")
			(hide yes)
			(effects
				(font
					(size 1.016 1.016)
					(thickness 0.1524)
				)
			)
		)
		(duplicate_pad_numbers_are_jumpers no)
		(fp_line
			(start 0.508 -0.9398)
			(end -0.508 -0.9398)
			(stroke
				(width 0.1524)
				(type default)
			)
			(layer "F.SilkS")
		)
		(fp_line
			(start -0.508 -0.9398)
			(end -0.508 0.9398)
			(stroke
				(width 0.1524)
				(type default)
			)
			(layer "F.SilkS")
		)
		(fp_rect
			(start -0.508 0.9398)
			(end 0.508 -0.9398)
			(stroke
				(width 0)
				(type default)
			)
			(fill no)
			(layer "F.CrtYd")
		)
		(fp_rect
			(start -0.508 0.9398)
			(end 0.508 -0.9398)
			(stroke
				(width 0)
				(type default)
			)
			(fill no)
			(layer "F.Fab")
		)
		(pad "1" smd custom
			(at 0 -0.4445 90)
			(size 0.1397 0.1397)
			(layers "F.Cu" "F.Mask" "F.Paste")
			(net "IO_EXP5_A1")
			(options
				(clearance outline)
				(anchor circle)
			)
			(primitives
				(gr_poly
					(pts
						(arc
							(start -0.1778 -0.2794)
							(mid -0.249642 -0.249642)
							(end -0.2794 -0.1778)
						)
						(arc
							(start -0.2794 0.1778)
							(mid -0.249642 0.249642)
							(end -0.1778 0.2794)
						)
						(arc
							(start 0.1778 0.2794)
							(mid 0.249642 0.249642)
							(end 0.2794 0.1778)
						)
						(arc
							(start 0.2794 -0.1778)
							(mid 0.249642 -0.249642)
							(end 0.1778 -0.2794)
						)
					)
					(width 0)
					(fill yes)
				)
			)
		)
		(pad "2" smd custom
			(at 0 0.4445 90)
			(size 0.1397 0.1397)
			(layers "F.Cu" "F.Mask" "F.Paste")
			(net "GND")
			(options
				(clearance outline)
				(anchor circle)
			)
			(primitives
				(gr_poly
					(pts
						(arc
							(start -0.1778 -0.2794)
							(mid -0.249642 -0.249642)
							(end -0.2794 -0.1778)
						)
						(arc
							(start -0.2794 0.1778)
							(mid -0.249642 0.249642)
							(end -0.1778 0.2794)
						)
						(arc
							(start 0.1778 0.2794)
							(mid 0.249642 0.249642)
							(end 0.2794 0.1778)
						)
						(arc
							(start 0.2794 -0.1778)
							(mid 0.249642 -0.249642)
							(end 0.1778 -0.2794)
						)
					)
					(width 0)
					(fill yes)
				)
			)
		)
	)
	(footprint ""
		(layer "F.Cu")
		(at 161.544 -263.144 -90)
		(property "Reference" "R223"
			(at 0 0 270)
			(layer "F.SilkS")
			(hide yes)
			(effects
				(font
					(size 1.27 1.27)
				)
			)
		)
		(property "Value" "10KR2F-2-GP"
			(at 0.064008 -3.993896 270)
			(unlocked yes)
			(layer "F.Fab")
			(hide yes)
			(effects
				(font
					(size 1.016 1.016)
					(thickness 0.1524)
				)
			)
		)
		(property "Device Type" "R402H16"
			(at 0.064008 -5.517896 270)
			(unlocked yes)
			(layer "F.Fab")
			(hide yes)
			(effects
				(font
					(size 1.016 1.016)
					(thickness 0.1524)
				)
			)
		)
		(duplicate_pad_numbers_are_jumpers no)
		(fp_line
			(start -0.508 -0.9398)
			(end -0.508 0.9398)
			(stroke
				(width 0.1524)
				(type default)
			)
			(layer "F.SilkS")
		)
		(fp_line
			(start 0.508 -0.9398)
			(end -0.508 -0.9398)
			(stroke
				(width 0.1524)
				(type default)
			)
			(layer "F.SilkS")
		)
		(fp_rect
			(start -0.508 0.9398)
			(end 0.508 -0.9398)
			(stroke
				(width 0)
				(type default)
			)
			(fill no)
			(layer "F.CrtYd")
		)
		(fp_rect
			(start -0.508 0.9398)
			(end 0.508 -0.9398)
			(stroke
				(width 0)
				(type default)
			)
			(fill no)
			(layer "F.Fab")
		)
		(pad "1" smd custom
			(at 0 -0.4445 270)
			(size 0.1397 0.1397)
			(layers "F.Cu" "F.Mask" "F.Paste")
			(net "P3V3_STBY_B")
			(options
				(clearance outline)
				(anchor circle)
			)
			(primitives
				(gr_poly
					(pts
						(arc
							(start -0.1778 -0.2794)
							(mid -0.249642 -0.249642)
							(end -0.2794 -0.1778)
						)
						(arc
							(start -0.2794 0.1778)
							(mid -0.249642 0.249642)
							(end -0.1778 0.2794)
						)
						(arc
							(start 0.1778 0.2794)
							(mid 0.249642 0.249642)
							(end 0.2794 0.1778)
						)
						(arc
							(start 0.2794 -0.1778)
							(mid 0.249642 -0.249642)
							(end 0.1778 -0.2794)
						)
					)
					(width 0)
					(fill yes)
				)
			)
		)
		(pad "2" smd custom
			(at 0 0.4445 270)
			(size 0.1397 0.1397)
			(layers "F.Cu" "F.Mask" "F.Paste")
			(net "HDD_PRSNT_4")
			(options
				(clearance outline)
				(anchor circle)
			)
			(primitives
				(gr_poly
					(pts
						(arc
							(start -0.1778 -0.2794)
							(mid -0.249642 -0.249642)
							(end -0.2794 -0.1778)
						)
						(arc
							(start -0.2794 0.1778)
							(mid -0.249642 0.249642)
							(end -0.1778 0.2794)
						)
						(arc
							(start 0.1778 0.2794)
							(mid 0.249642 0.249642)
							(end 0.2794 0.1778)
						)
						(arc
							(start 0.2794 -0.1778)
							(mid 0.249642 -0.249642)
							(end 0.1778 -0.2794)
						)
					)
					(width 0)
					(fill yes)
				)
			)
		)
	)
	(footprint ""
		(layer "F.Cu")
		(at 192.513966 -269.705074)
		(property "Reference" "TP46"
			(at 0 0 0)
			(layer "F.SilkS")
			(hide yes)
			(effects
				(font
					(size 1.27 1.27)
				)
			)
		)
		(property "Value" "*"
			(at -0.0508 -1.6764 0)
			(unlocked yes)
			(layer "F.Fab")
			(hide yes)
			(effects
				(font
					(size 1.016 1.016)
					(thickness 0.1524)
				)
			)
		)
		(property "Device Type" "TPAD32"
			(at -0.0508 -3.2004 0)
			(unlocked yes)
			(layer "F.Fab")
			(hide yes)
			(effects
				(font
					(size 1.016 1.016)
					(thickness 0.1524)
				)
			)
		)
		(duplicate_pad_numbers_are_jumpers no)
		(fp_poly
			(pts
				(arc
					(start 0.4064 0)
					(mid -0.4064 0)
					(end 0.4064 0)
				)
			)
			(stroke
				(width 0)
				(type default)
			)
			(fill no)
			(layer "F.CrtYd")
		)
		(fp_poly
			(pts
				(arc
					(start 0.7112 0)
					(mid -0.7112 0)
					(end 0.7112 0)
				)
			)
			(stroke
				(width 0)
				(type default)
			)
			(fill no)
			(layer "F.Fab")
		)
		(pad "1" smd circle
			(at 0 0)
			(size 0.8128 0.8128)
			(layers "F.Cu" "F.Mask" "F.Paste")
			(net "ACT_HDD_5")
		)
	)
	(footprint ""
		(layer "F.Cu")
		(at 416.3314 -261.6454)
		(property "Reference" "C154"
			(at 0 0 0)
			(layer "F.SilkS")
			(hide yes)
			(effects
				(font
					(size 1.27 1.27)
				)
			)
		)
		(property "Value" "SCD01U50V2KX-1GP"
			(at 1.1811 -2.7051 0)
			(unlocked yes)
			(layer "F.Fab")
			(hide yes)
			(effects
				(font
					(size 1.016 1.016)
					(thickness 0.1524)
				)
			)
		)
		(property "Device Type" "C402H22"
			(at 1.1811 -4.2291 0)
			(unlocked yes)
			(layer "F.Fab")
			(hide yes)
			(effects
				(font
					(size 1.016 1.016)
					(thickness 0.1524)
				)
			)
		)
		(duplicate_pad_numbers_are_jumpers no)
		(fp_rect
			(start -0.4318 0.9525)
			(end 0.4318 -0.9525)
			(stroke
				(width 0)
				(type default)
			)
			(fill no)
			(layer "F.CrtYd")
		)
		(fp_rect
			(start -0.4318 0.9525)
			(end 0.4318 -0.9525)
			(stroke
				(width 0)
				(type default)
			)
			(fill no)
			(layer "F.Fab")
		)
		(pad "1" smd custom
			(at 0 -0.4445)
			(size 0.1524 0.1524)
			(layers "F.Cu" "F.Mask" "F.Paste")
			(net "HDD_PRSNT_9")
			(options
				(clearance outline)
				(anchor circle)
			)
			(primitives
				(gr_poly
					(pts
						(arc
							(start 0.3048 -0.2032)
							(mid 0.275042 -0.275042)
							(end 0.2032 -0.3048)
						)
						(arc
							(start -0.2032 -0.3048)
							(mid -0.275042 -0.275042)
							(end -0.3048 -0.2032)
						)
						(arc
							(start -0.3048 0.2032)
							(mid -0.275042 0.275042)
							(end -0.2032 0.3048)
						)
						(arc
							(start 0.2032 0.3048)
							(mid 0.275042 0.275042)
							(end 0.3048 0.2032)
						)
					)
					(width 0)
					(fill yes)
				)
			)
		)
		(pad "2" smd custom
			(at 0 0.4445)
			(size 0.1524 0.1524)
			(layers "F.Cu" "F.Mask" "F.Paste")
			(net "GND")
			(options
				(clearance outline)
				(anchor circle)
			)
			(primitives
				(gr_poly
					(pts
						(arc
							(start 0.3048 -0.2032)
							(mid 0.275042 -0.275042)
							(end 0.2032 -0.3048)
						)
						(arc
							(start -0.2032 -0.3048)
							(mid -0.275042 -0.275042)
							(end -0.3048 -0.2032)
						)
						(arc
							(start -0.3048 0.2032)
							(mid -0.275042 0.275042)
							(end -0.2032 0.3048)
						)
						(arc
							(start 0.2032 0.3048)
							(mid 0.275042 0.275042)
							(end 0.3048 0.2032)
						)
					)
					(width 0)
					(fill yes)
				)
			)
		)
	)
	(footprint ""
		(layer "F.Cu")
		(at 240.665 -311.912)
		(property "Reference" "R1085"
			(at 0 0 0)
			(layer "F.SilkS")
			(hide yes)
			(effects
				(font
					(size 1.27 1.27)
				)
			)
		)
		(property "Value" "4K7R2F-GP"
			(at 0.064008 -3.993896 0)
			(unlocked yes)
			(layer "F.Fab")
			(hide yes)
			(effects
				(font
					(size 1.016 1.016)
					(thickness 0.1524)
				)
			)
		)
		(property "Device Type" "R402H16"
			(at 0.064008 -5.517896 0)
			(unlocked yes)
			(layer "F.Fab")
			(hide yes)
			(effects
				(font
					(size 1.016 1.016)
					(thickness 0.1524)
				)
			)
		)
		(duplicate_pad_numbers_are_jumpers no)
		(fp_line
			(start -0.508 -0.9398)
			(end -0.508 0.9398)
			(stroke
				(width 0.1524)
				(type default)
			)
			(layer "F.SilkS")
		)
		(fp_line
			(start 0.508 -0.9398)
			(end -0.508 -0.9398)
			(stroke
				(width 0.1524)
				(type default)
			)
			(layer "F.SilkS")
		)
		(fp_rect
			(start -0.508 0.9398)
			(end 0.508 -0.9398)
			(stroke
				(width 0)
				(type default)
			)
			(fill no)
			(layer "F.CrtYd")
		)
		(fp_rect
			(start -0.508 0.9398)
			(end 0.508 -0.9398)
			(stroke
				(width 0)
				(type default)
			)
			(fill no)
			(layer "F.Fab")
		)
		(pad "1" smd custom
			(at 0 -0.4445)
			(size 0.1397 0.1397)
			(layers "F.Cu" "F.Mask" "F.Paste")
			(net "P3V3_STBY_A")
			(options
				(clearance outline)
				(anchor circle)
			)
			(primitives
				(gr_poly
					(pts
						(arc
							(start -0.1778 -0.2794)
							(mid -0.249642 -0.249642)
							(end -0.2794 -0.1778)
						)
						(arc
							(start -0.2794 0.1778)
							(mid -0.249642 0.249642)
							(end -0.1778 0.2794)
						)
						(arc
							(start 0.1778 0.2794)
							(mid 0.249642 0.249642)
							(end 0.2794 0.1778)
						)
						(arc
							(start 0.2794 -0.1778)
							(mid 0.249642 -0.249642)
							(end 0.1778 -0.2794)
						)
					)
					(width 0)
					(fill yes)
				)
			)
		)
		(pad "2" smd custom
			(at 0 0.4445)
			(size 0.1397 0.1397)
			(layers "F.Cu" "F.Mask" "F.Paste")
			(net "MAX31790_A_ADD0")
			(options
				(clearance outline)
				(anchor circle)
			)
			(primitives
				(gr_poly
					(pts
						(arc
							(start -0.1778 -0.2794)
							(mid -0.249642 -0.249642)
							(end -0.2794 -0.1778)
						)
						(arc
							(start -0.2794 0.1778)
							(mid -0.249642 0.249642)
							(end -0.1778 0.2794)
						)
						(arc
							(start 0.1778 0.2794)
							(mid 0.249642 0.249642)
							(end 0.2794 0.1778)
						)
						(arc
							(start 0.2794 -0.1778)
							(mid 0.249642 -0.249642)
							(end 0.1778 -0.2794)
						)
					)
					(width 0)
					(fill yes)
				)
			)
		)
	)
	(footprint ""
		(layer "F.Cu")
		(at 218.214702 -329.061064)
		(property "Reference" "C513"
			(at 0 0 0)
			(layer "F.SilkS")
			(hide yes)
			(effects
				(font
					(size 1.27 1.27)
				)
			)
		)
		(property "Value" "SC22U25V6KX-2-GP-U"
			(at -2.860802 -5.279644 0)
			(unlocked yes)
			(layer "F.Fab")
			(hide yes)
			(effects
				(font
					(size 1.016 1.016)
					(thickness 0.1524)
				)
			)
		)
		(property "Device Type" "C1206-TO0D3H75"
			(at -2.860802 -6.803644 0)
			(unlocked yes)
			(layer "F.Fab")
			(hide yes)
			(effects
				(font
					(size 1.016 1.016)
					(thickness 0.1524)
				)
			)
		)
		(duplicate_pad_numbers_are_jumpers no)
		(fp_line
			(start -1.3081 -2.3749)
			(end 1.3081 -2.3749)
			(stroke
				(width 0.1524)
				(type default)
			)
			(layer "F.SilkS")
		)
		(fp_line
			(start -1.3081 2.3749)
			(end -1.3081 -2.3749)
			(stroke
				(width 0.1524)
				(type default)
			)
			(layer "F.SilkS")
		)
		(fp_line
			(start 1.3081 -2.3749)
			(end 1.3081 2.3749)
			(stroke
				(width 0.1524)
				(type default)
			)
			(layer "F.SilkS")
		)
		(fp_line
			(start 1.3081 2.3749)
			(end -1.3081 2.3749)
			(stroke
				(width 0.1524)
				(type default)
			)
			(layer "F.SilkS")
		)
		(fp_rect
			(start -0.8001 1.6002)
			(end 0.8001 -1.6002)
			(stroke
				(width 0)
				(type default)
			)
			(fill no)
			(layer "F.CrtYd")
		)
		(fp_poly
			(pts
				(xy -1.5621 2.4511) (xy -1.5621 1.6002) (xy 0.8001 1.6002) (xy 0.8001 -1.6002) (xy -0.8001 -1.6002)
				(xy -0.8001 1.5875) (xy -1.5621 1.5875) (xy -1.5621 -2.4511) (xy 1.5621 -2.4511) (xy 1.5621 2.4511)
			)
			(stroke
				(width 0)
				(type default)
			)
			(fill no)
			(layer "F.CrtYd")
		)
		(fp_rect
			(start -1.5621 2.4511)
			(end 1.5621 -2.4511)
			(stroke
				(width 0)
				(type default)
			)
			(fill no)
			(layer "F.Fab")
		)
		(pad "1" smd rect
			(at 0 -1.392936)
			(size 2.1082 1.4478)
			(layers "F.Cu" "F.Mask" "F.Paste")
			(net "P12V_IN")
		)
		(pad "2" smd rect
			(at 0 1.392936)
			(size 2.1082 1.4478)
			(layers "F.Cu" "F.Mask" "F.Paste")
			(net "GND")
		)
	)
	(footprint ""
		(layer "F.Cu")
		(at 413.866076 -269.705074)
		(property "Reference" "TP66"
			(at 0 0 0)
			(layer "F.SilkS")
			(hide yes)
			(effects
				(font
					(size 1.27 1.27)
				)
			)
		)
		(property "Value" "*"
			(at -0.0508 -1.6764 0)
			(unlocked yes)
			(layer "F.Fab")
			(hide yes)
			(effects
				(font
					(size 1.016 1.016)
					(thickness 0.1524)
				)
			)
		)
		(property "Device Type" "TPAD32"
			(at -0.0508 -3.2004 0)
			(unlocked yes)
			(layer "F.Fab")
			(hide yes)
			(effects
				(font
					(size 1.016 1.016)
					(thickness 0.1524)
				)
			)
		)
		(duplicate_pad_numbers_are_jumpers no)
		(fp_poly
			(pts
				(arc
					(start 0.4064 0)
					(mid -0.4064 0)
					(end 0.4064 0)
				)
			)
			(stroke
				(width 0)
				(type default)
			)
			(fill no)
			(layer "F.CrtYd")
		)
		(fp_poly
			(pts
				(arc
					(start 0.7112 0)
					(mid -0.7112 0)
					(end 0.7112 0)
				)
			)
			(stroke
				(width 0)
				(type default)
			)
			(fill no)
			(layer "F.Fab")
		)
		(pad "1" smd circle
			(at 0 0)
			(size 0.8128 0.8128)
			(layers "F.Cu" "F.Mask" "F.Paste")
			(net "ACT_HDD_9")
		)
	)
	(footprint ""
		(layer "F.Cu")
		(at 51.7652 -148.717 -90)
		(property "Reference" "C199"
			(at 0 0 270)
			(layer "F.SilkS")
			(hide yes)
			(effects
				(font
					(size 1.27 1.27)
				)
			)
		)
		(property "Value" "SC1U16V3KX-5GP"
			(at 0 -2.8194 270)
			(unlocked yes)
			(layer "F.Fab")
			(hide yes)
			(effects
				(font
					(size 1.016 1.016)
					(thickness 0.1524)
				)
			)
		)
		(property "Device Type" "C603H36"
			(at 0 -4.3434 270)
			(unlocked yes)
			(layer "F.Fab")
			(hide yes)
			(effects
				(font
					(size 1.016 1.016)
					(thickness 0.1524)
				)
			)
		)
		(duplicate_pad_numbers_are_jumpers no)
		(fp_line
			(start 0.508 0)
			(end -0.508 0)
			(stroke
				(width 0.2032)
				(type default)
			)
			(layer "F.SilkS")
		)
		(fp_rect
			(start -0.5842 1.3335)
			(end 0.5842 -1.3335)
			(stroke
				(width 0)
				(type default)
			)
			(fill no)
			(layer "F.CrtYd")
		)
		(fp_rect
			(start -0.5842 1.3335)
			(end 0.5842 -1.3335)
			(stroke
				(width 0)
				(type default)
			)
			(fill no)
			(layer "F.Fab")
		)
		(pad "1" smd custom
			(at 0 -0.762 270)
			(size 0.2159 0.2159)
			(layers "F.Cu" "F.Mask" "F.Paste")
			(net "P5V_HDD13")
			(options
				(clearance outline)
				(anchor circle)
			)
			(primitives
				(gr_poly
					(pts
						(arc
							(start -0.3302 -0.4318)
							(mid -0.402042 -0.402042)
							(end -0.4318 -0.3302)
						)
						(arc
							(start -0.4318 0.3302)
							(mid -0.402042 0.402042)
							(end -0.3302 0.4318)
						)
						(arc
							(start 0.3302 0.4318)
							(mid 0.402042 0.402042)
							(end 0.4318 0.3302)
						)
						(arc
							(start 0.4318 -0.3302)
							(mid 0.402042 -0.402042)
							(end 0.3302 -0.4318)
						)
					)
					(width 0)
					(fill yes)
				)
			)
		)
		(pad "2" smd custom
			(at 0 0.762 270)
			(size 0.2159 0.2159)
			(layers "F.Cu" "F.Mask" "F.Paste")
			(net "GND")
			(options
				(clearance outline)
				(anchor circle)
			)
			(primitives
				(gr_poly
					(pts
						(arc
							(start -0.3302 -0.4318)
							(mid -0.402042 -0.402042)
							(end -0.4318 -0.3302)
						)
						(arc
							(start -0.4318 0.3302)
							(mid -0.402042 0.402042)
							(end -0.3302 0.4318)
						)
						(arc
							(start 0.3302 0.4318)
							(mid 0.402042 0.402042)
							(end 0.4318 0.3302)
						)
						(arc
							(start 0.4318 -0.3302)
							(mid 0.402042 -0.402042)
							(end 0.3302 -0.4318)
						)
					)
					(width 0)
					(fill yes)
				)
			)
		)
	)
	(footprint ""
		(layer "F.Cu")
		(at 47.173388 -118.778274 90)
		(property "Reference" "R1128"
			(at 0 0 90)
			(layer "F.SilkS")
			(hide yes)
			(effects
				(font
					(size 1.27 1.27)
				)
			)
		)
		(property "Value" "100KR2F-L1-GP"
			(at 0.064008 -3.993896 90)
			(unlocked yes)
			(layer "F.Fab")
			(hide yes)
			(effects
				(font
					(size 1.016 1.016)
					(thickness 0.1524)
				)
			)
		)
		(property "Device Type" "R402H16"
			(at 0.064008 -5.517896 90)
			(unlocked yes)
			(layer "F.Fab")
			(hide yes)
			(effects
				(font
					(size 1.016 1.016)
					(thickness 0.1524)
				)
			)
		)
		(duplicate_pad_numbers_are_jumpers no)
		(fp_line
			(start 0.508 -0.9398)
			(end -0.508 -0.9398)
			(stroke
				(width 0.1524)
				(type default)
			)
			(layer "F.SilkS")
		)
		(fp_line
			(start -0.508 -0.9398)
			(end -0.508 0.9398)
			(stroke
				(width 0.1524)
				(type default)
			)
			(layer "F.SilkS")
		)
		(fp_rect
			(start -0.508 0.9398)
			(end 0.508 -0.9398)
			(stroke
				(width 0)
				(type default)
			)
			(fill no)
			(layer "F.CrtYd")
		)
		(fp_rect
			(start -0.508 0.9398)
			(end 0.508 -0.9398)
			(stroke
				(width 0)
				(type default)
			)
			(fill no)
			(layer "F.Fab")
		)
		(pad "1" smd custom
			(at 0 -0.4445 90)
			(size 0.1397 0.1397)
			(layers "F.Cu" "F.Mask" "F.Paste")
			(net "AGND_P5V_B_2")
			(options
				(clearance outline)
				(anchor circle)
			)
			(primitives
				(gr_poly
					(pts
						(arc
							(start -0.1778 -0.2794)
							(mid -0.249642 -0.249642)
							(end -0.2794 -0.1778)
						)
						(arc
							(start -0.2794 0.1778)
							(mid -0.249642 0.249642)
							(end -0.1778 0.2794)
						)
						(arc
							(start 0.1778 0.2794)
							(mid 0.249642 0.249642)
							(end 0.2794 0.1778)
						)
						(arc
							(start 0.2794 -0.1778)
							(mid 0.249642 -0.249642)
							(end 0.1778 -0.2794)
						)
					)
					(width 0)
					(fill yes)
				)
			)
		)
		(pad "2" smd custom
			(at 0 0.4445 90)
			(size 0.1397 0.1397)
			(layers "F.Cu" "F.Mask" "F.Paste")
			(net "P5V_B_2_MODE")
			(options
				(clearance outline)
				(anchor circle)
			)
			(primitives
				(gr_poly
					(pts
						(arc
							(start -0.1778 -0.2794)
							(mid -0.249642 -0.249642)
							(end -0.2794 -0.1778)
						)
						(arc
							(start -0.2794 0.1778)
							(mid -0.249642 0.249642)
							(end -0.1778 0.2794)
						)
						(arc
							(start 0.1778 0.2794)
							(mid 0.249642 0.249642)
							(end 0.2794 0.1778)
						)
						(arc
							(start 0.2794 -0.1778)
							(mid 0.249642 -0.249642)
							(end 0.1778 -0.2794)
						)
					)
					(width 0)
					(fill yes)
				)
			)
		)
	)
	(footprint ""
		(layer "F.Cu")
		(at 447.834512 -15.219426 -90)
		(property "Reference" "C470"
			(at 0 0 270)
			(layer "F.SilkS")
			(hide yes)
			(effects
				(font
					(size 1.27 1.27)
				)
			)
		)
		(property "Value" "SCD01U16V1KX-GP"
			(at -2.8321 -1.7399 270)
			(unlocked yes)
			(layer "F.Fab")
			(hide yes)
			(effects
				(font
					(size 1.016 1.016)
					(thickness 0.1524)
				)
			)
		)
		(property "Device Type" "C0201H13"
			(at -2.8321 -3.2639 270)
			(unlocked yes)
			(layer "F.Fab")
			(hide yes)
			(effects
				(font
					(size 1.016 1.016)
					(thickness 0.1524)
				)
			)
		)
		(duplicate_pad_numbers_are_jumpers no)
		(fp_rect
			(start -0.2794 0.6477)
			(end 0.2794 -0.6477)
			(stroke
				(width 0)
				(type default)
			)
			(fill no)
			(layer "F.CrtYd")
		)
		(fp_rect
			(start -0.2794 0.6477)
			(end 0.2794 -0.6477)
			(stroke
				(width 0)
				(type default)
			)
			(fill no)
			(layer "F.Fab")
		)
		(pad "1" smd custom
			(at 0 -0.2794 270)
			(size 0.0762 0.0762)
			(layers "F.Cu" "F.Mask" "F.Paste")
			(net "SAS_HDD_RX_N34")
			(options
				(clearance outline)
				(anchor circle)
			)
			(primitives
				(gr_poly
					(pts
						(arc
							(start 0.1524 -0.127)
							(mid 0.137521 -0.162921)
							(end 0.1016 -0.1778)
						)
						(arc
							(start -0.1016 -0.1778)
							(mid -0.137521 -0.162921)
							(end -0.1524 -0.127)
						)
						(arc
							(start -0.1524 0.127)
							(mid -0.137521 0.162921)
							(end -0.1016 0.1778)
						)
						(arc
							(start 0.1016 0.1778)
							(mid 0.137521 0.162921)
							(end 0.1524 0.127)
						)
					)
					(width 0)
					(fill yes)
				)
			)
		)
		(pad "2" smd custom
			(at 0 0.2794 270)
			(size 0.0762 0.0762)
			(layers "F.Cu" "F.Mask" "F.Paste")
			(net "PHY_SCC_B_TO_DRV_B_34_DN")
			(options
				(clearance outline)
				(anchor circle)
			)
			(primitives
				(gr_poly
					(pts
						(arc
							(start 0.1524 -0.127)
							(mid 0.137521 -0.162921)
							(end 0.1016 -0.1778)
						)
						(arc
							(start -0.1016 -0.1778)
							(mid -0.137521 -0.162921)
							(end -0.1524 -0.127)
						)
						(arc
							(start -0.1524 0.127)
							(mid -0.137521 0.162921)
							(end -0.1016 0.1778)
						)
						(arc
							(start 0.1016 0.1778)
							(mid 0.137521 0.162921)
							(end 0.1524 0.127)
						)
					)
					(width 0)
					(fill yes)
				)
			)
		)
	)
	(footprint ""
		(layer "F.Cu")
		(at 263.114536 -216.33307 -90)
		(property "Reference" "R163"
			(at 0 0 270)
			(layer "F.SilkS")
			(hide yes)
			(effects
				(font
					(size 1.27 1.27)
				)
			)
		)
		(property "Value" "4K7R2F-GP"
			(at 0.064008 -3.993896 270)
			(unlocked yes)
			(layer "F.Fab")
			(hide yes)
			(effects
				(font
					(size 1.016 1.016)
					(thickness 0.1524)
				)
			)
		)
		(property "Device Type" "R402H16"
			(at 0.064008 -5.517896 270)
			(unlocked yes)
			(layer "F.Fab")
			(hide yes)
			(effects
				(font
					(size 1.016 1.016)
					(thickness 0.1524)
				)
			)
		)
		(duplicate_pad_numbers_are_jumpers no)
		(fp_line
			(start -0.508 -0.9398)
			(end -0.508 0.9398)
			(stroke
				(width 0.1524)
				(type default)
			)
			(layer "F.SilkS")
		)
		(fp_line
			(start 0.508 -0.9398)
			(end -0.508 -0.9398)
			(stroke
				(width 0.1524)
				(type default)
			)
			(layer "F.SilkS")
		)
		(fp_rect
			(start -0.508 0.9398)
			(end 0.508 -0.9398)
			(stroke
				(width 0)
				(type default)
			)
			(fill no)
			(layer "F.CrtYd")
		)
		(fp_rect
			(start -0.508 0.9398)
			(end 0.508 -0.9398)
			(stroke
				(width 0)
				(type default)
			)
			(fill no)
			(layer "F.Fab")
		)
		(pad "1" smd custom
			(at 0 -0.4445 270)
			(size 0.1397 0.1397)
			(layers "F.Cu" "F.Mask" "F.Paste")
			(net "P3V3_STBY_B")
			(options
				(clearance outline)
				(anchor circle)
			)
			(primitives
				(gr_poly
					(pts
						(arc
							(start -0.1778 -0.2794)
							(mid -0.249642 -0.249642)
							(end -0.2794 -0.1778)
						)
						(arc
							(start -0.2794 0.1778)
							(mid -0.249642 0.249642)
							(end -0.1778 0.2794)
						)
						(arc
							(start 0.1778 0.2794)
							(mid 0.249642 0.249642)
							(end 0.2794 0.1778)
						)
						(arc
							(start 0.2794 -0.1778)
							(mid 0.249642 -0.249642)
							(end 0.1778 -0.2794)
						)
					)
					(width 0)
					(fill yes)
				)
			)
		)
		(pad "2" smd custom
			(at 0 0.4445 270)
			(size 0.1397 0.1397)
			(layers "F.Cu" "F.Mask" "F.Paste")
			(net "VOL_SEN_ADDR1")
			(options
				(clearance outline)
				(anchor circle)
			)
			(primitives
				(gr_poly
					(pts
						(arc
							(start -0.1778 -0.2794)
							(mid -0.249642 -0.249642)
							(end -0.2794 -0.1778)
						)
						(arc
							(start -0.2794 0.1778)
							(mid -0.249642 0.249642)
							(end -0.1778 0.2794)
						)
						(arc
							(start 0.1778 0.2794)
							(mid 0.249642 0.249642)
							(end 0.2794 0.1778)
						)
						(arc
							(start 0.2794 -0.1778)
							(mid 0.249642 -0.249642)
							(end 0.1778 -0.2794)
						)
					)
					(width 0)
					(fill yes)
				)
			)
		)
	)
	(footprint ""
		(layer "F.Cu")
		(at 368.427 -246.761 180)
		(property "Reference" "R280"
			(at 0 0 180)
			(layer "F.SilkS")
			(hide yes)
			(effects
				(font
					(size 1.27 1.27)
				)
			)
		)
		(property "Value" "4K7R2J-2-GP"
			(at 0.064008 -3.993896 180)
			(unlocked yes)
			(layer "F.Fab")
			(hide yes)
			(effects
				(font
					(size 1.016 1.016)
					(thickness 0.1524)
				)
			)
		)
		(property "Device Type" "R402H16"
			(at 0.064008 -5.517896 180)
			(unlocked yes)
			(layer "F.Fab")
			(hide yes)
			(effects
				(font
					(size 1.016 1.016)
					(thickness 0.1524)
				)
			)
		)
		(duplicate_pad_numbers_are_jumpers no)
		(fp_line
			(start 0.508 -0.9398)
			(end -0.508 -0.9398)
			(stroke
				(width 0.1524)
				(type default)
			)
			(layer "F.SilkS")
		)
		(fp_line
			(start -0.508 -0.9398)
			(end -0.508 0.9398)
			(stroke
				(width 0.1524)
				(type default)
			)
			(layer "F.SilkS")
		)
		(fp_rect
			(start -0.508 0.9398)
			(end 0.508 -0.9398)
			(stroke
				(width 0)
				(type default)
			)
			(fill no)
			(layer "F.CrtYd")
		)
		(fp_rect
			(start -0.508 0.9398)
			(end 0.508 -0.9398)
			(stroke
				(width 0)
				(type default)
			)
			(fill no)
			(layer "F.Fab")
		)
		(pad "1" smd custom
			(at 0 -0.4445 180)
			(size 0.1397 0.1397)
			(layers "F.Cu" "F.Mask" "F.Paste")
			(net "P12V_B")
			(options
				(clearance outline)
				(anchor circle)
			)
			(primitives
				(gr_poly
					(pts
						(arc
							(start -0.1778 -0.2794)
							(mid -0.249642 -0.249642)
							(end -0.2794 -0.1778)
						)
						(arc
							(start -0.2794 0.1778)
							(mid -0.249642 0.249642)
							(end -0.1778 0.2794)
						)
						(arc
							(start 0.1778 0.2794)
							(mid 0.249642 0.249642)
							(end 0.2794 0.1778)
						)
						(arc
							(start 0.2794 -0.1778)
							(mid 0.249642 -0.249642)
							(end 0.1778 -0.2794)
						)
					)
					(width 0)
					(fill yes)
				)
			)
		)
		(pad "2" smd custom
			(at 0 0.4445 180)
			(size 0.1397 0.1397)
			(layers "F.Cu" "F.Mask" "F.Paste")
			(net "SW_HDD_R7")
			(options
				(clearance outline)
				(anchor circle)
			)
			(primitives
				(gr_poly
					(pts
						(arc
							(start -0.1778 -0.2794)
							(mid -0.249642 -0.249642)
							(end -0.2794 -0.1778)
						)
						(arc
							(start -0.2794 0.1778)
							(mid -0.249642 0.249642)
							(end -0.1778 0.2794)
						)
						(arc
							(start 0.1778 0.2794)
							(mid 0.249642 0.249642)
							(end 0.2794 0.1778)
						)
						(arc
							(start 0.2794 -0.1778)
							(mid 0.249642 -0.249642)
							(end 0.1778 -0.2794)
						)
					)
					(width 0)
					(fill yes)
				)
			)
		)
	)
	(footprint ""
		(layer "F.Cu")
		(at 205.8416 -145.288)
		(property "Reference" "TC1"
			(at 0 0 0)
			(layer "F.SilkS")
			(hide yes)
			(effects
				(font
					(size 1.27 1.27)
				)
			)
		)
		(property "Value" "SE270U16VM-8-GP"
			(at -4.5974 -2.54 0)
			(unlocked yes)
			(layer "F.Fab")
			(hide yes)
			(effects
				(font
					(size 1.016 1.016)
					(thickness 0.1524)
				)
			)
		)
		(property "Device Type" "SE361416H394"
			(at -4.5974 -4.064 0)
			(unlocked yes)
			(layer "F.Fab")
			(hide yes)
			(effects
				(font
					(size 1.016 1.016)
					(thickness 0.1524)
				)
			)
		)
		(duplicate_pad_numbers_are_jumpers no)
		(fp_line
			(start -3.556 -3.4163)
			(end -2.3622 -4.6101)
			(stroke
				(width 0.1524)
				(type default)
			)
			(layer "F.SilkS")
		)
		(fp_line
			(start -3.556 4.6101)
			(end -3.556 -3.4163)
			(stroke
				(width 0.1524)
				(type default)
			)
			(layer "F.SilkS")
		)
		(fp_line
			(start -2.3622 -4.6101)
			(end 2.3622 -4.6101)
			(stroke
				(width 0.1524)
				(type default)
			)
			(layer "F.SilkS")
		)
		(fp_line
			(start 2.3622 -4.6101)
			(end 3.556 -3.4163)
			(stroke
				(width 0.1524)
				(type default)
			)
			(layer "F.SilkS")
		)
		(fp_line
			(start 3.556 -3.4163)
			(end 3.556 4.6101)
			(stroke
				(width 0.1524)
				(type default)
			)
			(layer "F.SilkS")
		)
		(fp_line
			(start 3.556 4.6101)
			(end -3.556 4.6101)
			(stroke
				(width 0.1524)
				(type default)
			)
			(layer "F.SilkS")
		)
		(fp_rect
			(start -3.302 3.6449)
			(end 3.302 -3.6449)
			(stroke
				(width 0)
				(type default)
			)
			(fill no)
			(layer "F.CrtYd")
		)
		(fp_poly
			(pts
				(xy 3.81 4.6863) (xy 3.81 -3.4925) (xy 3.302 -3.4925) (xy 3.302 3.6449) (xy -3.302 3.6449) (xy -3.302 -3.6449)
				(xy 3.302 -3.6449) (xy 3.302 -3.5052) (xy 3.81 -3.5052) (xy 3.81 -4.6863) (xy -3.81 -4.6863) (xy -3.81 4.6863)
			)
			(stroke
				(width 0)
				(type default)
			)
			(fill no)
			(layer "F.CrtYd")
		)
		(fp_rect
			(start -3.81 4.6863)
			(end 3.81 -4.6863)
			(stroke
				(width 0)
				(type default)
			)
			(fill no)
			(layer "F.Fab")
		)
		(pad "1" smd rect
			(at 0 -2.574036)
			(size 1.4224 3.556)
			(layers "F.Cu" "F.Mask" "F.Paste")
			(net "P12V_B")
		)
		(pad "2" smd rect
			(at 0 2.574036)
			(size 1.4224 3.556)
			(layers "F.Cu" "F.Mask" "F.Paste")
			(net "GND")
		)
	)
	(footprint ""
		(layer "F.Cu")
		(at 375.543826 -217.413586 -90)
		(property "Reference" "R274"
			(at 0 0 270)
			(layer "F.SilkS")
			(hide yes)
			(effects
				(font
					(size 1.27 1.27)
				)
			)
		)
		(property "Value" "4K7R2F-GP"
			(at 0.064008 -3.993896 270)
			(unlocked yes)
			(layer "F.Fab")
			(hide yes)
			(effects
				(font
					(size 1.016 1.016)
					(thickness 0.1524)
				)
			)
		)
		(property "Device Type" "R402H16"
			(at 0.064008 -5.517896 270)
			(unlocked yes)
			(layer "F.Fab")
			(hide yes)
			(effects
				(font
					(size 1.016 1.016)
					(thickness 0.1524)
				)
			)
		)
		(duplicate_pad_numbers_are_jumpers no)
		(fp_line
			(start -0.508 -0.9398)
			(end -0.508 0.9398)
			(stroke
				(width 0.1524)
				(type default)
			)
			(layer "F.SilkS")
		)
		(fp_line
			(start 0.508 -0.9398)
			(end -0.508 -0.9398)
			(stroke
				(width 0.1524)
				(type default)
			)
			(layer "F.SilkS")
		)
		(fp_rect
			(start -0.508 0.9398)
			(end 0.508 -0.9398)
			(stroke
				(width 0)
				(type default)
			)
			(fill no)
			(layer "F.CrtYd")
		)
		(fp_rect
			(start -0.508 0.9398)
			(end 0.508 -0.9398)
			(stroke
				(width 0)
				(type default)
			)
			(fill no)
			(layer "F.Fab")
		)
		(pad "1" smd custom
			(at 0 -0.4445 270)
			(size 0.1397 0.1397)
			(layers "F.Cu" "F.Mask" "F.Paste")
			(net "DRIVE_B_8_FLT_LED")
			(options
				(clearance outline)
				(anchor circle)
			)
			(primitives
				(gr_poly
					(pts
						(arc
							(start -0.1778 -0.2794)
							(mid -0.249642 -0.249642)
							(end -0.2794 -0.1778)
						)
						(arc
							(start -0.2794 0.1778)
							(mid -0.249642 0.249642)
							(end -0.1778 0.2794)
						)
						(arc
							(start 0.1778 0.2794)
							(mid 0.249642 0.249642)
							(end 0.2794 0.1778)
						)
						(arc
							(start 0.2794 -0.1778)
							(mid 0.249642 -0.249642)
							(end 0.1778 -0.2794)
						)
					)
					(width 0)
					(fill yes)
				)
			)
		)
		(pad "2" smd custom
			(at 0 0.4445 270)
			(size 0.1397 0.1397)
			(layers "F.Cu" "F.Mask" "F.Paste")
			(net "GND")
			(options
				(clearance outline)
				(anchor circle)
			)
			(primitives
				(gr_poly
					(pts
						(arc
							(start -0.1778 -0.2794)
							(mid -0.249642 -0.249642)
							(end -0.2794 -0.1778)
						)
						(arc
							(start -0.2794 0.1778)
							(mid -0.249642 0.249642)
							(end -0.1778 0.2794)
						)
						(arc
							(start 0.1778 0.2794)
							(mid 0.249642 0.249642)
							(end 0.2794 0.1778)
						)
						(arc
							(start 0.2794 -0.1778)
							(mid 0.249642 -0.249642)
							(end 0.1778 -0.2794)
						)
					)
					(width 0)
					(fill yes)
				)
			)
		)
	)
	(footprint ""
		(layer "F.Cu")
		(at 371.293644 -99.860354 90)
		(property "Reference" "Q261"
			(at 0 0 90)
			(layer "F.SilkS")
			(hide yes)
			(effects
				(font
					(size 1.27 1.27)
				)
			)
		)
		(property "Value" "SSM3K324R-GP"
			(at 0.127 -8.9662 90)
			(unlocked yes)
			(layer "F.Fab")
			(hide yes)
			(effects
				(font
					(size 1.016 1.016)
					(thickness 0.1524)
				)
			)
		)
		(property "Device Type" "SOT23DGS2D4H35"
			(at 0.127 -10.4902 90)
			(unlocked yes)
			(layer "F.Fab")
			(hide yes)
			(effects
				(font
					(size 1.016 1.016)
					(thickness 0.1524)
				)
			)
		)
		(duplicate_pad_numbers_are_jumpers no)
		(fp_line
			(start 1.651 -1.778)
			(end -1.651 -1.778)
			(stroke
				(width 0.1524)
				(type default)
			)
			(layer "F.SilkS")
		)
		(fp_line
			(start -1.651 -1.778)
			(end -1.651 1.778)
			(stroke
				(width 0.1524)
				(type default)
			)
			(layer "F.SilkS")
		)
		(fp_line
			(start 1.651 1.778)
			(end 1.651 -1.778)
			(stroke
				(width 0.1524)
				(type default)
			)
			(layer "F.SilkS")
		)
		(fp_line
			(start -1.651 1.778)
			(end 1.651 1.778)
			(stroke
				(width 0.1524)
				(type default)
			)
			(layer "F.SilkS")
		)
		(fp_poly
			(pts
				(xy -1.778 1.8796) (xy -1.778 -1.8796) (xy 1.778 -1.8796) (xy 1.778 1.8796)
			)
			(stroke
				(width 0)
				(type default)
			)
			(fill no)
			(layer "F.CrtYd")
		)
		(fp_poly
			(pts
				(xy -1.778 1.8796) (xy -1.778 -1.8796) (xy 1.778 -1.8796) (xy 1.778 1.8796)
			)
			(stroke
				(width 0)
				(type default)
			)
			(fill no)
			(layer "F.Fab")
		)
		(pad "D" smd custom
			(at 0 -0.9525 90)
			(size 0.1905 0.1905)
			(layers "F.Cu" "F.Mask" "F.Paste")
			(net "DRV_ACT_20_N")
			(options
				(clearance outline)
				(anchor circle)
			)
			(primitives
				(gr_poly
					(pts
						(arc
							(start -0.1778 0.5715)
							(mid -0.321484 0.511984)
							(end -0.381 0.3683)
						)
						(arc
							(start -0.381 -0.3683)
							(mid -0.321484 -0.511984)
							(end -0.1778 -0.5715)
						)
						(arc
							(start 0.1778 -0.5715)
							(mid 0.321484 -0.511984)
							(end 0.381 -0.3683)
						)
						(arc
							(start 0.381 0.3683)
							(mid 0.321484 0.511984)
							(end 0.1778 0.5715)
						)
					)
					(width 0)
					(fill yes)
				)
			)
		)
		(pad "G" smd custom
			(at -0.98425 0.9525 90)
			(size 0.1905 0.1905)
			(layers "F.Cu" "F.Mask" "F.Paste")
			(net "DRIVE_B_20_ACT")
			(options
				(clearance outline)
				(anchor circle)
			)
			(primitives
				(gr_poly
					(pts
						(arc
							(start -0.1778 0.5715)
							(mid -0.321484 0.511984)
							(end -0.381 0.3683)
						)
						(arc
							(start -0.381 -0.3683)
							(mid -0.321484 -0.511984)
							(end -0.1778 -0.5715)
						)
						(arc
							(start 0.1778 -0.5715)
							(mid 0.321484 -0.511984)
							(end 0.381 -0.3683)
						)
						(arc
							(start 0.381 0.3683)
							(mid 0.321484 0.511984)
							(end 0.1778 0.5715)
						)
					)
					(width 0)
					(fill yes)
				)
			)
		)
		(pad "S" smd custom
			(at 0.98425 0.9525 90)
			(size 0.1905 0.1905)
			(layers "F.Cu" "F.Mask" "F.Paste")
			(net "GND")
			(options
				(clearance outline)
				(anchor circle)
			)
			(primitives
				(gr_poly
					(pts
						(arc
							(start -0.1778 0.5715)
							(mid -0.321484 0.511984)
							(end -0.381 0.3683)
						)
						(arc
							(start -0.381 -0.3683)
							(mid -0.321484 -0.511984)
							(end -0.1778 -0.5715)
						)
						(arc
							(start 0.1778 -0.5715)
							(mid 0.321484 -0.511984)
							(end 0.381 -0.3683)
						)
						(arc
							(start 0.381 0.3683)
							(mid 0.321484 0.511984)
							(end 0.1778 0.5715)
						)
					)
					(width 0)
					(fill yes)
				)
			)
		)
	)
	(footprint ""
		(layer "F.Cu")
		(at 384.734562 -244.660674 -90)
		(property "Reference" "C133"
			(at 0 0 270)
			(layer "F.SilkS")
			(hide yes)
			(effects
				(font
					(size 1.27 1.27)
				)
			)
		)
		(property "Value" "SCD01U16V1KX-GP"
			(at -2.8321 -1.7399 270)
			(unlocked yes)
			(layer "F.Fab")
			(hide yes)
			(effects
				(font
					(size 1.016 1.016)
					(thickness 0.1524)
				)
			)
		)
		(property "Device Type" "C0201H13"
			(at -2.8321 -3.2639 270)
			(unlocked yes)
			(layer "F.Fab")
			(hide yes)
			(effects
				(font
					(size 1.016 1.016)
					(thickness 0.1524)
				)
			)
		)
		(duplicate_pad_numbers_are_jumpers no)
		(fp_rect
			(start -0.2794 0.6477)
			(end 0.2794 -0.6477)
			(stroke
				(width 0)
				(type default)
			)
			(fill no)
			(layer "F.CrtYd")
		)
		(fp_rect
			(start -0.2794 0.6477)
			(end 0.2794 -0.6477)
			(stroke
				(width 0)
				(type default)
			)
			(fill no)
			(layer "F.Fab")
		)
		(pad "1" smd custom
			(at 0 -0.2794 270)
			(size 0.0762 0.0762)
			(layers "F.Cu" "F.Mask" "F.Paste")
			(net "SAS_HDD_RX_P8")
			(options
				(clearance outline)
				(anchor circle)
			)
			(primitives
				(gr_poly
					(pts
						(arc
							(start 0.1524 -0.127)
							(mid 0.137521 -0.162921)
							(end 0.1016 -0.1778)
						)
						(arc
							(start -0.1016 -0.1778)
							(mid -0.137521 -0.162921)
							(end -0.1524 -0.127)
						)
						(arc
							(start -0.1524 0.127)
							(mid -0.137521 0.162921)
							(end -0.1016 0.1778)
						)
						(arc
							(start 0.1016 0.1778)
							(mid 0.137521 0.162921)
							(end 0.1524 0.127)
						)
					)
					(width 0)
					(fill yes)
				)
			)
		)
		(pad "2" smd custom
			(at 0 0.2794 270)
			(size 0.0762 0.0762)
			(layers "F.Cu" "F.Mask" "F.Paste")
			(net "PHY_SCC_B_TO_DRV_B_8_DP")
			(options
				(clearance outline)
				(anchor circle)
			)
			(primitives
				(gr_poly
					(pts
						(arc
							(start 0.1524 -0.127)
							(mid 0.137521 -0.162921)
							(end 0.1016 -0.1778)
						)
						(arc
							(start -0.1016 -0.1778)
							(mid -0.137521 -0.162921)
							(end -0.1524 -0.127)
						)
						(arc
							(start -0.1524 0.127)
							(mid -0.137521 0.162921)
							(end -0.1016 0.1778)
						)
						(arc
							(start 0.1016 0.1778)
							(mid 0.137521 0.162921)
							(end 0.1524 0.127)
						)
					)
					(width 0)
					(fill yes)
				)
			)
		)
	)
	(footprint ""
		(layer "F.Cu")
		(at 144.653 -16.637)
		(property "Reference" "R731"
			(at 0 0 0)
			(layer "F.SilkS")
			(hide yes)
			(effects
				(font
					(size 1.27 1.27)
				)
			)
		)
		(property "Value" "0R2J-2-GP"
			(at 0.064008 -3.993896 0)
			(unlocked yes)
			(layer "F.Fab")
			(hide yes)
			(effects
				(font
					(size 1.016 1.016)
					(thickness 0.1524)
				)
			)
		)
		(property "Device Type" "R402H16"
			(at 0.064008 -5.517896 0)
			(unlocked yes)
			(layer "F.Fab")
			(hide yes)
			(effects
				(font
					(size 1.016 1.016)
					(thickness 0.1524)
				)
			)
		)
		(duplicate_pad_numbers_are_jumpers no)
		(fp_line
			(start -0.508 -0.9398)
			(end -0.508 0.9398)
			(stroke
				(width 0.1524)
				(type default)
			)
			(layer "F.SilkS")
		)
		(fp_line
			(start 0.508 -0.9398)
			(end -0.508 -0.9398)
			(stroke
				(width 0.1524)
				(type default)
			)
			(layer "F.SilkS")
		)
		(fp_rect
			(start -0.508 0.9398)
			(end 0.508 -0.9398)
			(stroke
				(width 0)
				(type default)
			)
			(fill no)
			(layer "F.CrtYd")
		)
		(fp_rect
			(start -0.508 0.9398)
			(end 0.508 -0.9398)
			(stroke
				(width 0)
				(type default)
			)
			(fill no)
			(layer "F.Fab")
		)
		(pad "1" smd custom
			(at 0 -0.4445)
			(size 0.1397 0.1397)
			(layers "F.Cu" "F.Mask" "F.Paste")
			(net "SW_HDD_G28")
			(options
				(clearance outline)
				(anchor circle)
			)
			(primitives
				(gr_poly
					(pts
						(arc
							(start -0.1778 -0.2794)
							(mid -0.249642 -0.249642)
							(end -0.2794 -0.1778)
						)
						(arc
							(start -0.2794 0.1778)
							(mid -0.249642 0.249642)
							(end -0.1778 0.2794)
						)
						(arc
							(start 0.1778 0.2794)
							(mid 0.249642 0.249642)
							(end 0.2794 0.1778)
						)
						(arc
							(start 0.2794 -0.1778)
							(mid 0.249642 -0.249642)
							(end 0.1778 -0.2794)
						)
					)
					(width 0)
					(fill yes)
				)
			)
		)
		(pad "2" smd custom
			(at 0 0.4445)
			(size 0.1397 0.1397)
			(layers "F.Cu" "F.Mask" "F.Paste")
			(net "SW_HDD_R28")
			(options
				(clearance outline)
				(anchor circle)
			)
			(primitives
				(gr_poly
					(pts
						(arc
							(start -0.1778 -0.2794)
							(mid -0.249642 -0.249642)
							(end -0.2794 -0.1778)
						)
						(arc
							(start -0.2794 0.1778)
							(mid -0.249642 0.249642)
							(end -0.1778 0.2794)
						)
						(arc
							(start 0.1778 0.2794)
							(mid 0.249642 0.249642)
							(end 0.2794 0.1778)
						)
						(arc
							(start 0.2794 -0.1778)
							(mid 0.249642 -0.249642)
							(end 0.1778 -0.2794)
						)
					)
					(width 0)
					(fill yes)
				)
			)
		)
	)
	(footprint ""
		(layer "F.Cu")
		(at 140.97 -265.684 -90)
		(property "Reference" "C86"
			(at 0 0 270)
			(layer "F.SilkS")
			(hide yes)
			(effects
				(font
					(size 1.27 1.27)
				)
			)
		)
		(property "Value" "SC4D7U25V5KX-1-GP"
			(at -0.0762 -6.1214 270)
			(unlocked yes)
			(layer "F.Fab")
			(hide yes)
			(effects
				(font
					(size 1.016 1.016)
					(thickness 0.1524)
				)
			)
		)
		(property "Device Type" "C805H58"
			(at -0.0762 -8.1534 270)
			(unlocked yes)
			(layer "F.Fab")
			(hide yes)
			(effects
				(font
					(size 1.016 1.016)
					(thickness 0.1524)
				)
			)
		)
		(duplicate_pad_numbers_are_jumpers no)
		(fp_line
			(start 0.635 0)
			(end -0.635 0)
			(stroke
				(width 0.508)
				(type default)
			)
			(layer "F.SilkS")
		)
		(fp_rect
			(start -0.9652 1.778)
			(end 0.9652 -1.778)
			(stroke
				(width 0)
				(type default)
			)
			(fill no)
			(layer "F.CrtYd")
		)
		(fp_poly
			(pts
				(xy -0.9652 -1.778) (xy 0.9652 -1.778) (xy 0.9652 1.778) (xy -0.9652 1.778)
			)
			(stroke
				(width 0)
				(type default)
			)
			(fill no)
			(layer "F.Fab")
		)
		(pad "1" smd rect
			(at 0 -0.9652 270)
			(size 1.397 1.143)
			(layers "F.Cu" "F.Mask" "F.Paste")
			(net "P12V_HDD4")
		)
		(pad "2" smd rect
			(at 0 0.9652 270)
			(size 1.397 1.143)
			(layers "F.Cu" "F.Mask" "F.Paste")
			(net "GND")
		)
	)
	(footprint ""
		(layer "F.Cu")
		(at 22.5044 -131.2672 -90)
		(property "Reference" "R358"
			(at 0 0 270)
			(layer "F.SilkS")
			(hide yes)
			(effects
				(font
					(size 1.27 1.27)
				)
			)
		)
		(property "Value" "0R2J-2-GP"
			(at 0.064008 -3.993896 270)
			(unlocked yes)
			(layer "F.Fab")
			(hide yes)
			(effects
				(font
					(size 1.016 1.016)
					(thickness 0.1524)
				)
			)
		)
		(property "Device Type" "R402H16"
			(at 0.064008 -5.517896 270)
			(unlocked yes)
			(layer "F.Fab")
			(hide yes)
			(effects
				(font
					(size 1.016 1.016)
					(thickness 0.1524)
				)
			)
		)
		(duplicate_pad_numbers_are_jumpers no)
		(fp_line
			(start -0.508 -0.9398)
			(end -0.508 0.9398)
			(stroke
				(width 0.1524)
				(type default)
			)
			(layer "F.SilkS")
		)
		(fp_line
			(start 0.508 -0.9398)
			(end -0.508 -0.9398)
			(stroke
				(width 0.1524)
				(type default)
			)
			(layer "F.SilkS")
		)
		(fp_rect
			(start -0.508 0.9398)
			(end 0.508 -0.9398)
			(stroke
				(width 0)
				(type default)
			)
			(fill no)
			(layer "F.CrtYd")
		)
		(fp_rect
			(start -0.508 0.9398)
			(end 0.508 -0.9398)
			(stroke
				(width 0)
				(type default)
			)
			(fill no)
			(layer "F.Fab")
		)
		(pad "1" smd custom
			(at 0 -0.4445 270)
			(size 0.1397 0.1397)
			(layers "F.Cu" "F.Mask" "F.Paste")
			(net "DRIVE_B_12_PWR")
			(options
				(clearance outline)
				(anchor circle)
			)
			(primitives
				(gr_poly
					(pts
						(arc
							(start -0.1778 -0.2794)
							(mid -0.249642 -0.249642)
							(end -0.2794 -0.1778)
						)
						(arc
							(start -0.2794 0.1778)
							(mid -0.249642 0.249642)
							(end -0.1778 0.2794)
						)
						(arc
							(start 0.1778 0.2794)
							(mid 0.249642 0.249642)
							(end 0.2794 0.1778)
						)
						(arc
							(start 0.2794 -0.1778)
							(mid 0.249642 -0.249642)
							(end 0.1778 -0.2794)
						)
					)
					(width 0)
					(fill yes)
				)
			)
		)
		(pad "2" smd custom
			(at 0 0.4445 270)
			(size 0.1397 0.1397)
			(layers "F.Cu" "F.Mask" "F.Paste")
			(net "SW_PWR_R_HDD12")
			(options
				(clearance outline)
				(anchor circle)
			)
			(primitives
				(gr_poly
					(pts
						(arc
							(start -0.1778 -0.2794)
							(mid -0.249642 -0.249642)
							(end -0.2794 -0.1778)
						)
						(arc
							(start -0.2794 0.1778)
							(mid -0.249642 0.249642)
							(end -0.1778 0.2794)
						)
						(arc
							(start 0.1778 0.2794)
							(mid 0.249642 0.249642)
							(end 0.2794 0.1778)
						)
						(arc
							(start 0.2794 -0.1778)
							(mid 0.249642 -0.249642)
							(end 0.1778 -0.2794)
						)
					)
					(width 0)
					(fill yes)
				)
			)
		)
	)
	(footprint ""
		(layer "F.Cu")
		(at 273.5834 -331.34173 90)
		(property "Reference" "R90"
			(at 0 0 90)
			(layer "F.SilkS")
			(hide yes)
			(effects
				(font
					(size 1.27 1.27)
				)
			)
		)
		(property "Value" "4K7R2F-GP"
			(at 0.064008 -3.993896 90)
			(unlocked yes)
			(layer "F.Fab")
			(hide yes)
			(effects
				(font
					(size 1.016 1.016)
					(thickness 0.1524)
				)
			)
		)
		(property "Device Type" "R402H16"
			(at 0.064008 -5.517896 90)
			(unlocked yes)
			(layer "F.Fab")
			(hide yes)
			(effects
				(font
					(size 1.016 1.016)
					(thickness 0.1524)
				)
			)
		)
		(duplicate_pad_numbers_are_jumpers no)
		(fp_line
			(start 0.508 -0.9398)
			(end -0.508 -0.9398)
			(stroke
				(width 0.1524)
				(type default)
			)
			(layer "F.SilkS")
		)
		(fp_line
			(start -0.508 -0.9398)
			(end -0.508 0.9398)
			(stroke
				(width 0.1524)
				(type default)
			)
			(layer "F.SilkS")
		)
		(fp_rect
			(start -0.508 0.9398)
			(end 0.508 -0.9398)
			(stroke
				(width 0)
				(type default)
			)
			(fill no)
			(layer "F.CrtYd")
		)
		(fp_rect
			(start -0.508 0.9398)
			(end 0.508 -0.9398)
			(stroke
				(width 0)
				(type default)
			)
			(fill no)
			(layer "F.Fab")
		)
		(pad "1" smd custom
			(at 0 -0.4445 90)
			(size 0.1397 0.1397)
			(layers "F.Cu" "F.Mask" "F.Paste")
			(net "P3V3_IN")
			(options
				(clearance outline)
				(anchor circle)
			)
			(primitives
				(gr_poly
					(pts
						(arc
							(start -0.1778 -0.2794)
							(mid -0.249642 -0.249642)
							(end -0.2794 -0.1778)
						)
						(arc
							(start -0.2794 0.1778)
							(mid -0.249642 0.249642)
							(end -0.1778 0.2794)
						)
						(arc
							(start 0.1778 0.2794)
							(mid 0.249642 0.249642)
							(end 0.2794 0.1778)
						)
						(arc
							(start 0.2794 -0.1778)
							(mid 0.249642 -0.249642)
							(end 0.1778 -0.2794)
						)
					)
					(width 0)
					(fill yes)
				)
			)
		)
		(pad "2" smd custom
			(at 0 0.4445 90)
			(size 0.1397 0.1397)
			(layers "F.Cu" "F.Mask" "F.Paste")
			(net "PWM_OUT_FAN1")
			(options
				(clearance outline)
				(anchor circle)
			)
			(primitives
				(gr_poly
					(pts
						(arc
							(start -0.1778 -0.2794)
							(mid -0.249642 -0.249642)
							(end -0.2794 -0.1778)
						)
						(arc
							(start -0.2794 0.1778)
							(mid -0.249642 0.249642)
							(end -0.1778 0.2794)
						)
						(arc
							(start 0.1778 0.2794)
							(mid 0.249642 0.249642)
							(end 0.2794 0.1778)
						)
						(arc
							(start 0.2794 -0.1778)
							(mid 0.249642 -0.249642)
							(end 0.1778 -0.2794)
						)
					)
					(width 0)
					(fill yes)
				)
			)
		)
	)
	(footprint ""
		(layer "F.Cu")
		(at 236.22 -192.86728 90)
		(property "Reference" "C15"
			(at 0 0 90)
			(layer "F.SilkS")
			(hide yes)
			(effects
				(font
					(size 1.27 1.27)
				)
			)
		)
		(property "Value" "SC1U16V3KX-5GP"
			(at 0 -2.8194 90)
			(unlocked yes)
			(layer "F.Fab")
			(hide yes)
			(effects
				(font
					(size 1.016 1.016)
					(thickness 0.1524)
				)
			)
		)
		(property "Device Type" "C603H36"
			(at 0 -4.3434 90)
			(unlocked yes)
			(layer "F.Fab")
			(hide yes)
			(effects
				(font
					(size 1.016 1.016)
					(thickness 0.1524)
				)
			)
		)
		(duplicate_pad_numbers_are_jumpers no)
		(fp_line
			(start 0.508 0)
			(end -0.508 0)
			(stroke
				(width 0.2032)
				(type default)
			)
			(layer "F.SilkS")
		)
		(fp_rect
			(start -0.5842 1.3335)
			(end 0.5842 -1.3335)
			(stroke
				(width 0)
				(type default)
			)
			(fill no)
			(layer "F.CrtYd")
		)
		(fp_rect
			(start -0.5842 1.3335)
			(end 0.5842 -1.3335)
			(stroke
				(width 0)
				(type default)
			)
			(fill no)
			(layer "F.Fab")
		)
		(pad "1" smd custom
			(at 0 -0.762 90)
			(size 0.2159 0.2159)
			(layers "F.Cu" "F.Mask" "F.Paste")
			(net "GPIO_VCC_U9")
			(options
				(clearance outline)
				(anchor circle)
			)
			(primitives
				(gr_poly
					(pts
						(arc
							(start -0.3302 -0.4318)
							(mid -0.402042 -0.402042)
							(end -0.4318 -0.3302)
						)
						(arc
							(start -0.4318 0.3302)
							(mid -0.402042 0.402042)
							(end -0.3302 0.4318)
						)
						(arc
							(start 0.3302 0.4318)
							(mid 0.402042 0.402042)
							(end 0.4318 0.3302)
						)
						(arc
							(start 0.4318 -0.3302)
							(mid 0.402042 -0.402042)
							(end 0.3302 -0.4318)
						)
					)
					(width 0)
					(fill yes)
				)
			)
		)
		(pad "2" smd custom
			(at 0 0.762 90)
			(size 0.2159 0.2159)
			(layers "F.Cu" "F.Mask" "F.Paste")
			(net "GND")
			(options
				(clearance outline)
				(anchor circle)
			)
			(primitives
				(gr_poly
					(pts
						(arc
							(start -0.3302 -0.4318)
							(mid -0.402042 -0.402042)
							(end -0.4318 -0.3302)
						)
						(arc
							(start -0.4318 0.3302)
							(mid -0.402042 0.402042)
							(end -0.3302 0.4318)
						)
						(arc
							(start 0.3302 0.4318)
							(mid 0.402042 0.402042)
							(end 0.4318 0.3302)
						)
						(arc
							(start 0.4318 -0.3302)
							(mid 0.402042 -0.402042)
							(end 0.3302 -0.4318)
						)
					)
					(width 0)
					(fill yes)
				)
			)
		)
	)
	(footprint ""
		(layer "F.Cu")
		(at 348.546166 -364.24743 90)
		(property "Reference" "C532"
			(at 0 0 90)
			(layer "F.SilkS")
			(hide yes)
			(effects
				(font
					(size 1.27 1.27)
				)
			)
		)
		(property "Value" "SCD1U25V2KX-2-GP"
			(at 1.1811 -2.7051 90)
			(unlocked yes)
			(layer "F.Fab")
			(hide yes)
			(effects
				(font
					(size 1.016 1.016)
					(thickness 0.1524)
				)
			)
		)
		(property "Device Type" "C402H22"
			(at 1.1811 -4.2291 90)
			(unlocked yes)
			(layer "F.Fab")
			(hide yes)
			(effects
				(font
					(size 1.016 1.016)
					(thickness 0.1524)
				)
			)
		)
		(duplicate_pad_numbers_are_jumpers no)
		(fp_rect
			(start -0.4318 0.9525)
			(end 0.4318 -0.9525)
			(stroke
				(width 0)
				(type default)
			)
			(fill no)
			(layer "F.CrtYd")
		)
		(fp_rect
			(start -0.4318 0.9525)
			(end 0.4318 -0.9525)
			(stroke
				(width 0)
				(type default)
			)
			(fill no)
			(layer "F.Fab")
		)
		(pad "1" smd custom
			(at 0 -0.4445 90)
			(size 0.1524 0.1524)
			(layers "F.Cu" "F.Mask" "F.Paste")
			(net "P12V_FAN2")
			(options
				(clearance outline)
				(anchor circle)
			)
			(primitives
				(gr_poly
					(pts
						(arc
							(start 0.3048 -0.2032)
							(mid 0.275042 -0.275042)
							(end 0.2032 -0.3048)
						)
						(arc
							(start -0.2032 -0.3048)
							(mid -0.275042 -0.275042)
							(end -0.3048 -0.2032)
						)
						(arc
							(start -0.3048 0.2032)
							(mid -0.275042 0.275042)
							(end -0.2032 0.3048)
						)
						(arc
							(start 0.2032 0.3048)
							(mid 0.275042 0.275042)
							(end 0.3048 0.2032)
						)
					)
					(width 0)
					(fill yes)
				)
			)
		)
		(pad "2" smd custom
			(at 0 0.4445 90)
			(size 0.1524 0.1524)
			(layers "F.Cu" "F.Mask" "F.Paste")
			(net "GND")
			(options
				(clearance outline)
				(anchor circle)
			)
			(primitives
				(gr_poly
					(pts
						(arc
							(start 0.3048 -0.2032)
							(mid 0.275042 -0.275042)
							(end 0.2032 -0.3048)
						)
						(arc
							(start -0.2032 -0.3048)
							(mid -0.275042 -0.275042)
							(end -0.3048 -0.2032)
						)
						(arc
							(start -0.3048 0.2032)
							(mid -0.275042 0.275042)
							(end -0.2032 0.3048)
						)
						(arc
							(start 0.2032 0.3048)
							(mid 0.275042 0.275042)
							(end 0.3048 0.2032)
						)
					)
					(width 0)
					(fill yes)
				)
			)
		)
	)
	(footprint ""
		(layer "F.Cu")
		(at 315.849 -98.171)
		(property "Reference" "R428"
			(at 0 0 0)
			(layer "F.SilkS")
			(hide yes)
			(effects
				(font
					(size 1.27 1.27)
				)
			)
		)
		(property "Value" "130R3F-GP"
			(at -0.0254 -2.5146 0)
			(unlocked yes)
			(layer "F.Fab")
			(hide yes)
			(effects
				(font
					(size 1.016 1.016)
					(thickness 0.1524)
				)
			)
		)
		(property "Device Type" "R603H22"
			(at -0.0254 -4.0386 0)
			(unlocked yes)
			(layer "F.Fab")
			(hide yes)
			(effects
				(font
					(size 1.016 1.016)
					(thickness 0.1524)
				)
			)
		)
		(duplicate_pad_numbers_are_jumpers no)
		(fp_line
			(start -0.4826 0)
			(end -0.2032 0)
			(stroke
				(width 0.2032)
				(type default)
			)
			(layer "F.SilkS")
		)
		(fp_line
			(start 0.2032 0)
			(end 0.4826 0)
			(stroke
				(width 0.2032)
				(type default)
			)
			(layer "F.SilkS")
		)
		(fp_rect
			(start -0.5842 1.3335)
			(end 0.5842 -1.3335)
			(stroke
				(width 0)
				(type default)
			)
			(fill no)
			(layer "F.CrtYd")
		)
		(fp_rect
			(start -0.5842 1.3335)
			(end 0.5842 -1.3335)
			(stroke
				(width 0)
				(type default)
			)
			(fill no)
			(layer "F.Fab")
		)
		(pad "1" smd custom
			(at 0 -0.762)
			(size 0.2159 0.2159)
			(layers "F.Cu" "F.Mask" "F.Paste")
			(net "P5V_B_3")
			(options
				(clearance outline)
				(anchor circle)
			)
			(primitives
				(gr_poly
					(pts
						(arc
							(start -0.3302 -0.4318)
							(mid -0.402042 -0.402042)
							(end -0.4318 -0.3302)
						)
						(arc
							(start -0.4318 0.3302)
							(mid -0.402042 0.402042)
							(end -0.3302 0.4318)
						)
						(arc
							(start 0.3302 0.4318)
							(mid 0.402042 0.402042)
							(end 0.4318 0.3302)
						)
						(arc
							(start 0.4318 -0.3302)
							(mid 0.402042 -0.402042)
							(end 0.3302 -0.4318)
						)
					)
					(width 0)
					(fill yes)
				)
			)
		)
		(pad "2" smd custom
			(at 0 0.762)
			(size 0.2159 0.2159)
			(layers "F.Cu" "F.Mask" "F.Paste")
			(net "FLT_HDD18")
			(options
				(clearance outline)
				(anchor circle)
			)
			(primitives
				(gr_poly
					(pts
						(arc
							(start -0.3302 -0.4318)
							(mid -0.402042 -0.402042)
							(end -0.4318 -0.3302)
						)
						(arc
							(start -0.4318 0.3302)
							(mid -0.402042 0.402042)
							(end -0.3302 0.4318)
						)
						(arc
							(start 0.3302 0.4318)
							(mid 0.402042 0.402042)
							(end 0.4318 0.3302)
						)
						(arc
							(start 0.4318 -0.3302)
							(mid 0.402042 -0.402042)
							(end 0.3302 -0.4318)
						)
					)
					(width 0)
					(fill yes)
				)
			)
		)
	)
	(footprint ""
		(layer "F.Cu")
		(at 396.7734 -270.637 -90)
		(property "Reference" "R288"
			(at 0 0 270)
			(layer "F.SilkS")
			(hide yes)
			(effects
				(font
					(size 1.27 1.27)
				)
			)
		)
		(property "Value" "2R6F-GP"
			(at -0.0508 -4.8514 270)
			(unlocked yes)
			(layer "F.Fab")
			(hide yes)
			(effects
				(font
					(size 1.016 1.016)
					(thickness 0.1524)
				)
			)
		)
		(property "Device Type" "R1206H26"
			(at 0 -6.3754 270)
			(unlocked yes)
			(layer "F.Fab")
			(hide yes)
			(effects
				(font
					(size 1.016 1.016)
					(thickness 0.1524)
				)
			)
		)
		(duplicate_pad_numbers_are_jumpers no)
		(fp_line
			(start -1.016 2.2352)
			(end -1.016 -2.2352)
			(stroke
				(width 0.1524)
				(type default)
			)
			(layer "F.SilkS")
		)
		(fp_line
			(start 1.016 2.2352)
			(end -1.016 2.2352)
			(stroke
				(width 0.1524)
				(type default)
			)
			(layer "F.SilkS")
		)
		(fp_line
			(start -1.016 -2.2352)
			(end 1.016 -2.2352)
			(stroke
				(width 0.1524)
				(type default)
			)
			(layer "F.SilkS")
		)
		(fp_line
			(start 1.016 -2.2352)
			(end 1.016 2.2352)
			(stroke
				(width 0.1524)
				(type default)
			)
			(layer "F.SilkS")
		)
		(fp_rect
			(start -1.0922 2.3114)
			(end 1.0922 -2.3114)
			(stroke
				(width 0)
				(type default)
			)
			(fill no)
			(layer "F.CrtYd")
		)
		(fp_poly
			(pts
				(xy -1.0922 -2.3114) (xy 1.0922 -2.3114) (xy 1.0922 2.3114) (xy -1.0922 2.3114)
			)
			(stroke
				(width 0)
				(type default)
			)
			(fill no)
			(layer "F.Fab")
		)
		(pad "1" smd rect
			(at 0 -1.397 270)
			(size 1.651 1.27)
			(layers "F.Cu" "F.Mask" "F.Paste")
			(net "P12V_HDD8")
		)
		(pad "2" smd rect
			(at 0 1.397 270)
			(size 1.651 1.27)
			(layers "F.Cu" "F.Mask" "F.Paste")
			(net "12V_PRE_8")
		)
	)
	(footprint ""
		(layer "F.Cu")
		(at 371.801644 -97.390204 -90)
		(property "Reference" "R479"
			(at 0 0 270)
			(layer "F.SilkS")
			(hide yes)
			(effects
				(font
					(size 1.27 1.27)
				)
			)
		)
		(property "Value" "4K7R2F-GP"
			(at 0.064008 -3.993896 270)
			(unlocked yes)
			(layer "F.Fab")
			(hide yes)
			(effects
				(font
					(size 1.016 1.016)
					(thickness 0.1524)
				)
			)
		)
		(property "Device Type" "R402H16"
			(at 0.064008 -5.517896 270)
			(unlocked yes)
			(layer "F.Fab")
			(hide yes)
			(effects
				(font
					(size 1.016 1.016)
					(thickness 0.1524)
				)
			)
		)
		(duplicate_pad_numbers_are_jumpers no)
		(fp_line
			(start -0.508 -0.9398)
			(end -0.508 0.9398)
			(stroke
				(width 0.1524)
				(type default)
			)
			(layer "F.SilkS")
		)
		(fp_line
			(start 0.508 -0.9398)
			(end -0.508 -0.9398)
			(stroke
				(width 0.1524)
				(type default)
			)
			(layer "F.SilkS")
		)
		(fp_rect
			(start -0.508 0.9398)
			(end 0.508 -0.9398)
			(stroke
				(width 0)
				(type default)
			)
			(fill no)
			(layer "F.CrtYd")
		)
		(fp_rect
			(start -0.508 0.9398)
			(end 0.508 -0.9398)
			(stroke
				(width 0)
				(type default)
			)
			(fill no)
			(layer "F.Fab")
		)
		(pad "1" smd custom
			(at 0 -0.4445 270)
			(size 0.1397 0.1397)
			(layers "F.Cu" "F.Mask" "F.Paste")
			(net "DRIVE_B_20_ACT")
			(options
				(clearance outline)
				(anchor circle)
			)
			(primitives
				(gr_poly
					(pts
						(arc
							(start -0.1778 -0.2794)
							(mid -0.249642 -0.249642)
							(end -0.2794 -0.1778)
						)
						(arc
							(start -0.2794 0.1778)
							(mid -0.249642 0.249642)
							(end -0.1778 0.2794)
						)
						(arc
							(start 0.1778 0.2794)
							(mid 0.249642 0.249642)
							(end 0.2794 0.1778)
						)
						(arc
							(start 0.2794 -0.1778)
							(mid 0.249642 -0.249642)
							(end 0.1778 -0.2794)
						)
					)
					(width 0)
					(fill yes)
				)
			)
		)
		(pad "2" smd custom
			(at 0 0.4445 270)
			(size 0.1397 0.1397)
			(layers "F.Cu" "F.Mask" "F.Paste")
			(net "GND")
			(options
				(clearance outline)
				(anchor circle)
			)
			(primitives
				(gr_poly
					(pts
						(arc
							(start -0.1778 -0.2794)
							(mid -0.249642 -0.249642)
							(end -0.2794 -0.1778)
						)
						(arc
							(start -0.2794 0.1778)
							(mid -0.249642 0.249642)
							(end -0.1778 0.2794)
						)
						(arc
							(start 0.1778 0.2794)
							(mid 0.249642 0.249642)
							(end 0.2794 0.1778)
						)
						(arc
							(start 0.2794 -0.1778)
							(mid 0.249642 -0.249642)
							(end 0.1778 -0.2794)
						)
					)
					(width 0)
					(fill yes)
				)
			)
		)
	)
	(footprint ""
		(layer "F.Cu")
		(at 244.9322 -341.4268)
		(property "Reference" "R1047"
			(at 0 0 0)
			(layer "F.SilkS")
			(hide yes)
			(effects
				(font
					(size 1.27 1.27)
				)
			)
		)
		(property "Value" "D0003R4026F-GP"
			(at -6.737858 -1.79959 0)
			(unlocked yes)
			(layer "F.Fab")
			(hide yes)
			(effects
				(font
					(size 1.016 1.016)
					(thickness 0.1524)
				)
			)
		)
		(property "Device Type" "RL4026-4PH149"
			(at -6.737858 -3.32359 0)
			(unlocked yes)
			(layer "F.Fab")
			(hide yes)
			(effects
				(font
					(size 1.016 1.016)
					(thickness 0.1524)
				)
			)
		)
		(duplicate_pad_numbers_are_jumpers no)
		(fp_line
			(start -5.6769 2.4765)
			(end -5.6769 4.0259)
			(stroke
				(width 0.3302)
				(type default)
			)
			(layer "F.SilkS")
		)
		(fp_line
			(start -5.6769 4.0259)
			(end -4.1402 4.0259)
			(stroke
				(width 0.3302)
				(type default)
			)
			(layer "F.SilkS")
		)
		(fp_line
			(start -5.588 -3.937)
			(end 5.588 -3.937)
			(stroke
				(width 0.1524)
				(type default)
			)
			(layer "F.SilkS")
		)
		(fp_line
			(start -5.588 3.937)
			(end -5.588 -3.937)
			(stroke
				(width 0.1524)
				(type default)
			)
			(layer "F.SilkS")
		)
		(fp_line
			(start 5.588 -3.937)
			(end 5.588 3.937)
			(stroke
				(width 0.1524)
				(type default)
			)
			(layer "F.SilkS")
		)
		(fp_line
			(start 5.588 3.937)
			(end -5.588 3.937)
			(stroke
				(width 0.1524)
				(type default)
			)
			(layer "F.SilkS")
		)
		(fp_poly
			(pts
				(xy -4.703572 3.998468) (xy -5.289804 4.5847) (xy -4.11734 4.5847)
			)
			(stroke
				(width 0)
				(type default)
			)
			(fill yes)
			(layer "F.SilkS")
		)
		(fp_rect
			(start -5.0546 3.302)
			(end 5.0546 -3.302)
			(stroke
				(width 0)
				(type default)
			)
			(fill no)
			(layer "F.CrtYd")
		)
		(fp_poly
			(pts
				(xy -5.842 4.191) (xy -5.842 -4.191) (xy 5.842 -4.191) (xy 5.842 -0.00635) (xy 5.0546 -0.00635)
				(xy 5.0546 -3.302) (xy -5.0546 -3.302) (xy -5.0546 3.302) (xy 5.0546 3.302) (xy 5.0546 0.00635)
				(xy 5.842 0.00635) (xy 5.842 4.191)
			)
			(stroke
				(width 0)
				(type default)
			)
			(fill no)
			(layer "F.CrtYd")
		)
		(fp_rect
			(start -5.842 4.191)
			(end 5.842 -4.191)
			(stroke
				(width 0)
				(type default)
			)
			(fill no)
			(layer "F.Fab")
		)
		(pad "1" smd rect
			(at -4.115054 0.890016)
			(size 2.4384 5.588)
			(layers "F.Cu" "F.Mask" "F.Paste")
			(net "P12V_IN")
		)
		(pad "2" smd rect
			(at 4.115054 0.890016)
			(size 2.4384 5.588)
			(layers "F.Cu" "F.Mask" "F.Paste")
			(net "MB3_P12V_IN_R")
		)
		(pad "3" smd rect
			(at -4.115054 -3.245104)
			(size 2.4384 0.889)
			(layers "F.Cu" "F.Mask" "F.Paste")
			(net "MB3_CM_SENSE_R1_P")
		)
		(pad "4" smd rect
			(at 4.115054 -3.245104)
			(size 2.4384 0.889)
			(layers "F.Cu" "F.Mask" "F.Paste")
			(net "MB3_CM_SENSE_R1_N")
		)
		(zone
			(layer "F.Cu")
			(hatch none 0.5)
			(connect_pads
				(clearance 0)
			)
			(min_thickness 0.25)
			(keepout
				(tracks allowed)
				(vias not_allowed)
				(pads allowed)
				(copperpour not_allowed)
				(footprints allowed)
			)
			(placement
				(enabled no)
				(sheetname "")
			)
			(fill
				(thermal_gap 0.5)
				(thermal_bridge_width 0.5)
				(island_removal_mode 0)
			)
			(polygon
				(pts
					(xy 239.597946 -344.227404) (xy 239.597946 -343.330784) (xy 242.036346 -343.330784) (xy 242.036346 -344.227404)
				)
			)
		)
		(zone
			(layer "F.Cu")
			(hatch none 0.5)
			(connect_pads
				(clearance 0)
			)
			(min_thickness 0.25)
			(keepout
				(tracks not_allowed)
				(vias allowed)
				(pads allowed)
				(copperpour not_allowed)
				(footprints allowed)
			)
			(placement
				(enabled no)
				(sheetname "")
			)
			(fill
				(thermal_gap 0.5)
				(thermal_bridge_width 0.5)
				(island_removal_mode 0)
			)
			(polygon
				(pts
					(xy 239.597946 -343.330784) (xy 242.036346 -343.330784) (xy 242.036346 -344.227404) (xy 239.597946 -344.227404)
				)
			)
		)
		(zone
			(layer "F.Cu")
			(hatch none 0.5)
			(connect_pads
				(clearance 0)
			)
			(min_thickness 0.25)
			(keepout
				(tracks allowed)
				(vias not_allowed)
				(pads allowed)
				(copperpour not_allowed)
				(footprints allowed)
			)
			(placement
				(enabled no)
				(sheetname "")
			)
			(fill
				(thermal_gap 0.5)
				(thermal_bridge_width 0.5)
				(island_removal_mode 0)
			)
			(polygon
				(pts
					(xy 247.828054 -344.227404) (xy 247.828054 -343.330784) (xy 250.266454 -343.330784) (xy 250.266454 -344.227404)
				)
			)
		)
		(zone
			(layer "F.Cu")
			(hatch none 0.5)
			(connect_pads
				(clearance 0)
			)
			(min_thickness 0.25)
			(keepout
				(tracks not_allowed)
				(vias allowed)
				(pads allowed)
				(copperpour not_allowed)
				(footprints allowed)
			)
			(placement
				(enabled no)
				(sheetname "")
			)
			(fill
				(thermal_gap 0.5)
				(thermal_bridge_width 0.5)
				(island_removal_mode 0)
			)
			(polygon
				(pts
					(xy 247.828054 -343.330784) (xy 250.266454 -343.330784) (xy 250.266454 -344.227404) (xy 247.828054 -344.227404)
				)
			)
		)
	)
	(footprint ""
		(layer "F.Cu")
		(at 239.859566 -140.050266 90)
		(property "Reference" "R444"
			(at 0 0 90)
			(layer "F.SilkS")
			(hide yes)
			(effects
				(font
					(size 1.27 1.27)
				)
			)
		)
		(property "Value" "1KR2J-1-GP"
			(at 0.064008 -3.993896 90)
			(unlocked yes)
			(layer "F.Fab")
			(hide yes)
			(effects
				(font
					(size 1.016 1.016)
					(thickness 0.1524)
				)
			)
		)
		(property "Device Type" "R402H16"
			(at 0.064008 -5.517896 90)
			(unlocked yes)
			(layer "F.Fab")
			(hide yes)
			(effects
				(font
					(size 1.016 1.016)
					(thickness 0.1524)
				)
			)
		)
		(duplicate_pad_numbers_are_jumpers no)
		(fp_line
			(start 0.508 -0.9398)
			(end -0.508 -0.9398)
			(stroke
				(width 0.1524)
				(type default)
			)
			(layer "F.SilkS")
		)
		(fp_line
			(start -0.508 -0.9398)
			(end -0.508 0.9398)
			(stroke
				(width 0.1524)
				(type default)
			)
			(layer "F.SilkS")
		)
		(fp_rect
			(start -0.508 0.9398)
			(end 0.508 -0.9398)
			(stroke
				(width 0)
				(type default)
			)
			(fill no)
			(layer "F.CrtYd")
		)
		(fp_rect
			(start -0.508 0.9398)
			(end 0.508 -0.9398)
			(stroke
				(width 0)
				(type default)
			)
			(fill no)
			(layer "F.Fab")
		)
		(pad "1" smd custom
			(at 0 -0.4445 90)
			(size 0.1397 0.1397)
			(layers "F.Cu" "F.Mask" "F.Paste")
			(net "P3V3_STBY_B")
			(options
				(clearance outline)
				(anchor circle)
			)
			(primitives
				(gr_poly
					(pts
						(arc
							(start -0.1778 -0.2794)
							(mid -0.249642 -0.249642)
							(end -0.2794 -0.1778)
						)
						(arc
							(start -0.2794 0.1778)
							(mid -0.249642 0.249642)
							(end -0.1778 0.2794)
						)
						(arc
							(start 0.1778 0.2794)
							(mid 0.249642 0.249642)
							(end 0.2794 0.1778)
						)
						(arc
							(start 0.2794 -0.1778)
							(mid 0.249642 -0.249642)
							(end 0.1778 -0.2794)
						)
					)
					(width 0)
					(fill yes)
				)
			)
		)
		(pad "2" smd custom
			(at 0 0.4445 90)
			(size 0.1397 0.1397)
			(layers "F.Cu" "F.Mask" "F.Paste")
			(net "I2C_SCC_B_SCL_BUF")
			(options
				(clearance outline)
				(anchor circle)
			)
			(primitives
				(gr_poly
					(pts
						(arc
							(start -0.1778 -0.2794)
							(mid -0.249642 -0.249642)
							(end -0.2794 -0.1778)
						)
						(arc
							(start -0.2794 0.1778)
							(mid -0.249642 0.249642)
							(end -0.1778 0.2794)
						)
						(arc
							(start 0.1778 0.2794)
							(mid 0.249642 0.249642)
							(end 0.2794 0.1778)
						)
						(arc
							(start 0.2794 -0.1778)
							(mid 0.249642 -0.249642)
							(end 0.1778 -0.2794)
						)
					)
					(width 0)
					(fill yes)
				)
			)
		)
	)
	(footprint ""
		(layer "F.Cu")
		(at 51.689 -262.001 -90)
		(property "Reference" "C45"
			(at 0 0 270)
			(layer "F.SilkS")
			(hide yes)
			(effects
				(font
					(size 1.27 1.27)
				)
			)
		)
		(property "Value" "SC10U16V6KX-2GP"
			(at -0.0762 -5.1308 270)
			(unlocked yes)
			(layer "F.Fab")
			(hide yes)
			(effects
				(font
					(size 1.016 1.016)
					(thickness 0.1524)
				)
			)
		)
		(property "Device Type" "C1206H71"
			(at -0.127 -6.6548 270)
			(unlocked yes)
			(layer "F.Fab")
			(hide yes)
			(effects
				(font
					(size 1.016 1.016)
					(thickness 0.1524)
				)
			)
		)
		(duplicate_pad_numbers_are_jumpers no)
		(fp_line
			(start -1.016 2.2352)
			(end -1.016 0.8382)
			(stroke
				(width 0.1524)
				(type default)
			)
			(layer "F.SilkS")
		)
		(fp_line
			(start 1.016 2.2352)
			(end -1.016 2.2352)
			(stroke
				(width 0.1524)
				(type default)
			)
			(layer "F.SilkS")
		)
		(fp_line
			(start 1.016 0.8382)
			(end 1.016 2.2352)
			(stroke
				(width 0.1524)
				(type default)
			)
			(layer "F.SilkS")
		)
		(fp_line
			(start -1.016 -0.8382)
			(end -1.016 -2.2352)
			(stroke
				(width 0.1524)
				(type default)
			)
			(layer "F.SilkS")
		)
		(fp_line
			(start -1.016 -2.2352)
			(end 1.016 -2.2352)
			(stroke
				(width 0.1524)
				(type default)
			)
			(layer "F.SilkS")
		)
		(fp_line
			(start 1.016 -2.2352)
			(end 1.016 -0.8382)
			(stroke
				(width 0.1524)
				(type default)
			)
			(layer "F.SilkS")
		)
		(fp_rect
			(start -1.0922 2.3114)
			(end 1.0922 -2.3114)
			(stroke
				(width 0)
				(type default)
			)
			(fill no)
			(layer "F.CrtYd")
		)
		(fp_poly
			(pts
				(xy 1.0922 -2.3114) (xy 1.0922 2.3114) (xy -1.0922 2.3114) (xy -1.0922 -2.3114)
			)
			(stroke
				(width 0)
				(type default)
			)
			(fill no)
			(layer "F.Fab")
		)
		(pad "1" smd rect
			(at 0 -1.397 270)
			(size 1.651 1.27)
			(layers "F.Cu" "F.Mask" "F.Paste")
			(net "P5V_HDD1")
		)
		(pad "2" smd rect
			(at 0 1.397 270)
			(size 1.651 1.27)
			(layers "F.Cu" "F.Mask" "F.Paste")
			(net "GND")
		)
	)
	(footprint ""
		(layer "F.Cu")
		(at 229.49916 -226.431856 180)
		(property "Reference" "U8"
			(at 0 0 180)
			(layer "F.SilkS")
			(hide yes)
			(effects
				(font
					(size 1.27 1.27)
				)
			)
		)
		(property "Value" "TCA9555PWR-GP"
			(at 0 -6.9342 180)
			(unlocked yes)
			(layer "F.Fab")
			(hide yes)
			(effects
				(font
					(size 1.016 1.016)
					(thickness 0.1524)
				)
			)
		)
		(property "Device Type" "TSOIC24H48"
			(at 0 -8.5852 180)
			(unlocked yes)
			(layer "F.Fab")
			(hide yes)
			(effects
				(font
					(size 1.016 1.016)
					(thickness 0.1524)
				)
			)
		)
		(duplicate_pad_numbers_are_jumpers no)
		(fp_line
			(start 3.81 1.397)
			(end -4.2291 1.397)
			(stroke
				(width 0.1524)
				(type default)
			)
			(layer "F.SilkS")
		)
		(fp_line
			(start 3.81 -1.397)
			(end 3.81 1.397)
			(stroke
				(width 0.1524)
				(type default)
			)
			(layer "F.SilkS")
		)
		(fp_line
			(start -3.429 0)
			(end -4.2291 0.8001)
			(stroke
				(width 0.1524)
				(type default)
			)
			(layer "F.SilkS")
		)
		(fp_line
			(start -4.22656 3.81)
			(end -4.2291 1.397)
			(stroke
				(width 0.508)
				(type default)
			)
			(layer "F.SilkS")
		)
		(fp_line
			(start -4.2291 3.937)
			(end -4.2291 -1.397)
			(stroke
				(width 0.1524)
				(type default)
			)
			(layer "F.SilkS")
		)
		(fp_line
			(start -4.2291 -0.8001)
			(end -3.429 0)
			(stroke
				(width 0.1524)
				(type default)
			)
			(layer "F.SilkS")
		)
		(fp_line
			(start -4.2291 -1.397)
			(end 3.81 -1.397)
			(stroke
				(width 0.1524)
				(type default)
			)
			(layer "F.SilkS")
		)
		(fp_poly
			(pts
				(xy -3.90652 -1.8542) (xy 3.90652 -1.8542) (xy 3.90652 1.8542) (xy -3.90652 1.8542)
			)
			(stroke
				(width 0)
				(type default)
			)
			(fill yes)
			(layer "F.SilkS")
		)
		(fp_poly
			(pts
				(xy -4.2164 3.81) (xy 4.2164 3.81) (xy 4.22656 -3.81) (xy -4.2164 -3.81)
			)
			(stroke
				(width 0)
				(type default)
			)
			(fill no)
			(layer "F.CrtYd")
		)
		(fp_poly
			(pts
				(xy -4.22656 -3.81) (xy 4.22656 -3.81) (xy 4.22656 3.81) (xy -4.22656 3.81)
			)
			(stroke
				(width 0)
				(type default)
			)
			(fill no)
			(layer "F.Fab")
		)
		(pad "1" smd rect
			(at -3.57632 2.8194 180)
			(size 0.3556 1.524)
			(layers "F.Cu" "F.Mask" "F.Paste")
			(net "IO_EXP1_INT_N")
		)
		(pad "2" smd rect
			(at -2.92608 2.8194 180)
			(size 0.3556 1.524)
			(layers "F.Cu" "F.Mask" "F.Paste")
			(net "IO_EXP1_A1")
		)
		(pad "3" smd rect
			(at -2.27584 2.8194 180)
			(size 0.3556 1.524)
			(layers "F.Cu" "F.Mask" "F.Paste")
			(net "IO_EXP1_A2")
		)
		(pad "4" smd rect
			(at -1.6256 2.8194 180)
			(size 0.3556 1.524)
			(layers "F.Cu" "F.Mask" "F.Paste")
			(net "DRIVE_B_0_PWR")
		)
		(pad "5" smd rect
			(at -0.97536 2.8194 180)
			(size 0.3556 1.524)
			(layers "F.Cu" "F.Mask" "F.Paste")
			(net "DRIVE_B_1_PWR")
		)
		(pad "6" smd rect
			(at -0.32512 2.8194 180)
			(size 0.3556 1.524)
			(layers "F.Cu" "F.Mask" "F.Paste")
			(net "DRIVE_B_2_PWR")
		)
		(pad "7" smd rect
			(at 0.32512 2.8194 180)
			(size 0.3556 1.524)
			(layers "F.Cu" "F.Mask" "F.Paste")
			(net "DRIVE_B_3_PWR")
		)
		(pad "8" smd rect
			(at 0.97536 2.8194 180)
			(size 0.3556 1.524)
			(layers "F.Cu" "F.Mask" "F.Paste")
			(net "DRIVE_B_4_PWR")
		)
		(pad "9" smd rect
			(at 1.6256 2.8194 180)
			(size 0.3556 1.524)
			(layers "F.Cu" "F.Mask" "F.Paste")
			(net "DRIVE_B_5_PWR")
		)
		(pad "10" smd rect
			(at 2.27584 2.8194 180)
			(size 0.3556 1.524)
			(layers "F.Cu" "F.Mask" "F.Paste")
			(net "DRIVE_B_6_PWR")
		)
		(pad "11" smd rect
			(at 2.92608 2.8194 180)
			(size 0.3556 1.524)
			(layers "F.Cu" "F.Mask" "F.Paste")
			(net "DRIVE_B_7_PWR")
		)
		(pad "12" smd rect
			(at 3.57632 2.8194 180)
			(size 0.3556 1.524)
			(layers "F.Cu" "F.Mask" "F.Paste")
			(net "GND")
		)
		(pad "13" smd rect
			(at 3.57632 -2.8194 180)
			(size 0.3556 1.524)
			(layers "F.Cu" "F.Mask" "F.Paste")
			(net "DRIVE_B_8_PWR")
		)
		(pad "14" smd rect
			(at 2.92608 -2.8194 180)
			(size 0.3556 1.524)
			(layers "F.Cu" "F.Mask" "F.Paste")
			(net "DRIVE_B_9_PWR")
		)
		(pad "15" smd rect
			(at 2.27584 -2.8194 180)
			(size 0.3556 1.524)
			(layers "F.Cu" "F.Mask" "F.Paste")
			(net "DRIVE_B_10_PWR")
		)
		(pad "16" smd rect
			(at 1.6256 -2.8194 180)
			(size 0.3556 1.524)
			(layers "F.Cu" "F.Mask" "F.Paste")
			(net "DRIVE_B_11_PWR")
		)
		(pad "17" smd rect
			(at 0.97536 -2.8194 180)
			(size 0.3556 1.524)
			(layers "F.Cu" "F.Mask" "F.Paste")
			(net "DRIVE_B_12_PWR")
		)
		(pad "18" smd rect
			(at 0.32512 -2.8194 180)
			(size 0.3556 1.524)
			(layers "F.Cu" "F.Mask" "F.Paste")
			(net "DRIVE_B_13_PWR")
		)
		(pad "19" smd rect
			(at -0.32512 -2.8194 180)
			(size 0.3556 1.524)
			(layers "F.Cu" "F.Mask" "F.Paste")
			(net "DRIVE_B_14_PWR")
		)
		(pad "20" smd rect
			(at -0.97536 -2.8194 180)
			(size 0.3556 1.524)
			(layers "F.Cu" "F.Mask" "F.Paste")
			(net "DRIVE_B_15_PWR")
		)
		(pad "21" smd rect
			(at -1.6256 -2.8194 180)
			(size 0.3556 1.524)
			(layers "F.Cu" "F.Mask" "F.Paste")
			(net "IO_EXP1_A0")
		)
		(pad "22" smd rect
			(at -2.27584 -2.8194 180)
			(size 0.3556 1.524)
			(layers "F.Cu" "F.Mask" "F.Paste")
			(net "IO_EXP1_SCL")
		)
		(pad "23" smd rect
			(at -2.92608 -2.8194 180)
			(size 0.3556 1.524)
			(layers "F.Cu" "F.Mask" "F.Paste")
			(net "IO_EXP1_SDA")
		)
		(pad "24" smd rect
			(at -3.57632 -2.8194 180)
			(size 0.3556 1.524)
			(layers "F.Cu" "F.Mask" "F.Paste")
			(net "GPIO_VCC_U8")
		)
	)
	(footprint ""
		(layer "F.Cu")
		(at 431.927 -18.796 90)
		(property "Reference" "D33"
			(at 0 0 90)
			(layer "F.SilkS")
			(hide yes)
			(effects
				(font
					(size 1.27 1.27)
				)
			)
		)
		(property "Value" "RB551V30-GP"
			(at 0 -6.7818 90)
			(unlocked yes)
			(layer "F.Fab")
			(hide yes)
			(effects
				(font
					(size 1.016 1.016)
					(thickness 0.1524)
				)
			)
		)
		(property "Device Type" "SOD323AKH38"
			(at 0 -8.6868 90)
			(unlocked yes)
			(layer "F.Fab")
			(hide yes)
			(effects
				(font
					(size 1.016 1.016)
					(thickness 0.1524)
				)
			)
		)
		(duplicate_pad_numbers_are_jumpers no)
		(fp_line
			(start 0.889 -1.9304)
			(end 0.889 2.159)
			(stroke
				(width 0.1524)
				(type default)
			)
			(layer "F.SilkS")
		)
		(fp_line
			(start -0.889 -1.9304)
			(end 0.889 -1.9304)
			(stroke
				(width 0.1524)
				(type default)
			)
			(layer "F.SilkS")
		)
		(fp_line
			(start 0.762 2.0574)
			(end -0.762 2.0574)
			(stroke
				(width 0.508)
				(type default)
			)
			(layer "F.SilkS")
		)
		(fp_line
			(start 0.889 2.159)
			(end -0.889 2.159)
			(stroke
				(width 0.1524)
				(type default)
			)
			(layer "F.SilkS")
		)
		(fp_line
			(start -0.889 2.159)
			(end -0.889 -1.9304)
			(stroke
				(width 0.1524)
				(type default)
			)
			(layer "F.SilkS")
		)
		(fp_rect
			(start -1.016 2.3114)
			(end 1.016 -2.0066)
			(stroke
				(width 0)
				(type default)
			)
			(fill no)
			(layer "F.CrtYd")
		)
		(fp_poly
			(pts
				(xy -1.016 -2.0066) (xy 1.016 -2.0066) (xy 1.016 2.3114) (xy -1.016 2.3114)
			)
			(stroke
				(width 0)
				(type default)
			)
			(fill no)
			(layer "F.Fab")
		)
		(pad "A" smd rect
			(at 0 -1.143 90)
			(size 0.5588 1.016)
			(layers "F.Cu" "F.Mask" "F.Paste")
			(net "SW_HDD_R33")
		)
		(pad "K" smd rect
			(at 0 1.143 90)
			(size 0.5588 1.016)
			(layers "F.Cu" "F.Mask" "F.Paste")
			(net "SW_HDD_N33")
		)
	)
	(footprint ""
		(layer "F.Cu")
		(at 221.996 -305.2826)
		(property "Reference" "Q268"
			(at 0 0 0)
			(layer "F.SilkS")
			(hide yes)
			(effects
				(font
					(size 1.27 1.27)
				)
			)
		)
		(property "Value" "2N7002K-2-GP"
			(at 0.127 -8.9662 0)
			(unlocked yes)
			(layer "F.Fab")
			(hide yes)
			(effects
				(font
					(size 1.016 1.016)
					(thickness 0.1524)
				)
			)
		)
		(property "Device Type" "SOT23DGS2D4H44"
			(at 0.127 -10.4902 0)
			(unlocked yes)
			(layer "F.Fab")
			(hide yes)
			(effects
				(font
					(size 1.016 1.016)
					(thickness 0.1524)
				)
			)
		)
		(duplicate_pad_numbers_are_jumpers no)
		(fp_line
			(start -1.651 -1.778)
			(end -1.651 1.778)
			(stroke
				(width 0.1524)
				(type default)
			)
			(layer "F.SilkS")
		)
		(fp_line
			(start -1.651 1.778)
			(end 1.651 1.778)
			(stroke
				(width 0.1524)
				(type default)
			)
			(layer "F.SilkS")
		)
		(fp_line
			(start 1.651 -1.778)
			(end -1.651 -1.778)
			(stroke
				(width 0.1524)
				(type default)
			)
			(layer "F.SilkS")
		)
		(fp_line
			(start 1.651 1.778)
			(end 1.651 -1.778)
			(stroke
				(width 0.1524)
				(type default)
			)
			(layer "F.SilkS")
		)
		(fp_poly
			(pts
				(xy -1.778 1.8796) (xy -1.778 -1.8796) (xy 1.778 -1.8796) (xy 1.778 1.8796)
			)
			(stroke
				(width 0)
				(type default)
			)
			(fill no)
			(layer "F.CrtYd")
		)
		(fp_poly
			(pts
				(xy -1.778 1.8796) (xy -1.778 -1.8796) (xy 1.778 -1.8796) (xy 1.778 1.8796)
			)
			(stroke
				(width 0)
				(type default)
			)
			(fill no)
			(layer "F.Fab")
		)
		(pad "D" smd custom
			(at 0 -0.9525)
			(size 0.1905 0.1905)
			(layers "F.Cu" "F.Mask" "F.Paste")
			(net "FANTACH_A_OE_N")
			(options
				(clearance outline)
				(anchor circle)
			)
			(primitives
				(gr_poly
					(pts
						(arc
							(start -0.1778 0.5715)
							(mid -0.321484 0.511984)
							(end -0.381 0.3683)
						)
						(arc
							(start -0.381 -0.3683)
							(mid -0.321484 -0.511984)
							(end -0.1778 -0.5715)
						)
						(arc
							(start 0.1778 -0.5715)
							(mid 0.321484 -0.511984)
							(end 0.381 -0.3683)
						)
						(arc
							(start 0.381 0.3683)
							(mid 0.321484 0.511984)
							(end 0.1778 0.5715)
						)
					)
					(width 0)
					(fill yes)
				)
			)
		)
		(pad "G" smd custom
			(at -0.98425 0.9525)
			(size 0.1905 0.1905)
			(layers "F.Cu" "F.Mask" "F.Paste")
			(net "FANTACH_A_OE")
			(options
				(clearance outline)
				(anchor circle)
			)
			(primitives
				(gr_poly
					(pts
						(arc
							(start -0.1778 0.5715)
							(mid -0.321484 0.511984)
							(end -0.381 0.3683)
						)
						(arc
							(start -0.381 -0.3683)
							(mid -0.321484 -0.511984)
							(end -0.1778 -0.5715)
						)
						(arc
							(start 0.1778 -0.5715)
							(mid 0.321484 -0.511984)
							(end 0.381 -0.3683)
						)
						(arc
							(start 0.381 0.3683)
							(mid 0.321484 0.511984)
							(end 0.1778 0.5715)
						)
					)
					(width 0)
					(fill yes)
				)
			)
		)
		(pad "S" smd custom
			(at 0.98425 0.9525)
			(size 0.1905 0.1905)
			(layers "F.Cu" "F.Mask" "F.Paste")
			(net "GND")
			(options
				(clearance outline)
				(anchor circle)
			)
			(primitives
				(gr_poly
					(pts
						(arc
							(start -0.1778 0.5715)
							(mid -0.321484 0.511984)
							(end -0.381 0.3683)
						)
						(arc
							(start -0.381 -0.3683)
							(mid -0.321484 -0.511984)
							(end -0.1778 -0.5715)
						)
						(arc
							(start 0.1778 -0.5715)
							(mid 0.321484 -0.511984)
							(end 0.381 -0.3683)
						)
						(arc
							(start 0.381 0.3683)
							(mid 0.321484 0.511984)
							(end 0.1778 0.5715)
						)
					)
					(width 0)
					(fill yes)
				)
			)
		)
	)
	(footprint ""
		(layer "F.Cu")
		(at 479.034602 -272.309844)
		(property "Reference" "C179"
			(at 0 0 0)
			(layer "F.SilkS")
			(hide yes)
			(effects
				(font
					(size 1.27 1.27)
				)
			)
		)
		(property "Value" "SC4D7U25V5KX-1-GP"
			(at -0.0762 -6.1214 0)
			(unlocked yes)
			(layer "F.Fab")
			(hide yes)
			(effects
				(font
					(size 1.016 1.016)
					(thickness 0.1524)
				)
			)
		)
		(property "Device Type" "C805H58"
			(at -0.0762 -8.1534 0)
			(unlocked yes)
			(layer "F.Fab")
			(hide yes)
			(effects
				(font
					(size 1.016 1.016)
					(thickness 0.1524)
				)
			)
		)
		(duplicate_pad_numbers_are_jumpers no)
		(fp_line
			(start 0.635 0)
			(end -0.635 0)
			(stroke
				(width 0.508)
				(type default)
			)
			(layer "F.SilkS")
		)
		(fp_rect
			(start -0.9652 1.778)
			(end 0.9652 -1.778)
			(stroke
				(width 0)
				(type default)
			)
			(fill no)
			(layer "F.CrtYd")
		)
		(fp_poly
			(pts
				(xy -0.9652 -1.778) (xy 0.9652 -1.778) (xy 0.9652 1.778) (xy -0.9652 1.778)
			)
			(stroke
				(width 0)
				(type default)
			)
			(fill no)
			(layer "F.Fab")
		)
		(pad "1" smd rect
			(at 0 -0.9652)
			(size 1.397 1.143)
			(layers "F.Cu" "F.Mask" "F.Paste")
			(net "P12V_HDD11")
		)
		(pad "2" smd rect
			(at 0 0.9652)
			(size 1.397 1.143)
			(layers "F.Cu" "F.Mask" "F.Paste")
			(net "GND")
		)
	)
	(footprint ""
		(layer "F.Cu")
		(at 133.7818 -367.8174 -90)
		(property "Reference" "C528"
			(at 0 0 270)
			(layer "F.SilkS")
			(hide yes)
			(effects
				(font
					(size 1.27 1.27)
				)
			)
		)
		(property "Value" "SCD1U25V2KX-2-GP"
			(at 1.1811 -2.7051 270)
			(unlocked yes)
			(layer "F.Fab")
			(hide yes)
			(effects
				(font
					(size 1.016 1.016)
					(thickness 0.1524)
				)
			)
		)
		(property "Device Type" "C402H22"
			(at 1.1811 -4.2291 270)
			(unlocked yes)
			(layer "F.Fab")
			(hide yes)
			(effects
				(font
					(size 1.016 1.016)
					(thickness 0.1524)
				)
			)
		)
		(duplicate_pad_numbers_are_jumpers no)
		(fp_rect
			(start -0.4318 0.9525)
			(end 0.4318 -0.9525)
			(stroke
				(width 0)
				(type default)
			)
			(fill no)
			(layer "F.CrtYd")
		)
		(fp_rect
			(start -0.4318 0.9525)
			(end 0.4318 -0.9525)
			(stroke
				(width 0)
				(type default)
			)
			(fill no)
			(layer "F.Fab")
		)
		(pad "1" smd custom
			(at 0 -0.4445 270)
			(size 0.1524 0.1524)
			(layers "F.Cu" "F.Mask" "F.Paste")
			(net "FAN_1_TACH1")
			(options
				(clearance outline)
				(anchor circle)
			)
			(primitives
				(gr_poly
					(pts
						(arc
							(start 0.3048 -0.2032)
							(mid 0.275042 -0.275042)
							(end 0.2032 -0.3048)
						)
						(arc
							(start -0.2032 -0.3048)
							(mid -0.275042 -0.275042)
							(end -0.3048 -0.2032)
						)
						(arc
							(start -0.3048 0.2032)
							(mid -0.275042 0.275042)
							(end -0.2032 0.3048)
						)
						(arc
							(start 0.2032 0.3048)
							(mid 0.275042 0.275042)
							(end 0.3048 0.2032)
						)
					)
					(width 0)
					(fill yes)
				)
			)
		)
		(pad "2" smd custom
			(at 0 0.4445 270)
			(size 0.1524 0.1524)
			(layers "F.Cu" "F.Mask" "F.Paste")
			(net "GND")
			(options
				(clearance outline)
				(anchor circle)
			)
			(primitives
				(gr_poly
					(pts
						(arc
							(start 0.3048 -0.2032)
							(mid 0.275042 -0.275042)
							(end 0.2032 -0.3048)
						)
						(arc
							(start -0.2032 -0.3048)
							(mid -0.275042 -0.275042)
							(end -0.3048 -0.2032)
						)
						(arc
							(start -0.3048 0.2032)
							(mid -0.275042 0.275042)
							(end -0.2032 0.3048)
						)
						(arc
							(start 0.2032 0.3048)
							(mid 0.275042 0.275042)
							(end 0.3048 0.2032)
						)
					)
					(width 0)
					(fill yes)
				)
			)
		)
	)
	(footprint ""
		(layer "F.Cu")
		(at 409.800044 -180.399944)
		(property "Reference" "LED10"
			(at 0 0 0)
			(layer "F.SilkS")
			(hide yes)
			(effects
				(font
					(size 1.27 1.27)
				)
			)
		)
		(property "Value" "LED-BY-19-GP"
			(at -2.132076 1.414018 0)
			(unlocked yes)
			(layer "F.Fab")
			(hide yes)
			(effects
				(font
					(size 1.016 1.016)
					(thickness 0.1524)
				)
			)
		)
		(property "Device Type" "LED-1615-4PH26"
			(at -2.132076 -0.109982 0)
			(unlocked yes)
			(layer "F.Fab")
			(hide yes)
			(effects
				(font
					(size 1.016 1.016)
					(thickness 0.1524)
				)
			)
		)
		(duplicate_pad_numbers_are_jumpers no)
		(fp_line
			(start -1.2954 0.254)
			(end -1.2954 1.6002)
			(stroke
				(width 0.508)
				(type default)
			)
			(layer "F.SilkS")
		)
		(fp_line
			(start -1.2954 1.6002)
			(end 1.2954 1.6002)
			(stroke
				(width 0.508)
				(type default)
			)
			(layer "F.SilkS")
		)
		(fp_line
			(start -1.1176 -1.4224)
			(end 1.1176 -1.4224)
			(stroke
				(width 0.1524)
				(type default)
			)
			(layer "F.SilkS")
		)
		(fp_line
			(start -1.1176 1.4224)
			(end -1.1176 -1.4224)
			(stroke
				(width 0.1524)
				(type default)
			)
			(layer "F.SilkS")
		)
		(fp_line
			(start 1.1176 -1.4224)
			(end 1.1176 1.4224)
			(stroke
				(width 0.1524)
				(type default)
			)
			(layer "F.SilkS")
		)
		(fp_line
			(start 1.1176 1.4224)
			(end -1.1176 1.4224)
			(stroke
				(width 0.1524)
				(type default)
			)
			(layer "F.SilkS")
		)
		(fp_line
			(start 1.2954 1.6002)
			(end 1.2954 0.254)
			(stroke
				(width 0.508)
				(type default)
			)
			(layer "F.SilkS")
		)
		(fp_rect
			(start -0.7493 0.8001)
			(end 0.7493 -0.8001)
			(stroke
				(width 0)
				(type default)
			)
			(fill no)
			(layer "F.CrtYd")
		)
		(fp_poly
			(pts
				(xy -1.3716 1.6764) (xy -1.3716 -1.6764) (xy 1.3716 -1.6764) (xy 1.3716 0.0635) (xy 0.7493 0.0635)
				(xy 0.7493 -0.8001) (xy -0.7493 -0.8001) (xy -0.7493 0.8001) (xy 0.7493 0.8001) (xy 0.7493 0.0762)
				(xy 1.3716 0.0762) (xy 1.3716 1.6764)
			)
			(stroke
				(width 0)
				(type default)
			)
			(fill no)
			(layer "F.CrtYd")
		)
		(fp_rect
			(start -1.3716 1.6764)
			(end 1.3716 -1.6764)
			(stroke
				(width 0)
				(type default)
			)
			(fill no)
			(layer "F.Fab")
		)
		(pad "1" smd rect
			(at 0.50038 -0.73025)
			(size 0.7112 0.8636)
			(layers "F.Cu" "F.Mask" "F.Paste")
			(net "DRV_ACT_9")
		)
		(pad "2" smd rect
			(at -0.50038 -0.73025)
			(size 0.7112 0.8636)
			(layers "F.Cu" "F.Mask" "F.Paste")
			(net "FLT_HDD9")
		)
		(pad "3" smd rect
			(at 0.50038 0.73025)
			(size 0.7112 0.8636)
			(layers "F.Cu" "F.Mask" "F.Paste")
			(net "DRV_ACT_9_N")
		)
		(pad "4" smd rect
			(at -0.50038 0.73025)
			(size 0.7112 0.8636)
			(layers "F.Cu" "F.Mask" "F.Paste")
			(net "FLT_HDD9_N")
		)
	)
	(footprint ""
		(layer "F.Cu")
		(at 261.5184 -217.2462)
		(property "Reference" "R126"
			(at 0 0 0)
			(layer "F.SilkS")
			(hide yes)
			(effects
				(font
					(size 1.27 1.27)
				)
			)
		)
		(property "Value" "4K7R2F-GP"
			(at 0.064008 -3.993896 0)
			(unlocked yes)
			(layer "F.Fab")
			(hide yes)
			(effects
				(font
					(size 1.016 1.016)
					(thickness 0.1524)
				)
			)
		)
		(property "Device Type" "R402H16"
			(at 0.064008 -5.517896 0)
			(unlocked yes)
			(layer "F.Fab")
			(hide yes)
			(effects
				(font
					(size 1.016 1.016)
					(thickness 0.1524)
				)
			)
		)
		(duplicate_pad_numbers_are_jumpers no)
		(fp_line
			(start -0.508 -0.9398)
			(end -0.508 0.9398)
			(stroke
				(width 0.1524)
				(type default)
			)
			(layer "F.SilkS")
		)
		(fp_line
			(start 0.508 -0.9398)
			(end -0.508 -0.9398)
			(stroke
				(width 0.1524)
				(type default)
			)
			(layer "F.SilkS")
		)
		(fp_rect
			(start -0.508 0.9398)
			(end 0.508 -0.9398)
			(stroke
				(width 0)
				(type default)
			)
			(fill no)
			(layer "F.CrtYd")
		)
		(fp_rect
			(start -0.508 0.9398)
			(end 0.508 -0.9398)
			(stroke
				(width 0)
				(type default)
			)
			(fill no)
			(layer "F.Fab")
		)
		(pad "1" smd custom
			(at 0 -0.4445)
			(size 0.1397 0.1397)
			(layers "F.Cu" "F.Mask" "F.Paste")
			(net "VOL_SEN_ADDR0")
			(options
				(clearance outline)
				(anchor circle)
			)
			(primitives
				(gr_poly
					(pts
						(arc
							(start -0.1778 -0.2794)
							(mid -0.249642 -0.249642)
							(end -0.2794 -0.1778)
						)
						(arc
							(start -0.2794 0.1778)
							(mid -0.249642 0.249642)
							(end -0.1778 0.2794)
						)
						(arc
							(start 0.1778 0.2794)
							(mid 0.249642 0.249642)
							(end 0.2794 0.1778)
						)
						(arc
							(start 0.2794 -0.1778)
							(mid 0.249642 -0.249642)
							(end 0.1778 -0.2794)
						)
					)
					(width 0)
					(fill yes)
				)
			)
		)
		(pad "2" smd custom
			(at 0 0.4445)
			(size 0.1397 0.1397)
			(layers "F.Cu" "F.Mask" "F.Paste")
			(net "GND")
			(options
				(clearance outline)
				(anchor circle)
			)
			(primitives
				(gr_poly
					(pts
						(arc
							(start -0.1778 -0.2794)
							(mid -0.249642 -0.249642)
							(end -0.2794 -0.1778)
						)
						(arc
							(start -0.2794 0.1778)
							(mid -0.249642 0.249642)
							(end -0.1778 0.2794)
						)
						(arc
							(start 0.1778 0.2794)
							(mid 0.249642 0.249642)
							(end 0.2794 0.1778)
						)
						(arc
							(start 0.2794 -0.1778)
							(mid 0.249642 -0.249642)
							(end 0.1778 -0.2794)
						)
					)
					(width 0)
					(fill yes)
				)
			)
		)
	)
	(footprint ""
		(layer "F.Cu")
		(at 20.193 -33.782 -90)
		(property "Reference" "C342"
			(at 0 0 270)
			(layer "F.SilkS")
			(hide yes)
			(effects
				(font
					(size 1.27 1.27)
				)
			)
		)
		(property "Value" "SC1U16V3KX-5GP"
			(at 0 -2.8194 270)
			(unlocked yes)
			(layer "F.Fab")
			(hide yes)
			(effects
				(font
					(size 1.016 1.016)
					(thickness 0.1524)
				)
			)
		)
		(property "Device Type" "C603H36"
			(at 0 -4.3434 270)
			(unlocked yes)
			(layer "F.Fab")
			(hide yes)
			(effects
				(font
					(size 1.016 1.016)
					(thickness 0.1524)
				)
			)
		)
		(duplicate_pad_numbers_are_jumpers no)
		(fp_line
			(start 0.508 0)
			(end -0.508 0)
			(stroke
				(width 0.2032)
				(type default)
			)
			(layer "F.SilkS")
		)
		(fp_rect
			(start -0.5842 1.3335)
			(end 0.5842 -1.3335)
			(stroke
				(width 0)
				(type default)
			)
			(fill no)
			(layer "F.CrtYd")
		)
		(fp_rect
			(start -0.5842 1.3335)
			(end 0.5842 -1.3335)
			(stroke
				(width 0)
				(type default)
			)
			(fill no)
			(layer "F.Fab")
		)
		(pad "1" smd custom
			(at 0 -0.762 270)
			(size 0.2159 0.2159)
			(layers "F.Cu" "F.Mask" "F.Paste")
			(net "P5V_HDD24")
			(options
				(clearance outline)
				(anchor circle)
			)
			(primitives
				(gr_poly
					(pts
						(arc
							(start -0.3302 -0.4318)
							(mid -0.402042 -0.402042)
							(end -0.4318 -0.3302)
						)
						(arc
							(start -0.4318 0.3302)
							(mid -0.402042 0.402042)
							(end -0.3302 0.4318)
						)
						(arc
							(start 0.3302 0.4318)
							(mid 0.402042 0.402042)
							(end 0.4318 0.3302)
						)
						(arc
							(start 0.4318 -0.3302)
							(mid 0.402042 -0.402042)
							(end 0.3302 -0.4318)
						)
					)
					(width 0)
					(fill yes)
				)
			)
		)
		(pad "2" smd custom
			(at 0 0.762 270)
			(size 0.2159 0.2159)
			(layers "F.Cu" "F.Mask" "F.Paste")
			(net "GND")
			(options
				(clearance outline)
				(anchor circle)
			)
			(primitives
				(gr_poly
					(pts
						(arc
							(start -0.3302 -0.4318)
							(mid -0.402042 -0.402042)
							(end -0.4318 -0.3302)
						)
						(arc
							(start -0.4318 0.3302)
							(mid -0.402042 0.402042)
							(end -0.3302 0.4318)
						)
						(arc
							(start 0.3302 0.4318)
							(mid 0.402042 0.402042)
							(end 0.4318 0.3302)
						)
						(arc
							(start 0.4318 -0.3302)
							(mid 0.402042 -0.402042)
							(end 0.3302 -0.4318)
						)
					)
					(width 0)
					(fill yes)
				)
			)
		)
	)
	(footprint ""
		(layer "F.Cu")
		(at 206.756 -338.582 90)
		(property "Reference" "R1016"
			(at 0 0 90)
			(layer "F.SilkS")
			(hide yes)
			(effects
				(font
					(size 1.27 1.27)
				)
			)
		)
		(property "Value" "10R5F-1-GP"
			(at 0 -8.9535 90)
			(unlocked yes)
			(layer "F.Fab")
			(hide yes)
			(effects
				(font
					(size 1.27 1.016)
					(thickness 0.1524)
				)
			)
		)
		(property "Device Type" "R805H24"
			(at 0 -10.6299 90)
			(unlocked yes)
			(layer "F.Fab")
			(hide yes)
			(effects
				(font
					(size 1.27 1.016)
					(thickness 0.1524)
				)
			)
		)
		(duplicate_pad_numbers_are_jumpers no)
		(fp_line
			(start 0.889 -1.7018)
			(end -0.889 -1.7018)
			(stroke
				(width 0.1524)
				(type default)
			)
			(layer "F.SilkS")
		)
		(fp_line
			(start 0.889 -1.7018)
			(end 0.889 -0.381)
			(stroke
				(width 0.1524)
				(type default)
			)
			(layer "F.SilkS")
		)
		(fp_line
			(start -0.889 -1.7018)
			(end -0.889 0.2794)
			(stroke
				(width 0.1524)
				(type default)
			)
			(layer "F.SilkS")
		)
		(fp_line
			(start -0.889 0.0762)
			(end -0.889 1.7018)
			(stroke
				(width 0.1524)
				(type default)
			)
			(layer "F.SilkS")
		)
		(fp_line
			(start 0.889 1.7018)
			(end 0.889 -0.508)
			(stroke
				(width 0.1524)
				(type default)
			)
			(layer "F.SilkS")
		)
		(fp_line
			(start -0.889 1.7018)
			(end 0.889 1.7018)
			(stroke
				(width 0.1524)
				(type default)
			)
			(layer "F.SilkS")
		)
		(fp_poly
			(pts
				(xy 0.9652 -1.778) (xy 0.9652 1.778) (xy -0.9652 1.778) (xy -0.9652 -1.778)
			)
			(stroke
				(width 0)
				(type default)
			)
			(fill no)
			(layer "F.CrtYd")
		)
		(fp_rect
			(start -0.9652 1.778)
			(end 0.9652 -1.778)
			(stroke
				(width 0)
				(type default)
			)
			(fill no)
			(layer "F.Fab")
		)
		(pad "1" smd rect
			(at 0 -0.9652 90)
			(size 1.397 1.143)
			(layers "F.Cu" "F.Mask" "F.Paste")
			(net "MB0_12V_CTRL_GATE2")
		)
		(pad "2" smd rect
			(at 0 0.9652 90)
			(size 1.397 1.143)
			(layers "F.Cu" "F.Mask" "F.Paste")
			(net "MB0_CM_GATE_R")
		)
	)
	(footprint ""
		(layer "F.Cu")
		(at 244.37848 -195.58254 90)
		(property "Reference" "R72"
			(at 0 0 90)
			(layer "F.SilkS")
			(hide yes)
			(effects
				(font
					(size 1.27 1.27)
				)
			)
		)
		(property "Value" "4K7R2F-GP"
			(at 0.064008 -3.993896 90)
			(unlocked yes)
			(layer "F.Fab")
			(hide yes)
			(effects
				(font
					(size 1.016 1.016)
					(thickness 0.1524)
				)
			)
		)
		(property "Device Type" "R402H16"
			(at 0.064008 -5.517896 90)
			(unlocked yes)
			(layer "F.Fab")
			(hide yes)
			(effects
				(font
					(size 1.016 1.016)
					(thickness 0.1524)
				)
			)
		)
		(duplicate_pad_numbers_are_jumpers no)
		(fp_line
			(start 0.508 -0.9398)
			(end -0.508 -0.9398)
			(stroke
				(width 0.1524)
				(type default)
			)
			(layer "F.SilkS")
		)
		(fp_line
			(start -0.508 -0.9398)
			(end -0.508 0.9398)
			(stroke
				(width 0.1524)
				(type default)
			)
			(layer "F.SilkS")
		)
		(fp_rect
			(start -0.508 0.9398)
			(end 0.508 -0.9398)
			(stroke
				(width 0)
				(type default)
			)
			(fill no)
			(layer "F.CrtYd")
		)
		(fp_rect
			(start -0.508 0.9398)
			(end 0.508 -0.9398)
			(stroke
				(width 0)
				(type default)
			)
			(fill no)
			(layer "F.Fab")
		)
		(pad "1" smd custom
			(at 0 -0.4445 90)
			(size 0.1397 0.1397)
			(layers "F.Cu" "F.Mask" "F.Paste")
			(net "IO_EXP2_A1")
			(options
				(clearance outline)
				(anchor circle)
			)
			(primitives
				(gr_poly
					(pts
						(arc
							(start -0.1778 -0.2794)
							(mid -0.249642 -0.249642)
							(end -0.2794 -0.1778)
						)
						(arc
							(start -0.2794 0.1778)
							(mid -0.249642 0.249642)
							(end -0.1778 0.2794)
						)
						(arc
							(start 0.1778 0.2794)
							(mid 0.249642 0.249642)
							(end 0.2794 0.1778)
						)
						(arc
							(start 0.2794 -0.1778)
							(mid 0.249642 -0.249642)
							(end 0.1778 -0.2794)
						)
					)
					(width 0)
					(fill yes)
				)
			)
		)
		(pad "2" smd custom
			(at 0 0.4445 90)
			(size 0.1397 0.1397)
			(layers "F.Cu" "F.Mask" "F.Paste")
			(net "GND")
			(options
				(clearance outline)
				(anchor circle)
			)
			(primitives
				(gr_poly
					(pts
						(arc
							(start -0.1778 -0.2794)
							(mid -0.249642 -0.249642)
							(end -0.2794 -0.1778)
						)
						(arc
							(start -0.2794 0.1778)
							(mid -0.249642 0.249642)
							(end -0.1778 0.2794)
						)
						(arc
							(start 0.1778 0.2794)
							(mid 0.249642 0.249642)
							(end 0.2794 0.1778)
						)
						(arc
							(start 0.2794 -0.1778)
							(mid 0.249642 -0.249642)
							(end 0.1778 -0.2794)
						)
					)
					(width 0)
					(fill yes)
				)
			)
		)
	)
	(footprint ""
		(layer "F.Cu")
		(at 221.996 -221.996 90)
		(property "Reference" "R23"
			(at 0 0 90)
			(layer "F.SilkS")
			(hide yes)
			(effects
				(font
					(size 1.27 1.27)
				)
			)
		)
		(property "Value" "4K7R2F-GP"
			(at 0.064008 -3.993896 90)
			(unlocked yes)
			(layer "F.Fab")
			(hide yes)
			(effects
				(font
					(size 1.016 1.016)
					(thickness 0.1524)
				)
			)
		)
		(property "Device Type" "R402H16"
			(at 0.064008 -5.517896 90)
			(unlocked yes)
			(layer "F.Fab")
			(hide yes)
			(effects
				(font
					(size 1.016 1.016)
					(thickness 0.1524)
				)
			)
		)
		(duplicate_pad_numbers_are_jumpers no)
		(fp_line
			(start 0.508 -0.9398)
			(end -0.508 -0.9398)
			(stroke
				(width 0.1524)
				(type default)
			)
			(layer "F.SilkS")
		)
		(fp_line
			(start -0.508 -0.9398)
			(end -0.508 0.9398)
			(stroke
				(width 0.1524)
				(type default)
			)
			(layer "F.SilkS")
		)
		(fp_rect
			(start -0.508 0.9398)
			(end 0.508 -0.9398)
			(stroke
				(width 0)
				(type default)
			)
			(fill no)
			(layer "F.CrtYd")
		)
		(fp_rect
			(start -0.508 0.9398)
			(end 0.508 -0.9398)
			(stroke
				(width 0)
				(type default)
			)
			(fill no)
			(layer "F.Fab")
		)
		(pad "1" smd custom
			(at 0 -0.4445 90)
			(size 0.1397 0.1397)
			(layers "F.Cu" "F.Mask" "F.Paste")
			(net "IO_EXP1_HDD_FAULT_A0")
			(options
				(clearance outline)
				(anchor circle)
			)
			(primitives
				(gr_poly
					(pts
						(arc
							(start -0.1778 -0.2794)
							(mid -0.249642 -0.249642)
							(end -0.2794 -0.1778)
						)
						(arc
							(start -0.2794 0.1778)
							(mid -0.249642 0.249642)
							(end -0.1778 0.2794)
						)
						(arc
							(start 0.1778 0.2794)
							(mid 0.249642 0.249642)
							(end 0.2794 0.1778)
						)
						(arc
							(start 0.2794 -0.1778)
							(mid 0.249642 -0.249642)
							(end 0.1778 -0.2794)
						)
					)
					(width 0)
					(fill yes)
				)
			)
		)
		(pad "2" smd custom
			(at 0 0.4445 90)
			(size 0.1397 0.1397)
			(layers "F.Cu" "F.Mask" "F.Paste")
			(net "GND")
			(options
				(clearance outline)
				(anchor circle)
			)
			(primitives
				(gr_poly
					(pts
						(arc
							(start -0.1778 -0.2794)
							(mid -0.249642 -0.249642)
							(end -0.2794 -0.1778)
						)
						(arc
							(start -0.2794 0.1778)
							(mid -0.249642 0.249642)
							(end -0.1778 0.2794)
						)
						(arc
							(start 0.1778 0.2794)
							(mid 0.249642 0.249642)
							(end 0.2794 0.1778)
						)
						(arc
							(start 0.2794 -0.1778)
							(mid 0.249642 -0.249642)
							(end 0.1778 -0.2794)
						)
					)
					(width 0)
					(fill yes)
				)
			)
		)
	)
	(footprint ""
		(layer "F.Cu")
		(at 363.1184 -134.5946 90)
		(property "Reference" "R514"
			(at 0 0 90)
			(layer "F.SilkS")
			(hide yes)
			(effects
				(font
					(size 1.27 1.27)
				)
			)
		)
		(property "Value" "4K7R2J-2-GP"
			(at 0.064008 -3.993896 90)
			(unlocked yes)
			(layer "F.Fab")
			(hide yes)
			(effects
				(font
					(size 1.016 1.016)
					(thickness 0.1524)
				)
			)
		)
		(property "Device Type" "R402H16"
			(at 0.064008 -5.517896 90)
			(unlocked yes)
			(layer "F.Fab")
			(hide yes)
			(effects
				(font
					(size 1.016 1.016)
					(thickness 0.1524)
				)
			)
		)
		(duplicate_pad_numbers_are_jumpers no)
		(fp_line
			(start 0.508 -0.9398)
			(end -0.508 -0.9398)
			(stroke
				(width 0.1524)
				(type default)
			)
			(layer "F.SilkS")
		)
		(fp_line
			(start -0.508 -0.9398)
			(end -0.508 0.9398)
			(stroke
				(width 0.1524)
				(type default)
			)
			(layer "F.SilkS")
		)
		(fp_rect
			(start -0.508 0.9398)
			(end 0.508 -0.9398)
			(stroke
				(width 0)
				(type default)
			)
			(fill no)
			(layer "F.CrtYd")
		)
		(fp_rect
			(start -0.508 0.9398)
			(end 0.508 -0.9398)
			(stroke
				(width 0)
				(type default)
			)
			(fill no)
			(layer "F.Fab")
		)
		(pad "1" smd custom
			(at 0 -0.4445 90)
			(size 0.1397 0.1397)
			(layers "F.Cu" "F.Mask" "F.Paste")
			(net "P12V_B")
			(options
				(clearance outline)
				(anchor circle)
			)
			(primitives
				(gr_poly
					(pts
						(arc
							(start -0.1778 -0.2794)
							(mid -0.249642 -0.249642)
							(end -0.2794 -0.1778)
						)
						(arc
							(start -0.2794 0.1778)
							(mid -0.249642 0.249642)
							(end -0.1778 0.2794)
						)
						(arc
							(start 0.1778 0.2794)
							(mid 0.249642 0.249642)
							(end 0.2794 0.1778)
						)
						(arc
							(start 0.2794 -0.1778)
							(mid 0.249642 -0.249642)
							(end 0.1778 -0.2794)
						)
					)
					(width 0)
					(fill yes)
				)
			)
		)
		(pad "2" smd custom
			(at 0 0.4445 90)
			(size 0.1397 0.1397)
			(layers "F.Cu" "F.Mask" "F.Paste")
			(net "SW_HDD_P19")
			(options
				(clearance outline)
				(anchor circle)
			)
			(primitives
				(gr_poly
					(pts
						(arc
							(start -0.1778 -0.2794)
							(mid -0.249642 -0.249642)
							(end -0.2794 -0.1778)
						)
						(arc
							(start -0.2794 0.1778)
							(mid -0.249642 0.249642)
							(end -0.1778 0.2794)
						)
						(arc
							(start 0.1778 0.2794)
							(mid 0.249642 0.249642)
							(end 0.2794 0.1778)
						)
						(arc
							(start 0.2794 -0.1778)
							(mid 0.249642 -0.249642)
							(end 0.1778 -0.2794)
						)
					)
					(width 0)
					(fill yes)
				)
			)
		)
	)
	(footprint ""
		(layer "F.Cu")
		(at 364.236 -19.558 -90)
		(property "Reference" "R790"
			(at 0 0 270)
			(layer "F.SilkS")
			(hide yes)
			(effects
				(font
					(size 1.27 1.27)
				)
			)
		)
		(property "Value" "4K7R2J-2-GP"
			(at 0.064008 -3.993896 270)
			(unlocked yes)
			(layer "F.Fab")
			(hide yes)
			(effects
				(font
					(size 1.016 1.016)
					(thickness 0.1524)
				)
			)
		)
		(property "Device Type" "R402H16"
			(at 0.064008 -5.517896 270)
			(unlocked yes)
			(layer "F.Fab")
			(hide yes)
			(effects
				(font
					(size 1.016 1.016)
					(thickness 0.1524)
				)
			)
		)
		(duplicate_pad_numbers_are_jumpers no)
		(fp_line
			(start -0.508 -0.9398)
			(end -0.508 0.9398)
			(stroke
				(width 0.1524)
				(type default)
			)
			(layer "F.SilkS")
		)
		(fp_line
			(start 0.508 -0.9398)
			(end -0.508 -0.9398)
			(stroke
				(width 0.1524)
				(type default)
			)
			(layer "F.SilkS")
		)
		(fp_rect
			(start -0.508 0.9398)
			(end 0.508 -0.9398)
			(stroke
				(width 0)
				(type default)
			)
			(fill no)
			(layer "F.CrtYd")
		)
		(fp_rect
			(start -0.508 0.9398)
			(end 0.508 -0.9398)
			(stroke
				(width 0)
				(type default)
			)
			(fill no)
			(layer "F.Fab")
		)
		(pad "1" smd custom
			(at 0 -0.4445 270)
			(size 0.1397 0.1397)
			(layers "F.Cu" "F.Mask" "F.Paste")
			(net "P12V_B")
			(options
				(clearance outline)
				(anchor circle)
			)
			(primitives
				(gr_poly
					(pts
						(arc
							(start -0.1778 -0.2794)
							(mid -0.249642 -0.249642)
							(end -0.2794 -0.1778)
						)
						(arc
							(start -0.2794 0.1778)
							(mid -0.249642 0.249642)
							(end -0.1778 0.2794)
						)
						(arc
							(start 0.1778 0.2794)
							(mid 0.249642 0.249642)
							(end 0.2794 0.1778)
						)
						(arc
							(start 0.2794 -0.1778)
							(mid 0.249642 -0.249642)
							(end 0.1778 -0.2794)
						)
					)
					(width 0)
					(fill yes)
				)
			)
		)
		(pad "2" smd custom
			(at 0 0.4445 270)
			(size 0.1397 0.1397)
			(layers "F.Cu" "F.Mask" "F.Paste")
			(net "SW_HDD_P31")
			(options
				(clearance outline)
				(anchor circle)
			)
			(primitives
				(gr_poly
					(pts
						(arc
							(start -0.1778 -0.2794)
							(mid -0.249642 -0.249642)
							(end -0.2794 -0.1778)
						)
						(arc
							(start -0.2794 0.1778)
							(mid -0.249642 0.249642)
							(end -0.1778 0.2794)
						)
						(arc
							(start 0.1778 0.2794)
							(mid 0.249642 0.249642)
							(end 0.2794 0.1778)
						)
						(arc
							(start 0.2794 -0.1778)
							(mid 0.249642 -0.249642)
							(end 0.1778 -0.2794)
						)
					)
					(width 0)
					(fill yes)
				)
			)
		)
	)
	(footprint ""
		(layer "F.Cu")
		(at 475.361 -148.717 -90)
		(property "Reference" "C329"
			(at 0 0 270)
			(layer "F.SilkS")
			(hide yes)
			(effects
				(font
					(size 1.27 1.27)
				)
			)
		)
		(property "Value" "SC1U16V3KX-5GP"
			(at 0 -2.8194 270)
			(unlocked yes)
			(layer "F.Fab")
			(hide yes)
			(effects
				(font
					(size 1.016 1.016)
					(thickness 0.1524)
				)
			)
		)
		(property "Device Type" "C603H36"
			(at 0 -4.3434 270)
			(unlocked yes)
			(layer "F.Fab")
			(hide yes)
			(effects
				(font
					(size 1.016 1.016)
					(thickness 0.1524)
				)
			)
		)
		(duplicate_pad_numbers_are_jumpers no)
		(fp_line
			(start 0.508 0)
			(end -0.508 0)
			(stroke
				(width 0.2032)
				(type default)
			)
			(layer "F.SilkS")
		)
		(fp_rect
			(start -0.5842 1.3335)
			(end 0.5842 -1.3335)
			(stroke
				(width 0)
				(type default)
			)
			(fill no)
			(layer "F.CrtYd")
		)
		(fp_rect
			(start -0.5842 1.3335)
			(end 0.5842 -1.3335)
			(stroke
				(width 0)
				(type default)
			)
			(fill no)
			(layer "F.Fab")
		)
		(pad "1" smd custom
			(at 0 -0.762 270)
			(size 0.2159 0.2159)
			(layers "F.Cu" "F.Mask" "F.Paste")
			(net "P5V_HDD23")
			(options
				(clearance outline)
				(anchor circle)
			)
			(primitives
				(gr_poly
					(pts
						(arc
							(start -0.3302 -0.4318)
							(mid -0.402042 -0.402042)
							(end -0.4318 -0.3302)
						)
						(arc
							(start -0.4318 0.3302)
							(mid -0.402042 0.402042)
							(end -0.3302 0.4318)
						)
						(arc
							(start 0.3302 0.4318)
							(mid 0.402042 0.402042)
							(end 0.4318 0.3302)
						)
						(arc
							(start 0.4318 -0.3302)
							(mid 0.402042 -0.402042)
							(end 0.3302 -0.4318)
						)
					)
					(width 0)
					(fill yes)
				)
			)
		)
		(pad "2" smd custom
			(at 0 0.762 270)
			(size 0.2159 0.2159)
			(layers "F.Cu" "F.Mask" "F.Paste")
			(net "GND")
			(options
				(clearance outline)
				(anchor circle)
			)
			(primitives
				(gr_poly
					(pts
						(arc
							(start -0.3302 -0.4318)
							(mid -0.402042 -0.402042)
							(end -0.4318 -0.3302)
						)
						(arc
							(start -0.4318 0.3302)
							(mid -0.402042 0.402042)
							(end -0.3302 0.4318)
						)
						(arc
							(start 0.3302 0.4318)
							(mid 0.402042 0.402042)
							(end 0.4318 0.3302)
						)
						(arc
							(start 0.4318 -0.3302)
							(mid 0.402042 -0.402042)
							(end 0.3302 -0.4318)
						)
					)
					(width 0)
					(fill yes)
				)
			)
		)
	)
	(footprint ""
		(layer "F.Cu")
		(at 207.89138 -235.18622)
		(property "Reference" "R41"
			(at 0 0 0)
			(layer "F.SilkS")
			(hide yes)
			(effects
				(font
					(size 1.27 1.27)
				)
			)
		)
		(property "Value" "4K7R2F-GP"
			(at 0.064008 -3.993896 0)
			(unlocked yes)
			(layer "F.Fab")
			(hide yes)
			(effects
				(font
					(size 1.016 1.016)
					(thickness 0.1524)
				)
			)
		)
		(property "Device Type" "R402H16"
			(at 0.064008 -5.517896 0)
			(unlocked yes)
			(layer "F.Fab")
			(hide yes)
			(effects
				(font
					(size 1.016 1.016)
					(thickness 0.1524)
				)
			)
		)
		(duplicate_pad_numbers_are_jumpers no)
		(fp_line
			(start -0.508 -0.9398)
			(end -0.508 0.9398)
			(stroke
				(width 0.1524)
				(type default)
			)
			(layer "F.SilkS")
		)
		(fp_line
			(start 0.508 -0.9398)
			(end -0.508 -0.9398)
			(stroke
				(width 0.1524)
				(type default)
			)
			(layer "F.SilkS")
		)
		(fp_rect
			(start -0.508 0.9398)
			(end 0.508 -0.9398)
			(stroke
				(width 0)
				(type default)
			)
			(fill no)
			(layer "F.CrtYd")
		)
		(fp_rect
			(start -0.508 0.9398)
			(end 0.508 -0.9398)
			(stroke
				(width 0)
				(type default)
			)
			(fill no)
			(layer "F.Fab")
		)
		(pad "1" smd custom
			(at 0 -0.4445)
			(size 0.1397 0.1397)
			(layers "F.Cu" "F.Mask" "F.Paste")
			(net "IO_EXP4_A0")
			(options
				(clearance outline)
				(anchor circle)
			)
			(primitives
				(gr_poly
					(pts
						(arc
							(start -0.1778 -0.2794)
							(mid -0.249642 -0.249642)
							(end -0.2794 -0.1778)
						)
						(arc
							(start -0.2794 0.1778)
							(mid -0.249642 0.249642)
							(end -0.1778 0.2794)
						)
						(arc
							(start 0.1778 0.2794)
							(mid 0.249642 0.249642)
							(end 0.2794 0.1778)
						)
						(arc
							(start 0.2794 -0.1778)
							(mid 0.249642 -0.249642)
							(end 0.1778 -0.2794)
						)
					)
					(width 0)
					(fill yes)
				)
			)
		)
		(pad "2" smd custom
			(at 0 0.4445)
			(size 0.1397 0.1397)
			(layers "F.Cu" "F.Mask" "F.Paste")
			(net "GND")
			(options
				(clearance outline)
				(anchor circle)
			)
			(primitives
				(gr_poly
					(pts
						(arc
							(start -0.1778 -0.2794)
							(mid -0.249642 -0.249642)
							(end -0.2794 -0.1778)
						)
						(arc
							(start -0.2794 0.1778)
							(mid -0.249642 0.249642)
							(end -0.1778 0.2794)
						)
						(arc
							(start 0.1778 0.2794)
							(mid 0.249642 0.249642)
							(end 0.2794 0.1778)
						)
						(arc
							(start 0.2794 -0.1778)
							(mid 0.249642 -0.249642)
							(end 0.1778 -0.2794)
						)
					)
					(width 0)
					(fill yes)
				)
			)
		)
	)
	(footprint ""
		(layer "F.Cu")
		(at 129.286 -373.507 90)
		(property "Reference" "R934"
			(at 0 0 90)
			(layer "F.SilkS")
			(hide yes)
			(effects
				(font
					(size 1.27 1.27)
				)
			)
		)
		(property "Value" "4K7R2F-GP"
			(at 0.064008 -3.993896 90)
			(unlocked yes)
			(layer "F.Fab")
			(hide yes)
			(effects
				(font
					(size 1.016 1.016)
					(thickness 0.1524)
				)
			)
		)
		(property "Device Type" "R402H16"
			(at 0.064008 -5.517896 90)
			(unlocked yes)
			(layer "F.Fab")
			(hide yes)
			(effects
				(font
					(size 1.016 1.016)
					(thickness 0.1524)
				)
			)
		)
		(duplicate_pad_numbers_are_jumpers no)
		(fp_line
			(start 0.508 -0.9398)
			(end -0.508 -0.9398)
			(stroke
				(width 0.1524)
				(type default)
			)
			(layer "F.SilkS")
		)
		(fp_line
			(start -0.508 -0.9398)
			(end -0.508 0.9398)
			(stroke
				(width 0.1524)
				(type default)
			)
			(layer "F.SilkS")
		)
		(fp_rect
			(start -0.508 0.9398)
			(end 0.508 -0.9398)
			(stroke
				(width 0)
				(type default)
			)
			(fill no)
			(layer "F.CrtYd")
		)
		(fp_rect
			(start -0.508 0.9398)
			(end 0.508 -0.9398)
			(stroke
				(width 0)
				(type default)
			)
			(fill no)
			(layer "F.Fab")
		)
		(pad "1" smd custom
			(at 0 -0.4445 90)
			(size 0.1397 0.1397)
			(layers "F.Cu" "F.Mask" "F.Paste")
			(net "P12V_IN")
			(options
				(clearance outline)
				(anchor circle)
			)
			(primitives
				(gr_poly
					(pts
						(arc
							(start -0.1778 -0.2794)
							(mid -0.249642 -0.249642)
							(end -0.2794 -0.1778)
						)
						(arc
							(start -0.2794 0.1778)
							(mid -0.249642 0.249642)
							(end -0.1778 0.2794)
						)
						(arc
							(start 0.1778 0.2794)
							(mid 0.249642 0.249642)
							(end 0.2794 0.1778)
						)
						(arc
							(start 0.2794 -0.1778)
							(mid 0.249642 -0.249642)
							(end 0.1778 -0.2794)
						)
					)
					(width 0)
					(fill yes)
				)
			)
		)
		(pad "2" smd custom
			(at 0 0.4445 90)
			(size 0.1397 0.1397)
			(layers "F.Cu" "F.Mask" "F.Paste")
			(net "FAN_1_TACH0")
			(options
				(clearance outline)
				(anchor circle)
			)
			(primitives
				(gr_poly
					(pts
						(arc
							(start -0.1778 -0.2794)
							(mid -0.249642 -0.249642)
							(end -0.2794 -0.1778)
						)
						(arc
							(start -0.2794 0.1778)
							(mid -0.249642 0.249642)
							(end -0.1778 0.2794)
						)
						(arc
							(start 0.1778 0.2794)
							(mid 0.249642 0.249642)
							(end 0.2794 0.1778)
						)
						(arc
							(start 0.2794 -0.1778)
							(mid 0.249642 -0.249642)
							(end 0.1778 -0.2794)
						)
					)
					(width 0)
					(fill yes)
				)
			)
		)
	)
	(footprint ""
		(layer "F.Cu")
		(at 457.708 -249.4788 90)
		(property "Reference" "R323"
			(at 0 0 90)
			(layer "F.SilkS")
			(hide yes)
			(effects
				(font
					(size 1.27 1.27)
				)
			)
		)
		(property "Value" "4K7R2J-2-GP"
			(at 0.064008 -3.993896 90)
			(unlocked yes)
			(layer "F.Fab")
			(hide yes)
			(effects
				(font
					(size 1.016 1.016)
					(thickness 0.1524)
				)
			)
		)
		(property "Device Type" "R402H16"
			(at 0.064008 -5.517896 90)
			(unlocked yes)
			(layer "F.Fab")
			(hide yes)
			(effects
				(font
					(size 1.016 1.016)
					(thickness 0.1524)
				)
			)
		)
		(duplicate_pad_numbers_are_jumpers no)
		(fp_line
			(start 0.508 -0.9398)
			(end -0.508 -0.9398)
			(stroke
				(width 0.1524)
				(type default)
			)
			(layer "F.SilkS")
		)
		(fp_line
			(start -0.508 -0.9398)
			(end -0.508 0.9398)
			(stroke
				(width 0.1524)
				(type default)
			)
			(layer "F.SilkS")
		)
		(fp_rect
			(start -0.508 0.9398)
			(end 0.508 -0.9398)
			(stroke
				(width 0)
				(type default)
			)
			(fill no)
			(layer "F.CrtYd")
		)
		(fp_rect
			(start -0.508 0.9398)
			(end 0.508 -0.9398)
			(stroke
				(width 0)
				(type default)
			)
			(fill no)
			(layer "F.Fab")
		)
		(pad "1" smd custom
			(at 0 -0.4445 90)
			(size 0.1397 0.1397)
			(layers "F.Cu" "F.Mask" "F.Paste")
			(net "P12V_B")
			(options
				(clearance outline)
				(anchor circle)
			)
			(primitives
				(gr_poly
					(pts
						(arc
							(start -0.1778 -0.2794)
							(mid -0.249642 -0.249642)
							(end -0.2794 -0.1778)
						)
						(arc
							(start -0.2794 0.1778)
							(mid -0.249642 0.249642)
							(end -0.1778 0.2794)
						)
						(arc
							(start 0.1778 0.2794)
							(mid 0.249642 0.249642)
							(end 0.2794 0.1778)
						)
						(arc
							(start 0.2794 -0.1778)
							(mid 0.249642 -0.249642)
							(end 0.1778 -0.2794)
						)
					)
					(width 0)
					(fill yes)
				)
			)
		)
		(pad "2" smd custom
			(at 0 0.4445 90)
			(size 0.1397 0.1397)
			(layers "F.Cu" "F.Mask" "F.Paste")
			(net "SW_HDD_P10")
			(options
				(clearance outline)
				(anchor circle)
			)
			(primitives
				(gr_poly
					(pts
						(arc
							(start -0.1778 -0.2794)
							(mid -0.249642 -0.249642)
							(end -0.2794 -0.1778)
						)
						(arc
							(start -0.2794 0.1778)
							(mid -0.249642 0.249642)
							(end -0.1778 0.2794)
						)
						(arc
							(start 0.1778 0.2794)
							(mid 0.249642 0.249642)
							(end 0.2794 0.1778)
						)
						(arc
							(start 0.2794 -0.1778)
							(mid 0.249642 -0.249642)
							(end 0.1778 -0.2794)
						)
					)
					(width 0)
					(fill yes)
				)
			)
		)
	)
	(footprint ""
		(layer "F.Cu")
		(at 447.834512 -129.66065 -90)
		(property "Reference" "C315"
			(at 0 0 270)
			(layer "F.SilkS")
			(hide yes)
			(effects
				(font
					(size 1.27 1.27)
				)
			)
		)
		(property "Value" "SCD01U16V1KX-GP"
			(at -2.8321 -1.7399 270)
			(unlocked yes)
			(layer "F.Fab")
			(hide yes)
			(effects
				(font
					(size 1.016 1.016)
					(thickness 0.1524)
				)
			)
		)
		(property "Device Type" "C0201H13"
			(at -2.8321 -3.2639 270)
			(unlocked yes)
			(layer "F.Fab")
			(hide yes)
			(effects
				(font
					(size 1.016 1.016)
					(thickness 0.1524)
				)
			)
		)
		(duplicate_pad_numbers_are_jumpers no)
		(fp_rect
			(start -0.2794 0.6477)
			(end 0.2794 -0.6477)
			(stroke
				(width 0)
				(type default)
			)
			(fill no)
			(layer "F.CrtYd")
		)
		(fp_rect
			(start -0.2794 0.6477)
			(end 0.2794 -0.6477)
			(stroke
				(width 0)
				(type default)
			)
			(fill no)
			(layer "F.Fab")
		)
		(pad "1" smd custom
			(at 0 -0.2794 270)
			(size 0.0762 0.0762)
			(layers "F.Cu" "F.Mask" "F.Paste")
			(net "SAS_HDD_RX_P22")
			(options
				(clearance outline)
				(anchor circle)
			)
			(primitives
				(gr_poly
					(pts
						(arc
							(start 0.1524 -0.127)
							(mid 0.137521 -0.162921)
							(end 0.1016 -0.1778)
						)
						(arc
							(start -0.1016 -0.1778)
							(mid -0.137521 -0.162921)
							(end -0.1524 -0.127)
						)
						(arc
							(start -0.1524 0.127)
							(mid -0.137521 0.162921)
							(end -0.1016 0.1778)
						)
						(arc
							(start 0.1016 0.1778)
							(mid 0.137521 0.162921)
							(end 0.1524 0.127)
						)
					)
					(width 0)
					(fill yes)
				)
			)
		)
		(pad "2" smd custom
			(at 0 0.2794 270)
			(size 0.0762 0.0762)
			(layers "F.Cu" "F.Mask" "F.Paste")
			(net "PHY_SCC_B_TO_DRV_B_22_DP")
			(options
				(clearance outline)
				(anchor circle)
			)
			(primitives
				(gr_poly
					(pts
						(arc
							(start 0.1524 -0.127)
							(mid 0.137521 -0.162921)
							(end 0.1016 -0.1778)
						)
						(arc
							(start -0.1016 -0.1778)
							(mid -0.137521 -0.162921)
							(end -0.1524 -0.127)
						)
						(arc
							(start -0.1524 0.127)
							(mid -0.137521 0.162921)
							(end -0.1016 0.1778)
						)
						(arc
							(start 0.1016 0.1778)
							(mid 0.137521 0.162921)
							(end 0.1524 0.127)
						)
					)
					(width 0)
					(fill yes)
				)
			)
		)
	)
	(footprint ""
		(layer "F.Cu")
		(at 51.943 -134.493 180)
		(property "Reference" "Q53"
			(at 0 0 180)
			(layer "F.SilkS")
			(hide yes)
			(effects
				(font
					(size 1.27 1.27)
				)
			)
		)
		(property "Value" "2N7002KDW-GP"
			(at -2.3622 -8.2042 180)
			(unlocked yes)
			(layer "F.Fab")
			(hide yes)
			(effects
				(font
					(size 1.016 1.016)
					(thickness 0.1524)
				)
			)
		)
		(property "Device Type" "SOT-363H44"
			(at -2.3622 -10.1092 180)
			(unlocked yes)
			(layer "F.Fab")
			(hide yes)
			(effects
				(font
					(size 1.016 1.016)
					(thickness 0.1524)
				)
			)
		)
		(duplicate_pad_numbers_are_jumpers no)
		(fp_line
			(start 1.4478 1.7018)
			(end 1.4478 -1.7018)
			(stroke
				(width 0.1524)
				(type default)
			)
			(layer "F.SilkS")
		)
		(fp_line
			(start 1.4478 -1.7018)
			(end -1.4478 -1.7018)
			(stroke
				(width 0.1524)
				(type default)
			)
			(layer "F.SilkS")
		)
		(fp_line
			(start -1.27 1.524)
			(end -1.27 0.6604)
			(stroke
				(width 0.4826)
				(type default)
			)
			(layer "F.SilkS")
		)
		(fp_line
			(start -1.4478 1.7018)
			(end 1.4478 1.7018)
			(stroke
				(width 0.1524)
				(type default)
			)
			(layer "F.SilkS")
		)
		(fp_line
			(start -1.4478 -1.7018)
			(end -1.4478 1.7018)
			(stroke
				(width 0.1524)
				(type default)
			)
			(layer "F.SilkS")
		)
		(fp_poly
			(pts
				(xy -1.524 -1.778) (xy 1.524 -1.778) (xy 1.524 1.778) (xy -1.524 1.778)
			)
			(stroke
				(width 0)
				(type default)
			)
			(fill no)
			(layer "F.CrtYd")
		)
		(fp_poly
			(pts
				(xy -1.524 -1.778) (xy 1.524 -1.778) (xy 1.524 1.778) (xy -1.524 1.778)
			)
			(stroke
				(width 0)
				(type default)
			)
			(fill no)
			(layer "F.Fab")
		)
		(pad "1" smd rect
			(at -0.65024 0.9398 180)
			(size 0.4064 1.016)
			(layers "F.Cu" "F.Mask" "F.Paste")
			(net "GND")
		)
		(pad "2" smd rect
			(at 0 0.9398 180)
			(size 0.4064 1.016)
			(layers "F.Cu" "F.Mask" "F.Paste")
			(net "SW_PWR_R_HDD13")
		)
		(pad "3" smd rect
			(at 0.65024 0.9398 180)
			(size 0.4064 1.016)
			(layers "F.Cu" "F.Mask" "F.Paste")
			(net "SW_HDD_P13")
		)
		(pad "4" smd rect
			(at 0.65024 -0.9398 180)
			(size 0.4064 1.016)
			(layers "F.Cu" "F.Mask" "F.Paste")
			(net "GND")
		)
		(pad "5" smd rect
			(at 0 -0.9398 180)
			(size 0.4064 1.016)
			(layers "F.Cu" "F.Mask" "F.Paste")
			(net "SW_HDD_G13")
		)
		(pad "6" smd rect
			(at -0.65024 -0.9398 180)
			(size 0.4064 1.016)
			(layers "F.Cu" "F.Mask" "F.Paste")
			(net "SW_HDD_R13")
		)
	)
	(footprint ""
		(layer "F.Cu")
		(at 77.5716 -214.757 180)
		(property "Reference" "Q221"
			(at 0 0 180)
			(layer "F.SilkS")
			(hide yes)
			(effects
				(font
					(size 1.27 1.27)
				)
			)
		)
		(property "Value" "2N7002K-2-GP"
			(at 0.127 -8.9662 180)
			(unlocked yes)
			(layer "F.Fab")
			(hide yes)
			(effects
				(font
					(size 1.016 1.016)
					(thickness 0.1524)
				)
			)
		)
		(property "Device Type" "SOT23DGS2D4H44"
			(at 0.127 -10.4902 180)
			(unlocked yes)
			(layer "F.Fab")
			(hide yes)
			(effects
				(font
					(size 1.016 1.016)
					(thickness 0.1524)
				)
			)
		)
		(duplicate_pad_numbers_are_jumpers no)
		(fp_line
			(start 1.651 1.778)
			(end 1.651 -1.778)
			(stroke
				(width 0.1524)
				(type default)
			)
			(layer "F.SilkS")
		)
		(fp_line
			(start 1.651 -1.778)
			(end -1.651 -1.778)
			(stroke
				(width 0.1524)
				(type default)
			)
			(layer "F.SilkS")
		)
		(fp_line
			(start -1.651 1.778)
			(end 1.651 1.778)
			(stroke
				(width 0.1524)
				(type default)
			)
			(layer "F.SilkS")
		)
		(fp_line
			(start -1.651 -1.778)
			(end -1.651 1.778)
			(stroke
				(width 0.1524)
				(type default)
			)
			(layer "F.SilkS")
		)
		(fp_poly
			(pts
				(xy -1.778 1.8796) (xy -1.778 -1.8796) (xy 1.778 -1.8796) (xy 1.778 1.8796)
			)
			(stroke
				(width 0)
				(type default)
			)
			(fill no)
			(layer "F.CrtYd")
		)
		(fp_poly
			(pts
				(xy -1.778 1.8796) (xy -1.778 -1.8796) (xy 1.778 -1.8796) (xy 1.778 1.8796)
			)
			(stroke
				(width 0)
				(type default)
			)
			(fill no)
			(layer "F.Fab")
		)
		(pad "D" smd custom
			(at 0 -0.9525 180)
			(size 0.1905 0.1905)
			(layers "F.Cu" "F.Mask" "F.Paste")
			(net "FLT_HDD2_N")
			(options
				(clearance outline)
				(anchor circle)
			)
			(primitives
				(gr_poly
					(pts
						(arc
							(start -0.1778 0.5715)
							(mid -0.321484 0.511984)
							(end -0.381 0.3683)
						)
						(arc
							(start -0.381 -0.3683)
							(mid -0.321484 -0.511984)
							(end -0.1778 -0.5715)
						)
						(arc
							(start 0.1778 -0.5715)
							(mid 0.321484 -0.511984)
							(end 0.381 -0.3683)
						)
						(arc
							(start 0.381 0.3683)
							(mid 0.321484 0.511984)
							(end 0.1778 0.5715)
						)
					)
					(width 0)
					(fill yes)
				)
			)
		)
		(pad "G" smd custom
			(at -0.98425 0.9525 180)
			(size 0.1905 0.1905)
			(layers "F.Cu" "F.Mask" "F.Paste")
			(net "DRIVE_B_2_FLT_LED")
			(options
				(clearance outline)
				(anchor circle)
			)
			(primitives
				(gr_poly
					(pts
						(arc
							(start -0.1778 0.5715)
							(mid -0.321484 0.511984)
							(end -0.381 0.3683)
						)
						(arc
							(start -0.381 -0.3683)
							(mid -0.321484 -0.511984)
							(end -0.1778 -0.5715)
						)
						(arc
							(start 0.1778 -0.5715)
							(mid 0.321484 -0.511984)
							(end 0.381 -0.3683)
						)
						(arc
							(start 0.381 0.3683)
							(mid 0.321484 0.511984)
							(end 0.1778 0.5715)
						)
					)
					(width 0)
					(fill yes)
				)
			)
		)
		(pad "S" smd custom
			(at 0.98425 0.9525 180)
			(size 0.1905 0.1905)
			(layers "F.Cu" "F.Mask" "F.Paste")
			(net "GND")
			(options
				(clearance outline)
				(anchor circle)
			)
			(primitives
				(gr_poly
					(pts
						(arc
							(start -0.1778 0.5715)
							(mid -0.321484 0.511984)
							(end -0.381 0.3683)
						)
						(arc
							(start -0.381 -0.3683)
							(mid -0.321484 -0.511984)
							(end -0.1778 -0.5715)
						)
						(arc
							(start 0.1778 -0.5715)
							(mid 0.321484 -0.511984)
							(end 0.381 -0.3683)
						)
						(arc
							(start 0.381 0.3683)
							(mid 0.321484 0.511984)
							(end 0.1778 0.5715)
						)
					)
					(width 0)
					(fill yes)
				)
			)
		)
	)
	(footprint ""
		(layer "F.Cu")
		(at 149.225 -134.493 90)
		(property "Reference" "R451"
			(at 0 0 90)
			(layer "F.SilkS")
			(hide yes)
			(effects
				(font
					(size 1.27 1.27)
				)
			)
		)
		(property "Value" "4K7R2F-GP"
			(at 0.064008 -3.993896 90)
			(unlocked yes)
			(layer "F.Fab")
			(hide yes)
			(effects
				(font
					(size 1.016 1.016)
					(thickness 0.1524)
				)
			)
		)
		(property "Device Type" "R402H16"
			(at 0.064008 -5.517896 90)
			(unlocked yes)
			(layer "F.Fab")
			(hide yes)
			(effects
				(font
					(size 1.016 1.016)
					(thickness 0.1524)
				)
			)
		)
		(duplicate_pad_numbers_are_jumpers no)
		(fp_line
			(start 0.508 -0.9398)
			(end -0.508 -0.9398)
			(stroke
				(width 0.1524)
				(type default)
			)
			(layer "F.SilkS")
		)
		(fp_line
			(start -0.508 -0.9398)
			(end -0.508 0.9398)
			(stroke
				(width 0.1524)
				(type default)
			)
			(layer "F.SilkS")
		)
		(fp_rect
			(start -0.508 0.9398)
			(end 0.508 -0.9398)
			(stroke
				(width 0)
				(type default)
			)
			(fill no)
			(layer "F.CrtYd")
		)
		(fp_rect
			(start -0.508 0.9398)
			(end 0.508 -0.9398)
			(stroke
				(width 0)
				(type default)
			)
			(fill no)
			(layer "F.Fab")
		)
		(pad "1" smd custom
			(at 0 -0.4445 90)
			(size 0.1397 0.1397)
			(layers "F.Cu" "F.Mask" "F.Paste")
			(net "SW_PWR_R_HDD16")
			(options
				(clearance outline)
				(anchor circle)
			)
			(primitives
				(gr_poly
					(pts
						(arc
							(start -0.1778 -0.2794)
							(mid -0.249642 -0.249642)
							(end -0.2794 -0.1778)
						)
						(arc
							(start -0.2794 0.1778)
							(mid -0.249642 0.249642)
							(end -0.1778 0.2794)
						)
						(arc
							(start 0.1778 0.2794)
							(mid 0.249642 0.249642)
							(end 0.2794 0.1778)
						)
						(arc
							(start 0.2794 -0.1778)
							(mid 0.249642 -0.249642)
							(end 0.1778 -0.2794)
						)
					)
					(width 0)
					(fill yes)
				)
			)
		)
		(pad "2" smd custom
			(at 0 0.4445 90)
			(size 0.1397 0.1397)
			(layers "F.Cu" "F.Mask" "F.Paste")
			(net "GND")
			(options
				(clearance outline)
				(anchor circle)
			)
			(primitives
				(gr_poly
					(pts
						(arc
							(start -0.1778 -0.2794)
							(mid -0.249642 -0.249642)
							(end -0.2794 -0.1778)
						)
						(arc
							(start -0.2794 0.1778)
							(mid -0.249642 0.249642)
							(end -0.1778 0.2794)
						)
						(arc
							(start 0.1778 0.2794)
							(mid 0.249642 0.249642)
							(end 0.2794 0.1778)
						)
						(arc
							(start 0.2794 -0.1778)
							(mid 0.249642 -0.249642)
							(end 0.1778 -0.2794)
						)
					)
					(width 0)
					(fill yes)
				)
			)
		)
	)
	(footprint ""
		(layer "F.Cu")
		(at 426.72 -128.651)
		(property "Reference" "R565"
			(at 0 0 0)
			(layer "F.SilkS")
			(hide yes)
			(effects
				(font
					(size 1.27 1.27)
				)
			)
		)
		(property "Value" "4K7R2F-GP"
			(at 0.064008 -3.993896 0)
			(unlocked yes)
			(layer "F.Fab")
			(hide yes)
			(effects
				(font
					(size 1.016 1.016)
					(thickness 0.1524)
				)
			)
		)
		(property "Device Type" "R402H16"
			(at 0.064008 -5.517896 0)
			(unlocked yes)
			(layer "F.Fab")
			(hide yes)
			(effects
				(font
					(size 1.016 1.016)
					(thickness 0.1524)
				)
			)
		)
		(duplicate_pad_numbers_are_jumpers no)
		(fp_line
			(start -0.508 -0.9398)
			(end -0.508 0.9398)
			(stroke
				(width 0.1524)
				(type default)
			)
			(layer "F.SilkS")
		)
		(fp_line
			(start 0.508 -0.9398)
			(end -0.508 -0.9398)
			(stroke
				(width 0.1524)
				(type default)
			)
			(layer "F.SilkS")
		)
		(fp_rect
			(start -0.508 0.9398)
			(end 0.508 -0.9398)
			(stroke
				(width 0)
				(type default)
			)
			(fill no)
			(layer "F.CrtYd")
		)
		(fp_rect
			(start -0.508 0.9398)
			(end 0.508 -0.9398)
			(stroke
				(width 0)
				(type default)
			)
			(fill no)
			(layer "F.Fab")
		)
		(pad "1" smd custom
			(at 0 -0.4445)
			(size 0.1397 0.1397)
			(layers "F.Cu" "F.Mask" "F.Paste")
			(net "SW_PWR_R_HDD21")
			(options
				(clearance outline)
				(anchor circle)
			)
			(primitives
				(gr_poly
					(pts
						(arc
							(start -0.1778 -0.2794)
							(mid -0.249642 -0.249642)
							(end -0.2794 -0.1778)
						)
						(arc
							(start -0.2794 0.1778)
							(mid -0.249642 0.249642)
							(end -0.1778 0.2794)
						)
						(arc
							(start 0.1778 0.2794)
							(mid 0.249642 0.249642)
							(end 0.2794 0.1778)
						)
						(arc
							(start 0.2794 -0.1778)
							(mid 0.249642 -0.249642)
							(end 0.1778 -0.2794)
						)
					)
					(width 0)
					(fill yes)
				)
			)
		)
		(pad "2" smd custom
			(at 0 0.4445)
			(size 0.1397 0.1397)
			(layers "F.Cu" "F.Mask" "F.Paste")
			(net "GND")
			(options
				(clearance outline)
				(anchor circle)
			)
			(primitives
				(gr_poly
					(pts
						(arc
							(start -0.1778 -0.2794)
							(mid -0.249642 -0.249642)
							(end -0.2794 -0.1778)
						)
						(arc
							(start -0.2794 0.1778)
							(mid -0.249642 0.249642)
							(end -0.1778 0.2794)
						)
						(arc
							(start 0.1778 0.2794)
							(mid 0.249642 0.249642)
							(end 0.2794 0.1778)
						)
						(arc
							(start 0.2794 -0.1778)
							(mid 0.249642 -0.249642)
							(end 0.1778 -0.2794)
						)
					)
					(width 0)
					(fill yes)
				)
			)
		)
	)
	(footprint ""
		(layer "F.Cu")
		(at 431.546 -246.761 180)
		(property "Reference" "R312"
			(at 0 0 180)
			(layer "F.SilkS")
			(hide yes)
			(effects
				(font
					(size 1.27 1.27)
				)
			)
		)
		(property "Value" "4K7R2J-2-GP"
			(at 0.064008 -3.993896 180)
			(unlocked yes)
			(layer "F.Fab")
			(hide yes)
			(effects
				(font
					(size 1.016 1.016)
					(thickness 0.1524)
				)
			)
		)
		(property "Device Type" "R402H16"
			(at 0.064008 -5.517896 180)
			(unlocked yes)
			(layer "F.Fab")
			(hide yes)
			(effects
				(font
					(size 1.016 1.016)
					(thickness 0.1524)
				)
			)
		)
		(duplicate_pad_numbers_are_jumpers no)
		(fp_line
			(start 0.508 -0.9398)
			(end -0.508 -0.9398)
			(stroke
				(width 0.1524)
				(type default)
			)
			(layer "F.SilkS")
		)
		(fp_line
			(start -0.508 -0.9398)
			(end -0.508 0.9398)
			(stroke
				(width 0.1524)
				(type default)
			)
			(layer "F.SilkS")
		)
		(fp_rect
			(start -0.508 0.9398)
			(end 0.508 -0.9398)
			(stroke
				(width 0)
				(type default)
			)
			(fill no)
			(layer "F.CrtYd")
		)
		(fp_rect
			(start -0.508 0.9398)
			(end 0.508 -0.9398)
			(stroke
				(width 0)
				(type default)
			)
			(fill no)
			(layer "F.Fab")
		)
		(pad "1" smd custom
			(at 0 -0.4445 180)
			(size 0.1397 0.1397)
			(layers "F.Cu" "F.Mask" "F.Paste")
			(net "P12V_B")
			(options
				(clearance outline)
				(anchor circle)
			)
			(primitives
				(gr_poly
					(pts
						(arc
							(start -0.1778 -0.2794)
							(mid -0.249642 -0.249642)
							(end -0.2794 -0.1778)
						)
						(arc
							(start -0.2794 0.1778)
							(mid -0.249642 0.249642)
							(end -0.1778 0.2794)
						)
						(arc
							(start 0.1778 0.2794)
							(mid 0.249642 0.249642)
							(end 0.2794 0.1778)
						)
						(arc
							(start 0.2794 -0.1778)
							(mid 0.249642 -0.249642)
							(end 0.1778 -0.2794)
						)
					)
					(width 0)
					(fill yes)
				)
			)
		)
		(pad "2" smd custom
			(at 0 0.4445 180)
			(size 0.1397 0.1397)
			(layers "F.Cu" "F.Mask" "F.Paste")
			(net "SW_HDD_R9")
			(options
				(clearance outline)
				(anchor circle)
			)
			(primitives
				(gr_poly
					(pts
						(arc
							(start -0.1778 -0.2794)
							(mid -0.249642 -0.249642)
							(end -0.2794 -0.1778)
						)
						(arc
							(start -0.2794 0.1778)
							(mid -0.249642 0.249642)
							(end -0.1778 0.2794)
						)
						(arc
							(start 0.1778 0.2794)
							(mid 0.249642 0.249642)
							(end 0.2794 0.1778)
						)
						(arc
							(start 0.2794 -0.1778)
							(mid 0.249642 -0.249642)
							(end 0.1778 -0.2794)
						)
					)
					(width 0)
					(fill yes)
				)
			)
		)
	)
	(footprint ""
		(layer "F.Cu")
		(at 86.868 -263.271)
		(property "Reference" "R190"
			(at 0 0 0)
			(layer "F.SilkS")
			(hide yes)
			(effects
				(font
					(size 1.27 1.27)
				)
			)
		)
		(property "Value" "2R6F-GP"
			(at -0.0508 -4.8514 0)
			(unlocked yes)
			(layer "F.Fab")
			(hide yes)
			(effects
				(font
					(size 1.016 1.016)
					(thickness 0.1524)
				)
			)
		)
		(property "Device Type" "R1206H26"
			(at 0 -6.3754 0)
			(unlocked yes)
			(layer "F.Fab")
			(hide yes)
			(effects
				(font
					(size 1.016 1.016)
					(thickness 0.1524)
				)
			)
		)
		(duplicate_pad_numbers_are_jumpers no)
		(fp_line
			(start -1.016 -2.2352)
			(end 1.016 -2.2352)
			(stroke
				(width 0.1524)
				(type default)
			)
			(layer "F.SilkS")
		)
		(fp_line
			(start -1.016 2.2352)
			(end -1.016 -2.2352)
			(stroke
				(width 0.1524)
				(type default)
			)
			(layer "F.SilkS")
		)
		(fp_line
			(start 1.016 -2.2352)
			(end 1.016 2.2352)
			(stroke
				(width 0.1524)
				(type default)
			)
			(layer "F.SilkS")
		)
		(fp_line
			(start 1.016 2.2352)
			(end -1.016 2.2352)
			(stroke
				(width 0.1524)
				(type default)
			)
			(layer "F.SilkS")
		)
		(fp_rect
			(start -1.0922 2.3114)
			(end 1.0922 -2.3114)
			(stroke
				(width 0)
				(type default)
			)
			(fill no)
			(layer "F.CrtYd")
		)
		(fp_poly
			(pts
				(xy -1.0922 -2.3114) (xy 1.0922 -2.3114) (xy 1.0922 2.3114) (xy -1.0922 2.3114)
			)
			(stroke
				(width 0)
				(type default)
			)
			(fill no)
			(layer "F.Fab")
		)
		(pad "1" smd rect
			(at 0 -1.397)
			(size 1.651 1.27)
			(layers "F.Cu" "F.Mask" "F.Paste")
			(net "P5V_HDD2")
		)
		(pad "2" smd rect
			(at 0 1.397)
			(size 1.651 1.27)
			(layers "F.Cu" "F.Mask" "F.Paste")
			(net "5V_PRE_2")
		)
	)
	(footprint ""
		(layer "F.Cu")
		(at 248.525538 -135.479282 90)
		(property "Reference" "C58"
			(at 0 0 90)
			(layer "F.SilkS")
			(hide yes)
			(effects
				(font
					(size 1.27 1.27)
				)
			)
		)
		(property "Value" "SCD1U16V2KX-3GP"
			(at 1.1811 -2.7051 90)
			(unlocked yes)
			(layer "F.Fab")
			(hide yes)
			(effects
				(font
					(size 1.016 1.016)
					(thickness 0.1524)
				)
			)
		)
		(property "Device Type" "C402H22"
			(at 1.1811 -4.2291 90)
			(unlocked yes)
			(layer "F.Fab")
			(hide yes)
			(effects
				(font
					(size 1.016 1.016)
					(thickness 0.1524)
				)
			)
		)
		(duplicate_pad_numbers_are_jumpers no)
		(fp_rect
			(start -0.4318 0.9525)
			(end 0.4318 -0.9525)
			(stroke
				(width 0)
				(type default)
			)
			(fill no)
			(layer "F.CrtYd")
		)
		(fp_rect
			(start -0.4318 0.9525)
			(end 0.4318 -0.9525)
			(stroke
				(width 0)
				(type default)
			)
			(fill no)
			(layer "F.Fab")
		)
		(pad "1" smd custom
			(at 0 -0.4445 90)
			(size 0.1524 0.1524)
			(layers "F.Cu" "F.Mask" "F.Paste")
			(net "P3V3_STBY_B")
			(options
				(clearance outline)
				(anchor circle)
			)
			(primitives
				(gr_poly
					(pts
						(arc
							(start 0.3048 -0.2032)
							(mid 0.275042 -0.275042)
							(end 0.2032 -0.3048)
						)
						(arc
							(start -0.2032 -0.3048)
							(mid -0.275042 -0.275042)
							(end -0.3048 -0.2032)
						)
						(arc
							(start -0.3048 0.2032)
							(mid -0.275042 0.275042)
							(end -0.2032 0.3048)
						)
						(arc
							(start 0.2032 0.3048)
							(mid 0.275042 0.275042)
							(end 0.3048 0.2032)
						)
					)
					(width 0)
					(fill yes)
				)
			)
		)
		(pad "2" smd custom
			(at 0 0.4445 90)
			(size 0.1524 0.1524)
			(layers "F.Cu" "F.Mask" "F.Paste")
			(net "GND")
			(options
				(clearance outline)
				(anchor circle)
			)
			(primitives
				(gr_poly
					(pts
						(arc
							(start 0.3048 -0.2032)
							(mid 0.275042 -0.275042)
							(end 0.2032 -0.3048)
						)
						(arc
							(start -0.2032 -0.3048)
							(mid -0.275042 -0.275042)
							(end -0.3048 -0.2032)
						)
						(arc
							(start -0.3048 0.2032)
							(mid -0.275042 0.275042)
							(end -0.2032 0.3048)
						)
						(arc
							(start 0.2032 0.3048)
							(mid 0.275042 0.275042)
							(end 0.3048 0.2032)
						)
					)
					(width 0)
					(fill yes)
				)
			)
		)
	)
	(footprint ""
		(layer "F.Cu")
		(at 129.921 -262.128 90)
		(property "Reference" "C75"
			(at 0 0 90)
			(layer "F.SilkS")
			(hide yes)
			(effects
				(font
					(size 1.27 1.27)
				)
			)
		)
		(property "Value" "SCD01U50V2KX-1GP"
			(at 1.1811 -2.7051 90)
			(unlocked yes)
			(layer "F.Fab")
			(hide yes)
			(effects
				(font
					(size 1.016 1.016)
					(thickness 0.1524)
				)
			)
		)
		(property "Device Type" "C402H22"
			(at 1.1811 -4.2291 90)
			(unlocked yes)
			(layer "F.Fab")
			(hide yes)
			(effects
				(font
					(size 1.016 1.016)
					(thickness 0.1524)
				)
			)
		)
		(duplicate_pad_numbers_are_jumpers no)
		(fp_rect
			(start -0.4318 0.9525)
			(end 0.4318 -0.9525)
			(stroke
				(width 0)
				(type default)
			)
			(fill no)
			(layer "F.CrtYd")
		)
		(fp_rect
			(start -0.4318 0.9525)
			(end 0.4318 -0.9525)
			(stroke
				(width 0)
				(type default)
			)
			(fill no)
			(layer "F.Fab")
		)
		(pad "1" smd custom
			(at 0 -0.4445 90)
			(size 0.1524 0.1524)
			(layers "F.Cu" "F.Mask" "F.Paste")
			(net "HDD_PRSNT_3")
			(options
				(clearance outline)
				(anchor circle)
			)
			(primitives
				(gr_poly
					(pts
						(arc
							(start 0.3048 -0.2032)
							(mid 0.275042 -0.275042)
							(end 0.2032 -0.3048)
						)
						(arc
							(start -0.2032 -0.3048)
							(mid -0.275042 -0.275042)
							(end -0.3048 -0.2032)
						)
						(arc
							(start -0.3048 0.2032)
							(mid -0.275042 0.275042)
							(end -0.2032 0.3048)
						)
						(arc
							(start 0.2032 0.3048)
							(mid 0.275042 0.275042)
							(end 0.3048 0.2032)
						)
					)
					(width 0)
					(fill yes)
				)
			)
		)
		(pad "2" smd custom
			(at 0 0.4445 90)
			(size 0.1524 0.1524)
			(layers "F.Cu" "F.Mask" "F.Paste")
			(net "GND")
			(options
				(clearance outline)
				(anchor circle)
			)
			(primitives
				(gr_poly
					(pts
						(arc
							(start 0.3048 -0.2032)
							(mid 0.275042 -0.275042)
							(end 0.2032 -0.3048)
						)
						(arc
							(start -0.2032 -0.3048)
							(mid -0.275042 -0.275042)
							(end -0.3048 -0.2032)
						)
						(arc
							(start -0.3048 0.2032)
							(mid -0.275042 0.275042)
							(end -0.2032 0.3048)
						)
						(arc
							(start 0.2032 0.3048)
							(mid 0.275042 0.275042)
							(end 0.3048 0.2032)
						)
					)
					(width 0)
					(fill yes)
				)
			)
		)
	)
	(footprint ""
		(layer "F.Cu")
		(at 23.112476 -221.58325 -90)
		(property "Reference" "R1104"
			(at 0 0 270)
			(layer "F.SilkS")
			(hide yes)
			(effects
				(font
					(size 1.27 1.27)
				)
			)
		)
		(property "Value" "3D01R5F-GP"
			(at 0 -8.9535 270)
			(unlocked yes)
			(layer "F.Fab")
			(hide yes)
			(effects
				(font
					(size 1.27 1.016)
					(thickness 0.1524)
				)
			)
		)
		(property "Device Type" "R805H24"
			(at 0 -10.6299 270)
			(unlocked yes)
			(layer "F.Fab")
			(hide yes)
			(effects
				(font
					(size 1.27 1.016)
					(thickness 0.1524)
				)
			)
		)
		(duplicate_pad_numbers_are_jumpers no)
		(fp_line
			(start -0.889 1.7018)
			(end 0.889 1.7018)
			(stroke
				(width 0.1524)
				(type default)
			)
			(layer "F.SilkS")
		)
		(fp_line
			(start 0.889 1.7018)
			(end 0.889 -0.508)
			(stroke
				(width 0.1524)
				(type default)
			)
			(layer "F.SilkS")
		)
		(fp_line
			(start -0.889 0.0762)
			(end -0.889 1.7018)
			(stroke
				(width 0.1524)
				(type default)
			)
			(layer "F.SilkS")
		)
		(fp_line
			(start -0.889 -1.7018)
			(end -0.889 0.2794)
			(stroke
				(width 0.1524)
				(type default)
			)
			(layer "F.SilkS")
		)
		(fp_line
			(start 0.889 -1.7018)
			(end 0.889 -0.381)
			(stroke
				(width 0.1524)
				(type default)
			)
			(layer "F.SilkS")
		)
		(fp_line
			(start 0.889 -1.7018)
			(end -0.889 -1.7018)
			(stroke
				(width 0.1524)
				(type default)
			)
			(layer "F.SilkS")
		)
		(fp_poly
			(pts
				(xy 0.9652 -1.778) (xy 0.9652 1.778) (xy -0.9652 1.778) (xy -0.9652 -1.778)
			)
			(stroke
				(width 0)
				(type default)
			)
			(fill no)
			(layer "F.CrtYd")
		)
		(fp_rect
			(start -0.9652 1.778)
			(end 0.9652 -1.778)
			(stroke
				(width 0)
				(type default)
			)
			(fill no)
			(layer "F.Fab")
		)
		(pad "1" smd rect
			(at 0 -0.9652 270)
			(size 1.397 1.143)
			(layers "F.Cu" "F.Mask" "F.Paste")
			(net "P5V_B_1_SNB")
		)
		(pad "2" smd rect
			(at 0 0.9652 270)
			(size 1.397 1.143)
			(layers "F.Cu" "F.Mask" "F.Paste")
			(net "GND")
		)
	)
	(footprint ""
		(layer "F.Cu")
		(at 66.802 -147.066 90)
		(property "Reference" "C205"
			(at 0 0 90)
			(layer "F.SilkS")
			(hide yes)
			(effects
				(font
					(size 1.27 1.27)
				)
			)
		)
		(property "Value" "SCD01U50V2KX-1GP"
			(at 1.1811 -2.7051 90)
			(unlocked yes)
			(layer "F.Fab")
			(hide yes)
			(effects
				(font
					(size 1.016 1.016)
					(thickness 0.1524)
				)
			)
		)
		(property "Device Type" "C402H22"
			(at 1.1811 -4.2291 90)
			(unlocked yes)
			(layer "F.Fab")
			(hide yes)
			(effects
				(font
					(size 1.016 1.016)
					(thickness 0.1524)
				)
			)
		)
		(duplicate_pad_numbers_are_jumpers no)
		(fp_rect
			(start -0.4318 0.9525)
			(end 0.4318 -0.9525)
			(stroke
				(width 0)
				(type default)
			)
			(fill no)
			(layer "F.CrtYd")
		)
		(fp_rect
			(start -0.4318 0.9525)
			(end 0.4318 -0.9525)
			(stroke
				(width 0)
				(type default)
			)
			(fill no)
			(layer "F.Fab")
		)
		(pad "1" smd custom
			(at 0 -0.4445 90)
			(size 0.1524 0.1524)
			(layers "F.Cu" "F.Mask" "F.Paste")
			(net "HDD_PRSNT_13")
			(options
				(clearance outline)
				(anchor circle)
			)
			(primitives
				(gr_poly
					(pts
						(arc
							(start 0.3048 -0.2032)
							(mid 0.275042 -0.275042)
							(end 0.2032 -0.3048)
						)
						(arc
							(start -0.2032 -0.3048)
							(mid -0.275042 -0.275042)
							(end -0.3048 -0.2032)
						)
						(arc
							(start -0.3048 0.2032)
							(mid -0.275042 0.275042)
							(end -0.2032 0.3048)
						)
						(arc
							(start 0.2032 0.3048)
							(mid 0.275042 0.275042)
							(end 0.3048 0.2032)
						)
					)
					(width 0)
					(fill yes)
				)
			)
		)
		(pad "2" smd custom
			(at 0 0.4445 90)
			(size 0.1524 0.1524)
			(layers "F.Cu" "F.Mask" "F.Paste")
			(net "GND")
			(options
				(clearance outline)
				(anchor circle)
			)
			(primitives
				(gr_poly
					(pts
						(arc
							(start 0.3048 -0.2032)
							(mid 0.275042 -0.275042)
							(end 0.2032 -0.3048)
						)
						(arc
							(start -0.2032 -0.3048)
							(mid -0.275042 -0.275042)
							(end -0.3048 -0.2032)
						)
						(arc
							(start -0.3048 0.2032)
							(mid -0.275042 0.275042)
							(end -0.2032 0.3048)
						)
						(arc
							(start 0.2032 0.3048)
							(mid 0.275042 0.275042)
							(end 0.3048 0.2032)
						)
					)
					(width 0)
					(fill yes)
				)
			)
		)
	)
	(footprint ""
		(layer "F.Cu")
		(at 416.3822 -31.6484)
		(property "Reference" "C461"
			(at 0 0 0)
			(layer "F.SilkS")
			(hide yes)
			(effects
				(font
					(size 1.27 1.27)
				)
			)
		)
		(property "Value" "SCD01U50V2KX-1GP"
			(at 1.1811 -2.7051 0)
			(unlocked yes)
			(layer "F.Fab")
			(hide yes)
			(effects
				(font
					(size 1.016 1.016)
					(thickness 0.1524)
				)
			)
		)
		(property "Device Type" "C402H22"
			(at 1.1811 -4.2291 0)
			(unlocked yes)
			(layer "F.Fab")
			(hide yes)
			(effects
				(font
					(size 1.016 1.016)
					(thickness 0.1524)
				)
			)
		)
		(duplicate_pad_numbers_are_jumpers no)
		(fp_rect
			(start -0.4318 0.9525)
			(end 0.4318 -0.9525)
			(stroke
				(width 0)
				(type default)
			)
			(fill no)
			(layer "F.CrtYd")
		)
		(fp_rect
			(start -0.4318 0.9525)
			(end 0.4318 -0.9525)
			(stroke
				(width 0)
				(type default)
			)
			(fill no)
			(layer "F.Fab")
		)
		(pad "1" smd custom
			(at 0 -0.4445)
			(size 0.1524 0.1524)
			(layers "F.Cu" "F.Mask" "F.Paste")
			(net "HDD_PRSNT_33")
			(options
				(clearance outline)
				(anchor circle)
			)
			(primitives
				(gr_poly
					(pts
						(arc
							(start 0.3048 -0.2032)
							(mid 0.275042 -0.275042)
							(end 0.2032 -0.3048)
						)
						(arc
							(start -0.2032 -0.3048)
							(mid -0.275042 -0.275042)
							(end -0.3048 -0.2032)
						)
						(arc
							(start -0.3048 0.2032)
							(mid -0.275042 0.275042)
							(end -0.2032 0.3048)
						)
						(arc
							(start 0.2032 0.3048)
							(mid 0.275042 0.275042)
							(end 0.3048 0.2032)
						)
					)
					(width 0)
					(fill yes)
				)
			)
		)
		(pad "2" smd custom
			(at 0 0.4445)
			(size 0.1524 0.1524)
			(layers "F.Cu" "F.Mask" "F.Paste")
			(net "GND")
			(options
				(clearance outline)
				(anchor circle)
			)
			(primitives
				(gr_poly
					(pts
						(arc
							(start 0.3048 -0.2032)
							(mid 0.275042 -0.275042)
							(end 0.2032 -0.3048)
						)
						(arc
							(start -0.2032 -0.3048)
							(mid -0.275042 -0.275042)
							(end -0.3048 -0.2032)
						)
						(arc
							(start -0.3048 0.2032)
							(mid -0.275042 0.275042)
							(end -0.2032 0.3048)
						)
						(arc
							(start 0.2032 0.3048)
							(mid 0.275042 0.275042)
							(end 0.3048 0.2032)
						)
					)
					(width 0)
					(fill yes)
				)
			)
		)
	)
	(footprint ""
		(layer "F.Cu")
		(at 259.490972 -372.32971)
		(property "Reference" "R1031"
			(at 0 0 0)
			(layer "F.SilkS")
			(hide yes)
			(effects
				(font
					(size 1.27 1.27)
				)
			)
		)
		(property "Value" "10KR2J-3-GP"
			(at 0.064008 -3.993896 0)
			(unlocked yes)
			(layer "F.Fab")
			(hide yes)
			(effects
				(font
					(size 1.016 1.016)
					(thickness 0.1524)
				)
			)
		)
		(property "Device Type" "R402H16"
			(at 0.064008 -5.517896 0)
			(unlocked yes)
			(layer "F.Fab")
			(hide yes)
			(effects
				(font
					(size 1.016 1.016)
					(thickness 0.1524)
				)
			)
		)
		(duplicate_pad_numbers_are_jumpers no)
		(fp_line
			(start -0.508 -0.9398)
			(end -0.508 0.9398)
			(stroke
				(width 0.1524)
				(type default)
			)
			(layer "F.SilkS")
		)
		(fp_line
			(start 0.508 -0.9398)
			(end -0.508 -0.9398)
			(stroke
				(width 0.1524)
				(type default)
			)
			(layer "F.SilkS")
		)
		(fp_rect
			(start -0.508 0.9398)
			(end 0.508 -0.9398)
			(stroke
				(width 0)
				(type default)
			)
			(fill no)
			(layer "F.CrtYd")
		)
		(fp_rect
			(start -0.508 0.9398)
			(end 0.508 -0.9398)
			(stroke
				(width 0)
				(type default)
			)
			(fill no)
			(layer "F.Fab")
		)
		(pad "1" smd custom
			(at 0 -0.4445)
			(size 0.1397 0.1397)
			(layers "F.Cu" "F.Mask" "F.Paste")
			(net "GND")
			(options
				(clearance outline)
				(anchor circle)
			)
			(primitives
				(gr_poly
					(pts
						(arc
							(start -0.1778 -0.2794)
							(mid -0.249642 -0.249642)
							(end -0.2794 -0.1778)
						)
						(arc
							(start -0.2794 0.1778)
							(mid -0.249642 0.249642)
							(end -0.1778 0.2794)
						)
						(arc
							(start 0.1778 0.2794)
							(mid 0.249642 0.249642)
							(end 0.2794 0.1778)
						)
						(arc
							(start 0.2794 -0.1778)
							(mid 0.249642 -0.249642)
							(end 0.1778 -0.2794)
						)
					)
					(width 0)
					(fill yes)
				)
			)
		)
		(pad "2" smd custom
			(at 0 0.4445)
			(size 0.1397 0.1397)
			(layers "F.Cu" "F.Mask" "F.Paste")
			(net "MB3_RETRY_R")
			(options
				(clearance outline)
				(anchor circle)
			)
			(primitives
				(gr_poly
					(pts
						(arc
							(start -0.1778 -0.2794)
							(mid -0.249642 -0.249642)
							(end -0.2794 -0.1778)
						)
						(arc
							(start -0.2794 0.1778)
							(mid -0.249642 0.249642)
							(end -0.1778 0.2794)
						)
						(arc
							(start 0.1778 0.2794)
							(mid 0.249642 0.249642)
							(end 0.2794 0.1778)
						)
						(arc
							(start 0.2794 -0.1778)
							(mid 0.249642 -0.249642)
							(end 0.1778 -0.2794)
						)
					)
					(width 0)
					(fill yes)
				)
			)
		)
	)
	(footprint ""
		(layer "F.Cu")
		(at 441.96 -214.249)
		(property "Reference" "R367"
			(at 0 0 0)
			(layer "F.SilkS")
			(hide yes)
			(effects
				(font
					(size 1.27 1.27)
				)
			)
		)
		(property "Value" "91R3F-1-GP"
			(at -0.0254 -2.5146 0)
			(unlocked yes)
			(layer "F.Fab")
			(hide yes)
			(effects
				(font
					(size 1.016 1.016)
					(thickness 0.1524)
				)
			)
		)
		(property "Device Type" "R603H22"
			(at -0.0254 -4.0386 0)
			(unlocked yes)
			(layer "F.Fab")
			(hide yes)
			(effects
				(font
					(size 1.016 1.016)
					(thickness 0.1524)
				)
			)
		)
		(duplicate_pad_numbers_are_jumpers no)
		(fp_line
			(start -0.4826 0)
			(end -0.2032 0)
			(stroke
				(width 0.2032)
				(type default)
			)
			(layer "F.SilkS")
		)
		(fp_line
			(start 0.2032 0)
			(end 0.4826 0)
			(stroke
				(width 0.2032)
				(type default)
			)
			(layer "F.SilkS")
		)
		(fp_rect
			(start -0.5842 1.3335)
			(end 0.5842 -1.3335)
			(stroke
				(width 0)
				(type default)
			)
			(fill no)
			(layer "F.CrtYd")
		)
		(fp_rect
			(start -0.5842 1.3335)
			(end 0.5842 -1.3335)
			(stroke
				(width 0)
				(type default)
			)
			(fill no)
			(layer "F.Fab")
		)
		(pad "1" smd custom
			(at 0 -0.762)
			(size 0.2159 0.2159)
			(layers "F.Cu" "F.Mask" "F.Paste")
			(net "P5V_B_3")
			(options
				(clearance outline)
				(anchor circle)
			)
			(primitives
				(gr_poly
					(pts
						(arc
							(start -0.3302 -0.4318)
							(mid -0.402042 -0.402042)
							(end -0.4318 -0.3302)
						)
						(arc
							(start -0.4318 0.3302)
							(mid -0.402042 0.402042)
							(end -0.3302 0.4318)
						)
						(arc
							(start 0.3302 0.4318)
							(mid 0.402042 0.402042)
							(end 0.4318 0.3302)
						)
						(arc
							(start 0.4318 -0.3302)
							(mid 0.402042 -0.402042)
							(end 0.3302 -0.4318)
						)
					)
					(width 0)
					(fill yes)
				)
			)
		)
		(pad "2" smd custom
			(at 0 0.762)
			(size 0.2159 0.2159)
			(layers "F.Cu" "F.Mask" "F.Paste")
			(net "DRV_ACT_10")
			(options
				(clearance outline)
				(anchor circle)
			)
			(primitives
				(gr_poly
					(pts
						(arc
							(start -0.3302 -0.4318)
							(mid -0.402042 -0.402042)
							(end -0.4318 -0.3302)
						)
						(arc
							(start -0.4318 0.3302)
							(mid -0.402042 0.402042)
							(end -0.3302 0.4318)
						)
						(arc
							(start 0.3302 0.4318)
							(mid 0.402042 0.402042)
							(end 0.4318 0.3302)
						)
						(arc
							(start 0.4318 -0.3302)
							(mid 0.402042 -0.402042)
							(end 0.3302 -0.4318)
						)
					)
					(width 0)
					(fill yes)
				)
			)
		)
	)
	(footprint ""
		(layer "F.Cu")
		(at 43.2054 -7.4168 -90)
		(property "Reference" "R121"
			(at 0 0 270)
			(layer "F.SilkS")
			(hide yes)
			(effects
				(font
					(size 1.27 1.27)
				)
			)
		)
		(property "Value" "4K7R2F-GP"
			(at 0.064008 -3.993896 270)
			(unlocked yes)
			(layer "F.Fab")
			(hide yes)
			(effects
				(font
					(size 1.016 1.016)
					(thickness 0.1524)
				)
			)
		)
		(property "Device Type" "R402H16"
			(at 0.064008 -5.517896 270)
			(unlocked yes)
			(layer "F.Fab")
			(hide yes)
			(effects
				(font
					(size 1.016 1.016)
					(thickness 0.1524)
				)
			)
		)
		(duplicate_pad_numbers_are_jumpers no)
		(fp_line
			(start -0.508 -0.9398)
			(end -0.508 0.9398)
			(stroke
				(width 0.1524)
				(type default)
			)
			(layer "F.SilkS")
		)
		(fp_line
			(start 0.508 -0.9398)
			(end -0.508 -0.9398)
			(stroke
				(width 0.1524)
				(type default)
			)
			(layer "F.SilkS")
		)
		(fp_rect
			(start -0.508 0.9398)
			(end 0.508 -0.9398)
			(stroke
				(width 0)
				(type default)
			)
			(fill no)
			(layer "F.CrtYd")
		)
		(fp_rect
			(start -0.508 0.9398)
			(end 0.508 -0.9398)
			(stroke
				(width 0)
				(type default)
			)
			(fill no)
			(layer "F.Fab")
		)
		(pad "1" smd custom
			(at 0 -0.4445 270)
			(size 0.1397 0.1397)
			(layers "F.Cu" "F.Mask" "F.Paste")
			(net "P3V3_STBY_A")
			(options
				(clearance outline)
				(anchor circle)
			)
			(primitives
				(gr_poly
					(pts
						(arc
							(start -0.1778 -0.2794)
							(mid -0.249642 -0.249642)
							(end -0.2794 -0.1778)
						)
						(arc
							(start -0.2794 0.1778)
							(mid -0.249642 0.249642)
							(end -0.1778 0.2794)
						)
						(arc
							(start 0.1778 0.2794)
							(mid 0.249642 0.249642)
							(end 0.2794 0.1778)
						)
						(arc
							(start 0.2794 -0.1778)
							(mid 0.249642 -0.249642)
							(end 0.1778 -0.2794)
						)
					)
					(width 0)
					(fill yes)
				)
			)
		)
		(pad "2" smd custom
			(at 0 0.4445 270)
			(size 0.1397 0.1397)
			(layers "F.Cu" "F.Mask" "F.Paste")
			(net "TEMP1_A0")
			(options
				(clearance outline)
				(anchor circle)
			)
			(primitives
				(gr_poly
					(pts
						(arc
							(start -0.1778 -0.2794)
							(mid -0.249642 -0.249642)
							(end -0.2794 -0.1778)
						)
						(arc
							(start -0.2794 0.1778)
							(mid -0.249642 0.249642)
							(end -0.1778 0.2794)
						)
						(arc
							(start 0.1778 0.2794)
							(mid 0.249642 0.249642)
							(end 0.2794 0.1778)
						)
						(arc
							(start 0.2794 -0.1778)
							(mid 0.249642 -0.249642)
							(end 0.1778 -0.2794)
						)
					)
					(width 0)
					(fill yes)
				)
			)
		)
	)
	(footprint ""
		(layer "F.Cu")
		(at 64.013334 -245.219474 90)
		(property "Reference" "C41"
			(at 0 0 90)
			(layer "F.SilkS")
			(hide yes)
			(effects
				(font
					(size 1.27 1.27)
				)
			)
		)
		(property "Value" "SCD01U16V1KX-GP"
			(at -2.8321 -1.7399 90)
			(unlocked yes)
			(layer "F.Fab")
			(hide yes)
			(effects
				(font
					(size 1.016 1.016)
					(thickness 0.1524)
				)
			)
		)
		(property "Device Type" "C0201H13"
			(at -2.8321 -3.2639 90)
			(unlocked yes)
			(layer "F.Fab")
			(hide yes)
			(effects
				(font
					(size 1.016 1.016)
					(thickness 0.1524)
				)
			)
		)
		(duplicate_pad_numbers_are_jumpers no)
		(fp_rect
			(start -0.2794 0.6477)
			(end 0.2794 -0.6477)
			(stroke
				(width 0)
				(type default)
			)
			(fill no)
			(layer "F.CrtYd")
		)
		(fp_rect
			(start -0.2794 0.6477)
			(end 0.2794 -0.6477)
			(stroke
				(width 0)
				(type default)
			)
			(fill no)
			(layer "F.Fab")
		)
		(pad "1" smd custom
			(at 0 -0.2794 90)
			(size 0.0762 0.0762)
			(layers "F.Cu" "F.Mask" "F.Paste")
			(net "SAS_HDD_RX_N1")
			(options
				(clearance outline)
				(anchor circle)
			)
			(primitives
				(gr_poly
					(pts
						(arc
							(start 0.1524 -0.127)
							(mid 0.137521 -0.162921)
							(end 0.1016 -0.1778)
						)
						(arc
							(start -0.1016 -0.1778)
							(mid -0.137521 -0.162921)
							(end -0.1524 -0.127)
						)
						(arc
							(start -0.1524 0.127)
							(mid -0.137521 0.162921)
							(end -0.1016 0.1778)
						)
						(arc
							(start 0.1016 0.1778)
							(mid 0.137521 0.162921)
							(end 0.1524 0.127)
						)
					)
					(width 0)
					(fill yes)
				)
			)
		)
		(pad "2" smd custom
			(at 0 0.2794 90)
			(size 0.0762 0.0762)
			(layers "F.Cu" "F.Mask" "F.Paste")
			(net "PHY_SCC_B_TO_DRV_B_1_DN")
			(options
				(clearance outline)
				(anchor circle)
			)
			(primitives
				(gr_poly
					(pts
						(arc
							(start 0.1524 -0.127)
							(mid 0.137521 -0.162921)
							(end 0.1016 -0.1778)
						)
						(arc
							(start -0.1016 -0.1778)
							(mid -0.137521 -0.162921)
							(end -0.1524 -0.127)
						)
						(arc
							(start -0.1524 0.127)
							(mid -0.137521 0.162921)
							(end -0.1016 0.1778)
						)
						(arc
							(start 0.1016 0.1778)
							(mid 0.137521 0.162921)
							(end 0.1524 0.127)
						)
					)
					(width 0)
					(fill yes)
				)
			)
		)
	)
	(footprint ""
		(layer "F.Cu")
		(at 52.27955 -102.351586 -90)
		(property "Reference" "R365"
			(at 0 0 270)
			(layer "F.SilkS")
			(hide yes)
			(effects
				(font
					(size 1.27 1.27)
				)
			)
		)
		(property "Value" "4K7R2F-GP"
			(at 0.064008 -3.993896 270)
			(unlocked yes)
			(layer "F.Fab")
			(hide yes)
			(effects
				(font
					(size 1.016 1.016)
					(thickness 0.1524)
				)
			)
		)
		(property "Device Type" "R402H16"
			(at 0.064008 -5.517896 270)
			(unlocked yes)
			(layer "F.Fab")
			(hide yes)
			(effects
				(font
					(size 1.016 1.016)
					(thickness 0.1524)
				)
			)
		)
		(duplicate_pad_numbers_are_jumpers no)
		(fp_line
			(start -0.508 -0.9398)
			(end -0.508 0.9398)
			(stroke
				(width 0.1524)
				(type default)
			)
			(layer "F.SilkS")
		)
		(fp_line
			(start 0.508 -0.9398)
			(end -0.508 -0.9398)
			(stroke
				(width 0.1524)
				(type default)
			)
			(layer "F.SilkS")
		)
		(fp_rect
			(start -0.508 0.9398)
			(end 0.508 -0.9398)
			(stroke
				(width 0)
				(type default)
			)
			(fill no)
			(layer "F.CrtYd")
		)
		(fp_rect
			(start -0.508 0.9398)
			(end 0.508 -0.9398)
			(stroke
				(width 0)
				(type default)
			)
			(fill no)
			(layer "F.Fab")
		)
		(pad "1" smd custom
			(at 0 -0.4445 270)
			(size 0.1397 0.1397)
			(layers "F.Cu" "F.Mask" "F.Paste")
			(net "DRIVE_B_13_FLT_LED")
			(options
				(clearance outline)
				(anchor circle)
			)
			(primitives
				(gr_poly
					(pts
						(arc
							(start -0.1778 -0.2794)
							(mid -0.249642 -0.249642)
							(end -0.2794 -0.1778)
						)
						(arc
							(start -0.2794 0.1778)
							(mid -0.249642 0.249642)
							(end -0.1778 0.2794)
						)
						(arc
							(start 0.1778 0.2794)
							(mid 0.249642 0.249642)
							(end 0.2794 0.1778)
						)
						(arc
							(start 0.2794 -0.1778)
							(mid 0.249642 -0.249642)
							(end 0.1778 -0.2794)
						)
					)
					(width 0)
					(fill yes)
				)
			)
		)
		(pad "2" smd custom
			(at 0 0.4445 270)
			(size 0.1397 0.1397)
			(layers "F.Cu" "F.Mask" "F.Paste")
			(net "GND")
			(options
				(clearance outline)
				(anchor circle)
			)
			(primitives
				(gr_poly
					(pts
						(arc
							(start -0.1778 -0.2794)
							(mid -0.249642 -0.249642)
							(end -0.2794 -0.1778)
						)
						(arc
							(start -0.2794 0.1778)
							(mid -0.249642 0.249642)
							(end -0.1778 0.2794)
						)
						(arc
							(start 0.1778 0.2794)
							(mid 0.249642 0.249642)
							(end 0.2794 0.1778)
						)
						(arc
							(start 0.2794 -0.1778)
							(mid 0.249642 -0.249642)
							(end 0.1778 -0.2794)
						)
					)
					(width 0)
					(fill yes)
				)
			)
		)
	)
	(footprint ""
		(layer "F.Cu")
		(at 463.047588 -229.5017 -90)
		(property "Reference" "R1140"
			(at 0 0 270)
			(layer "F.SilkS")
			(hide yes)
			(effects
				(font
					(size 1.27 1.27)
				)
			)
		)
		(property "Value" "10KR2F-2-GP"
			(at 0.064008 -3.993896 270)
			(unlocked yes)
			(layer "F.Fab")
			(hide yes)
			(effects
				(font
					(size 1.016 1.016)
					(thickness 0.1524)
				)
			)
		)
		(property "Device Type" "R402H16"
			(at 0.064008 -5.517896 270)
			(unlocked yes)
			(layer "F.Fab")
			(hide yes)
			(effects
				(font
					(size 1.016 1.016)
					(thickness 0.1524)
				)
			)
		)
		(duplicate_pad_numbers_are_jumpers no)
		(fp_line
			(start -0.508 -0.9398)
			(end -0.508 0.9398)
			(stroke
				(width 0.1524)
				(type default)
			)
			(layer "F.SilkS")
		)
		(fp_line
			(start 0.508 -0.9398)
			(end -0.508 -0.9398)
			(stroke
				(width 0.1524)
				(type default)
			)
			(layer "F.SilkS")
		)
		(fp_rect
			(start -0.508 0.9398)
			(end 0.508 -0.9398)
			(stroke
				(width 0)
				(type default)
			)
			(fill no)
			(layer "F.CrtYd")
		)
		(fp_rect
			(start -0.508 0.9398)
			(end 0.508 -0.9398)
			(stroke
				(width 0)
				(type default)
			)
			(fill no)
			(layer "F.Fab")
		)
		(pad "1" smd custom
			(at 0 -0.4445 270)
			(size 0.1397 0.1397)
			(layers "F.Cu" "F.Mask" "F.Paste")
			(net "P5V_B_3")
			(options
				(clearance outline)
				(anchor circle)
			)
			(primitives
				(gr_poly
					(pts
						(arc
							(start -0.1778 -0.2794)
							(mid -0.249642 -0.249642)
							(end -0.2794 -0.1778)
						)
						(arc
							(start -0.2794 0.1778)
							(mid -0.249642 0.249642)
							(end -0.1778 0.2794)
						)
						(arc
							(start 0.1778 0.2794)
							(mid 0.249642 0.249642)
							(end 0.2794 0.1778)
						)
						(arc
							(start 0.2794 -0.1778)
							(mid 0.249642 -0.249642)
							(end 0.1778 -0.2794)
						)
					)
					(width 0)
					(fill yes)
				)
			)
		)
		(pad "2" smd custom
			(at 0 0.4445 270)
			(size 0.1397 0.1397)
			(layers "F.Cu" "F.Mask" "F.Paste")
			(net "P5V_B_3_PGOOD")
			(options
				(clearance outline)
				(anchor circle)
			)
			(primitives
				(gr_poly
					(pts
						(arc
							(start -0.1778 -0.2794)
							(mid -0.249642 -0.249642)
							(end -0.2794 -0.1778)
						)
						(arc
							(start -0.2794 0.1778)
							(mid -0.249642 0.249642)
							(end -0.1778 0.2794)
						)
						(arc
							(start 0.1778 0.2794)
							(mid 0.249642 0.249642)
							(end 0.2794 0.1778)
						)
						(arc
							(start 0.2794 -0.1778)
							(mid 0.249642 -0.249642)
							(end 0.1778 -0.2794)
						)
					)
					(width 0)
					(fill yes)
				)
			)
		)
	)
	(footprint ""
		(layer "F.Cu")
		(at 65.83553 -14.990826 90)
		(property "Reference" "VIA51"
			(at 0 0 90)
			(layer "F.SilkS")
			(hide yes)
			(effects
				(font
					(size 1.27 1.27)
				)
			)
		)
		(property "Value" "100OHM-8L-2D36MM-L18-GP"
			(at 3.8989 0.5715 90)
			(unlocked yes)
			(layer "F.Fab")
			(hide yes)
			(effects
				(font
					(size 1.016 1.016)
					(thickness 0.1524)
				)
			)
		)
		(property "Device Type" "VIA-PCIE-4P-414097"
			(at 3.8989 -0.9525 90)
			(unlocked yes)
			(layer "F.Fab")
			(hide yes)
			(effects
				(font
					(size 1.016 1.016)
					(thickness 0.1524)
				)
			)
		)
		(duplicate_pad_numbers_are_jumpers no)
		(fp_rect
			(start -2.0701 0.4826)
			(end 2.0701 -0.4826)
			(stroke
				(width 0)
				(type default)
			)
			(fill no)
			(layer "F.CrtYd")
		)
		(fp_rect
			(start -2.0701 0.4826)
			(end 2.0701 -0.4826)
			(stroke
				(width 0)
				(type default)
			)
			(fill no)
			(layer "F.Fab")
		)
		(pad "1" thru_hole circle
			(at -1.5875 0 90)
			(size 0.508 0.508)
			(drill 0.254)
			(layers "*.Cu" "*.Mask")
			(remove_unused_layers no)
			(net "GND")
			(clearance 0.2286)
			(thermal_gap 0.2286)
		)
		(pad "2" thru_hole circle
			(at -0.5715 0 90)
			(size 0.508 0.508)
			(drill 0.254)
			(layers "*.Cu" "*.Mask")
			(remove_unused_layers no)
			(net "PHY_SCC_B_TO_DRV_B_25_DP")
			(clearance 0.2286)
			(thermal_gap 0.2286)
		)
		(pad "3" thru_hole circle
			(at 0.5715 0 90)
			(size 0.508 0.508)
			(drill 0.254)
			(layers "*.Cu" "*.Mask")
			(remove_unused_layers no)
			(net "PHY_SCC_B_TO_DRV_B_25_DN")
			(clearance 0.2286)
			(thermal_gap 0.2286)
		)
		(pad "4" thru_hole circle
			(at 1.5875 0 90)
			(size 0.508 0.508)
			(drill 0.254)
			(layers "*.Cu" "*.Mask")
			(remove_unused_layers no)
			(net "GND")
			(clearance 0.2286)
			(thermal_gap 0.2286)
		)
	)
	(footprint ""
		(layer "F.Cu")
		(at 314.0964 -340.812882 180)
		(property "Reference" "R105"
			(at 0 0 180)
			(layer "F.SilkS")
			(hide yes)
			(effects
				(font
					(size 1.27 1.27)
				)
			)
		)
		(property "Value" "4K7R2F-GP"
			(at 0.064008 -3.993896 180)
			(unlocked yes)
			(layer "F.Fab")
			(hide yes)
			(effects
				(font
					(size 1.016 1.016)
					(thickness 0.1524)
				)
			)
		)
		(property "Device Type" "R402H16"
			(at 0.064008 -5.517896 180)
			(unlocked yes)
			(layer "F.Fab")
			(hide yes)
			(effects
				(font
					(size 1.016 1.016)
					(thickness 0.1524)
				)
			)
		)
		(duplicate_pad_numbers_are_jumpers no)
		(fp_line
			(start 0.508 -0.9398)
			(end -0.508 -0.9398)
			(stroke
				(width 0.1524)
				(type default)
			)
			(layer "F.SilkS")
		)
		(fp_line
			(start -0.508 -0.9398)
			(end -0.508 0.9398)
			(stroke
				(width 0.1524)
				(type default)
			)
			(layer "F.SilkS")
		)
		(fp_rect
			(start -0.508 0.9398)
			(end 0.508 -0.9398)
			(stroke
				(width 0)
				(type default)
			)
			(fill no)
			(layer "F.CrtYd")
		)
		(fp_rect
			(start -0.508 0.9398)
			(end 0.508 -0.9398)
			(stroke
				(width 0)
				(type default)
			)
			(fill no)
			(layer "F.Fab")
		)
		(pad "1" smd custom
			(at 0 -0.4445 180)
			(size 0.1397 0.1397)
			(layers "F.Cu" "F.Mask" "F.Paste")
			(net "PWM_CAMP_SEL2")
			(options
				(clearance outline)
				(anchor circle)
			)
			(primitives
				(gr_poly
					(pts
						(arc
							(start -0.1778 -0.2794)
							(mid -0.249642 -0.249642)
							(end -0.2794 -0.1778)
						)
						(arc
							(start -0.2794 0.1778)
							(mid -0.249642 0.249642)
							(end -0.1778 0.2794)
						)
						(arc
							(start 0.1778 0.2794)
							(mid 0.249642 0.249642)
							(end 0.2794 0.1778)
						)
						(arc
							(start 0.2794 -0.1778)
							(mid 0.249642 -0.249642)
							(end 0.1778 -0.2794)
						)
					)
					(width 0)
					(fill yes)
				)
			)
		)
		(pad "2" smd custom
			(at 0 0.4445 180)
			(size 0.1397 0.1397)
			(layers "F.Cu" "F.Mask" "F.Paste")
			(net "GND")
			(options
				(clearance outline)
				(anchor circle)
			)
			(primitives
				(gr_poly
					(pts
						(arc
							(start -0.1778 -0.2794)
							(mid -0.249642 -0.249642)
							(end -0.2794 -0.1778)
						)
						(arc
							(start -0.2794 0.1778)
							(mid -0.249642 0.249642)
							(end -0.1778 0.2794)
						)
						(arc
							(start 0.1778 0.2794)
							(mid 0.249642 0.249642)
							(end 0.2794 0.1778)
						)
						(arc
							(start 0.2794 -0.1778)
							(mid 0.249642 -0.249642)
							(end 0.1778 -0.2794)
						)
					)
					(width 0)
					(fill yes)
				)
			)
		)
	)
	(footprint ""
		(layer "F.Cu")
		(at 319.786 -128.627124 180)
		(property "Reference" "VIA37"
			(at 0 0 180)
			(layer "F.SilkS")
			(hide yes)
			(effects
				(font
					(size 1.27 1.27)
				)
			)
		)
		(property "Value" "100OHM-8L-2D36MM-L18-GP"
			(at 3.8989 0.5715 180)
			(unlocked yes)
			(layer "F.Fab")
			(hide yes)
			(effects
				(font
					(size 1.016 1.016)
					(thickness 0.1524)
				)
			)
		)
		(property "Device Type" "VIA-PCIE-4P-414097"
			(at 3.8989 -0.9525 180)
			(unlocked yes)
			(layer "F.Fab")
			(hide yes)
			(effects
				(font
					(size 1.016 1.016)
					(thickness 0.1524)
				)
			)
		)
		(duplicate_pad_numbers_are_jumpers no)
		(fp_rect
			(start -2.0701 0.4826)
			(end 2.0701 -0.4826)
			(stroke
				(width 0)
				(type default)
			)
			(fill no)
			(layer "F.CrtYd")
		)
		(fp_rect
			(start -2.0701 0.4826)
			(end 2.0701 -0.4826)
			(stroke
				(width 0)
				(type default)
			)
			(fill no)
			(layer "F.Fab")
		)
		(pad "1" thru_hole circle
			(at -1.5875 0 180)
			(size 0.508 0.508)
			(drill 0.254)
			(layers "*.Cu" "*.Mask")
			(remove_unused_layers no)
			(net "GND")
			(clearance 0.2286)
			(thermal_gap 0.2286)
		)
		(pad "2" thru_hole circle
			(at -0.5715 0 180)
			(size 0.508 0.508)
			(drill 0.254)
			(layers "*.Cu" "*.Mask")
			(remove_unused_layers no)
			(net "PHY_SCC_B_TO_DRV_B_18_DP")
			(clearance 0.2286)
			(thermal_gap 0.2286)
		)
		(pad "3" thru_hole circle
			(at 0.5715 0 180)
			(size 0.508 0.508)
			(drill 0.254)
			(layers "*.Cu" "*.Mask")
			(remove_unused_layers no)
			(net "PHY_SCC_B_TO_DRV_B_18_DN")
			(clearance 0.2286)
			(thermal_gap 0.2286)
		)
		(pad "4" thru_hole circle
			(at 1.5875 0 180)
			(size 0.508 0.508)
			(drill 0.254)
			(layers "*.Cu" "*.Mask")
			(remove_unused_layers no)
			(net "GND")
			(clearance 0.2286)
			(thermal_gap 0.2286)
		)
	)
	(footprint ""
		(layer "F.Cu")
		(at 141.097 -25.527 90)
		(property "Reference" "C403"
			(at 0 0 90)
			(layer "F.SilkS")
			(hide yes)
			(effects
				(font
					(size 1.27 1.27)
				)
			)
		)
		(property "Value" "SCD033U25V2KX-GP"
			(at 1.1811 -2.7051 90)
			(unlocked yes)
			(layer "F.Fab")
			(hide yes)
			(effects
				(font
					(size 1.016 1.016)
					(thickness 0.1524)
				)
			)
		)
		(property "Device Type" "C402H22"
			(at 1.1811 -4.2291 90)
			(unlocked yes)
			(layer "F.Fab")
			(hide yes)
			(effects
				(font
					(size 1.016 1.016)
					(thickness 0.1524)
				)
			)
		)
		(duplicate_pad_numbers_are_jumpers no)
		(fp_rect
			(start -0.4318 0.9525)
			(end 0.4318 -0.9525)
			(stroke
				(width 0)
				(type default)
			)
			(fill no)
			(layer "F.CrtYd")
		)
		(fp_rect
			(start -0.4318 0.9525)
			(end 0.4318 -0.9525)
			(stroke
				(width 0)
				(type default)
			)
			(fill no)
			(layer "F.Fab")
		)
		(pad "1" smd custom
			(at 0 -0.4445 90)
			(size 0.1524 0.1524)
			(layers "F.Cu" "F.Mask" "F.Paste")
			(net "P12V_B")
			(options
				(clearance outline)
				(anchor circle)
			)
			(primitives
				(gr_poly
					(pts
						(arc
							(start 0.3048 -0.2032)
							(mid 0.275042 -0.275042)
							(end 0.2032 -0.3048)
						)
						(arc
							(start -0.2032 -0.3048)
							(mid -0.275042 -0.275042)
							(end -0.3048 -0.2032)
						)
						(arc
							(start -0.3048 0.2032)
							(mid -0.275042 0.275042)
							(end -0.2032 0.3048)
						)
						(arc
							(start 0.2032 0.3048)
							(mid 0.275042 0.275042)
							(end 0.3048 0.2032)
						)
					)
					(width 0)
					(fill yes)
				)
			)
		)
		(pad "2" smd custom
			(at 0 0.4445 90)
			(size 0.1524 0.1524)
			(layers "F.Cu" "F.Mask" "F.Paste")
			(net "SW_HDD_N28")
			(options
				(clearance outline)
				(anchor circle)
			)
			(primitives
				(gr_poly
					(pts
						(arc
							(start 0.3048 -0.2032)
							(mid 0.275042 -0.275042)
							(end 0.2032 -0.3048)
						)
						(arc
							(start -0.2032 -0.3048)
							(mid -0.275042 -0.275042)
							(end -0.3048 -0.2032)
						)
						(arc
							(start -0.3048 0.2032)
							(mid -0.275042 0.275042)
							(end -0.2032 0.3048)
						)
						(arc
							(start 0.2032 0.3048)
							(mid 0.275042 0.275042)
							(end 0.3048 0.2032)
						)
					)
					(width 0)
					(fill yes)
				)
			)
		)
	)
	(footprint ""
		(layer "F.Cu")
		(at 378.249942 -65.39992)
		(property "Reference" "LED21"
			(at 0 0 0)
			(layer "F.SilkS")
			(hide yes)
			(effects
				(font
					(size 1.27 1.27)
				)
			)
		)
		(property "Value" "LED-BY-19-GP"
			(at -2.132076 1.414018 0)
			(unlocked yes)
			(layer "F.Fab")
			(hide yes)
			(effects
				(font
					(size 1.016 1.016)
					(thickness 0.1524)
				)
			)
		)
		(property "Device Type" "LED-1615-4PH26"
			(at -2.132076 -0.109982 0)
			(unlocked yes)
			(layer "F.Fab")
			(hide yes)
			(effects
				(font
					(size 1.016 1.016)
					(thickness 0.1524)
				)
			)
		)
		(duplicate_pad_numbers_are_jumpers no)
		(fp_line
			(start -1.2954 0.254)
			(end -1.2954 1.6002)
			(stroke
				(width 0.508)
				(type default)
			)
			(layer "F.SilkS")
		)
		(fp_line
			(start -1.2954 1.6002)
			(end 1.2954 1.6002)
			(stroke
				(width 0.508)
				(type default)
			)
			(layer "F.SilkS")
		)
		(fp_line
			(start -1.1176 -1.4224)
			(end 1.1176 -1.4224)
			(stroke
				(width 0.1524)
				(type default)
			)
			(layer "F.SilkS")
		)
		(fp_line
			(start -1.1176 1.4224)
			(end -1.1176 -1.4224)
			(stroke
				(width 0.1524)
				(type default)
			)
			(layer "F.SilkS")
		)
		(fp_line
			(start 1.1176 -1.4224)
			(end 1.1176 1.4224)
			(stroke
				(width 0.1524)
				(type default)
			)
			(layer "F.SilkS")
		)
		(fp_line
			(start 1.1176 1.4224)
			(end -1.1176 1.4224)
			(stroke
				(width 0.1524)
				(type default)
			)
			(layer "F.SilkS")
		)
		(fp_line
			(start 1.2954 1.6002)
			(end 1.2954 0.254)
			(stroke
				(width 0.508)
				(type default)
			)
			(layer "F.SilkS")
		)
		(fp_rect
			(start -0.7493 0.8001)
			(end 0.7493 -0.8001)
			(stroke
				(width 0)
				(type default)
			)
			(fill no)
			(layer "F.CrtYd")
		)
		(fp_poly
			(pts
				(xy -1.3716 1.6764) (xy -1.3716 -1.6764) (xy 1.3716 -1.6764) (xy 1.3716 0.0635) (xy 0.7493 0.0635)
				(xy 0.7493 -0.8001) (xy -0.7493 -0.8001) (xy -0.7493 0.8001) (xy 0.7493 0.8001) (xy 0.7493 0.0762)
				(xy 1.3716 0.0762) (xy 1.3716 1.6764)
			)
			(stroke
				(width 0)
				(type default)
			)
			(fill no)
			(layer "F.CrtYd")
		)
		(fp_rect
			(start -1.3716 1.6764)
			(end 1.3716 -1.6764)
			(stroke
				(width 0)
				(type default)
			)
			(fill no)
			(layer "F.Fab")
		)
		(pad "1" smd rect
			(at 0.50038 -0.73025)
			(size 0.7112 0.8636)
			(layers "F.Cu" "F.Mask" "F.Paste")
			(net "DRV_ACT_20")
		)
		(pad "2" smd rect
			(at -0.50038 -0.73025)
			(size 0.7112 0.8636)
			(layers "F.Cu" "F.Mask" "F.Paste")
			(net "FLT_HDD20")
		)
		(pad "3" smd rect
			(at 0.50038 0.73025)
			(size 0.7112 0.8636)
			(layers "F.Cu" "F.Mask" "F.Paste")
			(net "DRV_ACT_20_N")
		)
		(pad "4" smd rect
			(at -0.50038 0.73025)
			(size 0.7112 0.8636)
			(layers "F.Cu" "F.Mask" "F.Paste")
			(net "FLT_HDD20_N")
		)
	)
	(footprint ""
		(layer "F.Cu")
		(at 181.356 -11.049 180)
		(property "Reference" "R751"
			(at 0 0 180)
			(layer "F.SilkS")
			(hide yes)
			(effects
				(font
					(size 1.27 1.27)
				)
			)
		)
		(property "Value" "4K7R2J-2-GP"
			(at 0.064008 -3.993896 180)
			(unlocked yes)
			(layer "F.Fab")
			(hide yes)
			(effects
				(font
					(size 1.016 1.016)
					(thickness 0.1524)
				)
			)
		)
		(property "Device Type" "R402H16"
			(at 0.064008 -5.517896 180)
			(unlocked yes)
			(layer "F.Fab")
			(hide yes)
			(effects
				(font
					(size 1.016 1.016)
					(thickness 0.1524)
				)
			)
		)
		(duplicate_pad_numbers_are_jumpers no)
		(fp_line
			(start 0.508 -0.9398)
			(end -0.508 -0.9398)
			(stroke
				(width 0.1524)
				(type default)
			)
			(layer "F.SilkS")
		)
		(fp_line
			(start -0.508 -0.9398)
			(end -0.508 0.9398)
			(stroke
				(width 0.1524)
				(type default)
			)
			(layer "F.SilkS")
		)
		(fp_rect
			(start -0.508 0.9398)
			(end 0.508 -0.9398)
			(stroke
				(width 0)
				(type default)
			)
			(fill no)
			(layer "F.CrtYd")
		)
		(fp_rect
			(start -0.508 0.9398)
			(end 0.508 -0.9398)
			(stroke
				(width 0)
				(type default)
			)
			(fill no)
			(layer "F.Fab")
		)
		(pad "1" smd custom
			(at 0 -0.4445 180)
			(size 0.1397 0.1397)
			(layers "F.Cu" "F.Mask" "F.Paste")
			(net "P12V_B")
			(options
				(clearance outline)
				(anchor circle)
			)
			(primitives
				(gr_poly
					(pts
						(arc
							(start -0.1778 -0.2794)
							(mid -0.249642 -0.249642)
							(end -0.2794 -0.1778)
						)
						(arc
							(start -0.2794 0.1778)
							(mid -0.249642 0.249642)
							(end -0.1778 0.2794)
						)
						(arc
							(start 0.1778 0.2794)
							(mid 0.249642 0.249642)
							(end 0.2794 0.1778)
						)
						(arc
							(start 0.2794 -0.1778)
							(mid 0.249642 -0.249642)
							(end 0.1778 -0.2794)
						)
					)
					(width 0)
					(fill yes)
				)
			)
		)
		(pad "2" smd custom
			(at 0 0.4445 180)
			(size 0.1397 0.1397)
			(layers "F.Cu" "F.Mask" "F.Paste")
			(net "SW_HDD_R29")
			(options
				(clearance outline)
				(anchor circle)
			)
			(primitives
				(gr_poly
					(pts
						(arc
							(start -0.1778 -0.2794)
							(mid -0.249642 -0.249642)
							(end -0.2794 -0.1778)
						)
						(arc
							(start -0.2794 0.1778)
							(mid -0.249642 0.249642)
							(end -0.1778 0.2794)
						)
						(arc
							(start 0.1778 0.2794)
							(mid 0.249642 0.249642)
							(end 0.2794 0.1778)
						)
						(arc
							(start 0.2794 -0.1778)
							(mid 0.249642 -0.249642)
							(end 0.1778 -0.2794)
						)
					)
					(width 0)
					(fill yes)
				)
			)
		)
	)
	(footprint ""
		(layer "F.Cu")
		(at 336.677 -33.02)
		(property "Reference" "Q156"
			(at 0 0 0)
			(layer "F.SilkS")
			(hide yes)
			(effects
				(font
					(size 1.27 1.27)
				)
			)
		)
		(property "Value" "AO4407AL-GP"
			(at -3.707384 -1.5367 0)
			(unlocked yes)
			(layer "F.Fab")
			(hide yes)
			(effects
				(font
					(size 1.016 1.016)
					(thickness 0.1524)
				)
			)
		)
		(property "Device Type" "SOIC8H69"
			(at -3.707384 -3.0607 0)
			(unlocked yes)
			(layer "F.Fab")
			(hide yes)
			(effects
				(font
					(size 1.016 1.016)
					(thickness 0.1524)
				)
			)
		)
		(duplicate_pad_numbers_are_jumpers no)
		(fp_line
			(start -2.7432 -1.4224)
			(end -2.7432 1.4224)
			(stroke
				(width 0.1524)
				(type default)
			)
			(layer "F.SilkS")
		)
		(fp_line
			(start -2.7432 1.4224)
			(end -2.6416 1.4224)
			(stroke
				(width 0.1524)
				(type default)
			)
			(layer "F.SilkS")
		)
		(fp_line
			(start -2.7432 1.4224)
			(end 2.1336 1.4224)
			(stroke
				(width 0.1524)
				(type default)
			)
			(layer "F.SilkS")
		)
		(fp_line
			(start -2.7178 -0.508)
			(end -2.1844 -0.0508)
			(stroke
				(width 0.1524)
				(type default)
			)
			(layer "F.SilkS")
		)
		(fp_line
			(start -2.6289 3.4417)
			(end -2.6289 1.4732)
			(stroke
				(width 0.381)
				(type default)
			)
			(layer "F.SilkS")
		)
		(fp_line
			(start -2.1844 -0.0508)
			(end -2.7178 0.508)
			(stroke
				(width 0.1524)
				(type default)
			)
			(layer "F.SilkS")
		)
		(fp_line
			(start 2.1336 -1.4224)
			(end -2.7432 -1.4224)
			(stroke
				(width 0.1524)
				(type default)
			)
			(layer "F.SilkS")
		)
		(fp_line
			(start 2.1336 1.4224)
			(end 2.1336 -1.4224)
			(stroke
				(width 0.1524)
				(type default)
			)
			(layer "F.SilkS")
		)
		(fp_poly
			(pts
				(xy -2.2098 -1.4224) (xy -2.2098 1.4224) (xy 2.2098 1.4224) (xy 2.2098 -1.4224)
			)
			(stroke
				(width 0)
				(type default)
			)
			(fill yes)
			(layer "F.SilkS")
		)
		(fp_rect
			(start -2.450084 2.999994)
			(end 2.450084 -2.999994)
			(stroke
				(width 0)
				(type default)
			)
			(fill no)
			(layer "F.CrtYd")
		)
		(fp_poly
			(pts
				(xy -2.8194 3.6322) (xy -2.8194 -3.6322) (xy 2.8194 -3.6322) (xy 2.8194 1.18364) (xy 2.450084 1.18364)
				(xy 2.450084 -2.999994) (xy -2.450084 -2.999994) (xy -2.450084 2.999994) (xy 2.450084 2.999994)
				(xy 2.450084 1.18618) (xy 2.8194 1.18618) (xy 2.8194 3.6322)
			)
			(stroke
				(width 0)
				(type default)
			)
			(fill no)
			(layer "F.CrtYd")
		)
		(fp_rect
			(start -2.8194 3.6322)
			(end 2.8194 -3.6322)
			(stroke
				(width 0)
				(type default)
			)
			(fill no)
			(layer "F.Fab")
		)
		(pad "1" smd rect
			(at -1.905 2.54)
			(size 0.635 1.651)
			(layers "F.Cu" "F.Mask" "F.Paste")
			(net "P12V_B")
		)
		(pad "2" smd rect
			(at -0.635 2.54)
			(size 0.635 1.651)
			(layers "F.Cu" "F.Mask" "F.Paste")
			(net "P12V_B")
		)
		(pad "3" smd rect
			(at 0.635 2.54)
			(size 0.635 1.651)
			(layers "F.Cu" "F.Mask" "F.Paste")
			(net "P12V_B")
		)
		(pad "4" smd rect
			(at 1.905 2.54)
			(size 0.635 1.651)
			(layers "F.Cu" "F.Mask" "F.Paste")
			(net "SW_HDD_N30")
		)
		(pad "5" smd rect
			(at 1.905 -2.54)
			(size 0.635 1.651)
			(layers "F.Cu" "F.Mask" "F.Paste")
			(net "P12V_HDD30")
		)
		(pad "6" smd rect
			(at 0.635 -2.54)
			(size 0.635 1.651)
			(layers "F.Cu" "F.Mask" "F.Paste")
			(net "P12V_HDD30")
		)
		(pad "7" smd rect
			(at -0.635 -2.54)
			(size 0.635 1.651)
			(layers "F.Cu" "F.Mask" "F.Paste")
			(net "P12V_HDD30")
		)
		(pad "8" smd rect
			(at -1.905 -2.54)
			(size 0.635 1.651)
			(layers "F.Cu" "F.Mask" "F.Paste")
			(net "P12V_HDD30")
		)
	)
	(footprint ""
		(layer "F.Cu")
		(at 105.407968 -214.784178 90)
		(property "Reference" "Q246"
			(at 0 0 90)
			(layer "F.SilkS")
			(hide yes)
			(effects
				(font
					(size 1.27 1.27)
				)
			)
		)
		(property "Value" "SSM3K324R-GP"
			(at 0.127 -8.9662 90)
			(unlocked yes)
			(layer "F.Fab")
			(hide yes)
			(effects
				(font
					(size 1.016 1.016)
					(thickness 0.1524)
				)
			)
		)
		(property "Device Type" "SOT23DGS2D4H35"
			(at 0.127 -10.4902 90)
			(unlocked yes)
			(layer "F.Fab")
			(hide yes)
			(effects
				(font
					(size 1.016 1.016)
					(thickness 0.1524)
				)
			)
		)
		(duplicate_pad_numbers_are_jumpers no)
		(fp_line
			(start 1.651 -1.778)
			(end -1.651 -1.778)
			(stroke
				(width 0.1524)
				(type default)
			)
			(layer "F.SilkS")
		)
		(fp_line
			(start -1.651 -1.778)
			(end -1.651 1.778)
			(stroke
				(width 0.1524)
				(type default)
			)
			(layer "F.SilkS")
		)
		(fp_line
			(start 1.651 1.778)
			(end 1.651 -1.778)
			(stroke
				(width 0.1524)
				(type default)
			)
			(layer "F.SilkS")
		)
		(fp_line
			(start -1.651 1.778)
			(end 1.651 1.778)
			(stroke
				(width 0.1524)
				(type default)
			)
			(layer "F.SilkS")
		)
		(fp_poly
			(pts
				(xy -1.778 1.8796) (xy -1.778 -1.8796) (xy 1.778 -1.8796) (xy 1.778 1.8796)
			)
			(stroke
				(width 0)
				(type default)
			)
			(fill no)
			(layer "F.CrtYd")
		)
		(fp_poly
			(pts
				(xy -1.778 1.8796) (xy -1.778 -1.8796) (xy 1.778 -1.8796) (xy 1.778 1.8796)
			)
			(stroke
				(width 0)
				(type default)
			)
			(fill no)
			(layer "F.Fab")
		)
		(pad "D" smd custom
			(at 0 -0.9525 90)
			(size 0.1905 0.1905)
			(layers "F.Cu" "F.Mask" "F.Paste")
			(net "DRV_ACT_3_N")
			(options
				(clearance outline)
				(anchor circle)
			)
			(primitives
				(gr_poly
					(pts
						(arc
							(start -0.1778 0.5715)
							(mid -0.321484 0.511984)
							(end -0.381 0.3683)
						)
						(arc
							(start -0.381 -0.3683)
							(mid -0.321484 -0.511984)
							(end -0.1778 -0.5715)
						)
						(arc
							(start 0.1778 -0.5715)
							(mid 0.321484 -0.511984)
							(end 0.381 -0.3683)
						)
						(arc
							(start 0.381 0.3683)
							(mid 0.321484 0.511984)
							(end 0.1778 0.5715)
						)
					)
					(width 0)
					(fill yes)
				)
			)
		)
		(pad "G" smd custom
			(at -0.98425 0.9525 90)
			(size 0.1905 0.1905)
			(layers "F.Cu" "F.Mask" "F.Paste")
			(net "DRIVE_B_3_ACT")
			(options
				(clearance outline)
				(anchor circle)
			)
			(primitives
				(gr_poly
					(pts
						(arc
							(start -0.1778 0.5715)
							(mid -0.321484 0.511984)
							(end -0.381 0.3683)
						)
						(arc
							(start -0.381 -0.3683)
							(mid -0.321484 -0.511984)
							(end -0.1778 -0.5715)
						)
						(arc
							(start 0.1778 -0.5715)
							(mid 0.321484 -0.511984)
							(end 0.381 -0.3683)
						)
						(arc
							(start 0.381 0.3683)
							(mid 0.321484 0.511984)
							(end 0.1778 0.5715)
						)
					)
					(width 0)
					(fill yes)
				)
			)
		)
		(pad "S" smd custom
			(at 0.98425 0.9525 90)
			(size 0.1905 0.1905)
			(layers "F.Cu" "F.Mask" "F.Paste")
			(net "GND")
			(options
				(clearance outline)
				(anchor circle)
			)
			(primitives
				(gr_poly
					(pts
						(arc
							(start -0.1778 0.5715)
							(mid -0.321484 0.511984)
							(end -0.381 0.3683)
						)
						(arc
							(start -0.381 -0.3683)
							(mid -0.321484 -0.511984)
							(end -0.1778 -0.5715)
						)
						(arc
							(start 0.1778 -0.5715)
							(mid 0.321484 -0.511984)
							(end 0.381 -0.3683)
						)
						(arc
							(start 0.381 0.3683)
							(mid 0.321484 0.511984)
							(end 0.1778 0.5715)
						)
					)
					(width 0)
					(fill yes)
				)
			)
		)
	)
	(footprint ""
		(layer "F.Cu")
		(at 353.184714 -129.66065 -90)
		(property "Reference" "C276"
			(at 0 0 270)
			(layer "F.SilkS")
			(hide yes)
			(effects
				(font
					(size 1.27 1.27)
				)
			)
		)
		(property "Value" "SCD01U16V1KX-GP"
			(at -2.8321 -1.7399 270)
			(unlocked yes)
			(layer "F.Fab")
			(hide yes)
			(effects
				(font
					(size 1.016 1.016)
					(thickness 0.1524)
				)
			)
		)
		(property "Device Type" "C0201H13"
			(at -2.8321 -3.2639 270)
			(unlocked yes)
			(layer "F.Fab")
			(hide yes)
			(effects
				(font
					(size 1.016 1.016)
					(thickness 0.1524)
				)
			)
		)
		(duplicate_pad_numbers_are_jumpers no)
		(fp_rect
			(start -0.2794 0.6477)
			(end 0.2794 -0.6477)
			(stroke
				(width 0)
				(type default)
			)
			(fill no)
			(layer "F.CrtYd")
		)
		(fp_rect
			(start -0.2794 0.6477)
			(end 0.2794 -0.6477)
			(stroke
				(width 0)
				(type default)
			)
			(fill no)
			(layer "F.Fab")
		)
		(pad "1" smd custom
			(at 0 -0.2794 270)
			(size 0.0762 0.0762)
			(layers "F.Cu" "F.Mask" "F.Paste")
			(net "SAS_HDD_RX_P19")
			(options
				(clearance outline)
				(anchor circle)
			)
			(primitives
				(gr_poly
					(pts
						(arc
							(start 0.1524 -0.127)
							(mid 0.137521 -0.162921)
							(end 0.1016 -0.1778)
						)
						(arc
							(start -0.1016 -0.1778)
							(mid -0.137521 -0.162921)
							(end -0.1524 -0.127)
						)
						(arc
							(start -0.1524 0.127)
							(mid -0.137521 0.162921)
							(end -0.1016 0.1778)
						)
						(arc
							(start 0.1016 0.1778)
							(mid 0.137521 0.162921)
							(end 0.1524 0.127)
						)
					)
					(width 0)
					(fill yes)
				)
			)
		)
		(pad "2" smd custom
			(at 0 0.2794 270)
			(size 0.0762 0.0762)
			(layers "F.Cu" "F.Mask" "F.Paste")
			(net "PHY_SCC_B_TO_DRV_B_19_DP")
			(options
				(clearance outline)
				(anchor circle)
			)
			(primitives
				(gr_poly
					(pts
						(arc
							(start 0.1524 -0.127)
							(mid 0.137521 -0.162921)
							(end 0.1016 -0.1778)
						)
						(arc
							(start -0.1016 -0.1778)
							(mid -0.137521 -0.162921)
							(end -0.1524 -0.127)
						)
						(arc
							(start -0.1524 0.127)
							(mid -0.137521 0.162921)
							(end -0.1016 0.1778)
						)
						(arc
							(start 0.1016 0.1778)
							(mid 0.137521 0.162921)
							(end 0.1524 0.127)
						)
					)
					(width 0)
					(fill yes)
				)
			)
		)
	)
	(footprint ""
		(layer "F.Cu")
		(at 140.7414 -99.7712 180)
		(property "Reference" "Q235"
			(at 0 0 180)
			(layer "F.SilkS")
			(hide yes)
			(effects
				(font
					(size 1.27 1.27)
				)
			)
		)
		(property "Value" "2N7002K-2-GP"
			(at 0.127 -8.9662 180)
			(unlocked yes)
			(layer "F.Fab")
			(hide yes)
			(effects
				(font
					(size 1.016 1.016)
					(thickness 0.1524)
				)
			)
		)
		(property "Device Type" "SOT23DGS2D4H44"
			(at 0.127 -10.4902 180)
			(unlocked yes)
			(layer "F.Fab")
			(hide yes)
			(effects
				(font
					(size 1.016 1.016)
					(thickness 0.1524)
				)
			)
		)
		(duplicate_pad_numbers_are_jumpers no)
		(fp_line
			(start 1.651 1.778)
			(end 1.651 -1.778)
			(stroke
				(width 0.1524)
				(type default)
			)
			(layer "F.SilkS")
		)
		(fp_line
			(start 1.651 -1.778)
			(end -1.651 -1.778)
			(stroke
				(width 0.1524)
				(type default)
			)
			(layer "F.SilkS")
		)
		(fp_line
			(start -1.651 1.778)
			(end 1.651 1.778)
			(stroke
				(width 0.1524)
				(type default)
			)
			(layer "F.SilkS")
		)
		(fp_line
			(start -1.651 -1.778)
			(end -1.651 1.778)
			(stroke
				(width 0.1524)
				(type default)
			)
			(layer "F.SilkS")
		)
		(fp_poly
			(pts
				(xy -1.778 1.8796) (xy -1.778 -1.8796) (xy 1.778 -1.8796) (xy 1.778 1.8796)
			)
			(stroke
				(width 0)
				(type default)
			)
			(fill no)
			(layer "F.CrtYd")
		)
		(fp_poly
			(pts
				(xy -1.778 1.8796) (xy -1.778 -1.8796) (xy 1.778 -1.8796) (xy 1.778 1.8796)
			)
			(stroke
				(width 0)
				(type default)
			)
			(fill no)
			(layer "F.Fab")
		)
		(pad "D" smd custom
			(at 0 -0.9525 180)
			(size 0.1905 0.1905)
			(layers "F.Cu" "F.Mask" "F.Paste")
			(net "FLT_HDD16_N")
			(options
				(clearance outline)
				(anchor circle)
			)
			(primitives
				(gr_poly
					(pts
						(arc
							(start -0.1778 0.5715)
							(mid -0.321484 0.511984)
							(end -0.381 0.3683)
						)
						(arc
							(start -0.381 -0.3683)
							(mid -0.321484 -0.511984)
							(end -0.1778 -0.5715)
						)
						(arc
							(start 0.1778 -0.5715)
							(mid 0.321484 -0.511984)
							(end 0.381 -0.3683)
						)
						(arc
							(start 0.381 0.3683)
							(mid 0.321484 0.511984)
							(end 0.1778 0.5715)
						)
					)
					(width 0)
					(fill yes)
				)
			)
		)
		(pad "G" smd custom
			(at -0.98425 0.9525 180)
			(size 0.1905 0.1905)
			(layers "F.Cu" "F.Mask" "F.Paste")
			(net "DRIVE_B_16_FLT_LED")
			(options
				(clearance outline)
				(anchor circle)
			)
			(primitives
				(gr_poly
					(pts
						(arc
							(start -0.1778 0.5715)
							(mid -0.321484 0.511984)
							(end -0.381 0.3683)
						)
						(arc
							(start -0.381 -0.3683)
							(mid -0.321484 -0.511984)
							(end -0.1778 -0.5715)
						)
						(arc
							(start 0.1778 -0.5715)
							(mid 0.321484 -0.511984)
							(end 0.381 -0.3683)
						)
						(arc
							(start 0.381 0.3683)
							(mid 0.321484 0.511984)
							(end 0.1778 0.5715)
						)
					)
					(width 0)
					(fill yes)
				)
			)
		)
		(pad "S" smd custom
			(at 0.98425 0.9525 180)
			(size 0.1905 0.1905)
			(layers "F.Cu" "F.Mask" "F.Paste")
			(net "GND")
			(options
				(clearance outline)
				(anchor circle)
			)
			(primitives
				(gr_poly
					(pts
						(arc
							(start -0.1778 0.5715)
							(mid -0.321484 0.511984)
							(end -0.381 0.3683)
						)
						(arc
							(start -0.381 -0.3683)
							(mid -0.321484 -0.511984)
							(end -0.1778 -0.5715)
						)
						(arc
							(start 0.1778 -0.5715)
							(mid 0.321484 -0.511984)
							(end 0.381 -0.3683)
						)
						(arc
							(start 0.381 0.3683)
							(mid 0.321484 0.511984)
							(end 0.1778 0.5715)
						)
					)
					(width 0)
					(fill yes)
				)
			)
		)
	)
	(footprint ""
		(layer "F.Cu")
		(at 127.113284 -245.219474 90)
		(property "Reference" "C67"
			(at 0 0 90)
			(layer "F.SilkS")
			(hide yes)
			(effects
				(font
					(size 1.27 1.27)
				)
			)
		)
		(property "Value" "SCD01U16V1KX-GP"
			(at -2.8321 -1.7399 90)
			(unlocked yes)
			(layer "F.Fab")
			(hide yes)
			(effects
				(font
					(size 1.016 1.016)
					(thickness 0.1524)
				)
			)
		)
		(property "Device Type" "C0201H13"
			(at -2.8321 -3.2639 90)
			(unlocked yes)
			(layer "F.Fab")
			(hide yes)
			(effects
				(font
					(size 1.016 1.016)
					(thickness 0.1524)
				)
			)
		)
		(duplicate_pad_numbers_are_jumpers no)
		(fp_rect
			(start -0.2794 0.6477)
			(end 0.2794 -0.6477)
			(stroke
				(width 0)
				(type default)
			)
			(fill no)
			(layer "F.CrtYd")
		)
		(fp_rect
			(start -0.2794 0.6477)
			(end 0.2794 -0.6477)
			(stroke
				(width 0)
				(type default)
			)
			(fill no)
			(layer "F.Fab")
		)
		(pad "1" smd custom
			(at 0 -0.2794 90)
			(size 0.0762 0.0762)
			(layers "F.Cu" "F.Mask" "F.Paste")
			(net "SAS_HDD_RX_N3")
			(options
				(clearance outline)
				(anchor circle)
			)
			(primitives
				(gr_poly
					(pts
						(arc
							(start 0.1524 -0.127)
							(mid 0.137521 -0.162921)
							(end 0.1016 -0.1778)
						)
						(arc
							(start -0.1016 -0.1778)
							(mid -0.137521 -0.162921)
							(end -0.1524 -0.127)
						)
						(arc
							(start -0.1524 0.127)
							(mid -0.137521 0.162921)
							(end -0.1016 0.1778)
						)
						(arc
							(start 0.1016 0.1778)
							(mid 0.137521 0.162921)
							(end 0.1524 0.127)
						)
					)
					(width 0)
					(fill yes)
				)
			)
		)
		(pad "2" smd custom
			(at 0 0.2794 90)
			(size 0.0762 0.0762)
			(layers "F.Cu" "F.Mask" "F.Paste")
			(net "PHY_SCC_B_TO_DRV_B_3_DN")
			(options
				(clearance outline)
				(anchor circle)
			)
			(primitives
				(gr_poly
					(pts
						(arc
							(start 0.1524 -0.127)
							(mid 0.137521 -0.162921)
							(end 0.1016 -0.1778)
						)
						(arc
							(start -0.1016 -0.1778)
							(mid -0.137521 -0.162921)
							(end -0.1524 -0.127)
						)
						(arc
							(start -0.1524 0.127)
							(mid -0.137521 0.162921)
							(end -0.1016 0.1778)
						)
						(arc
							(start 0.1016 0.1778)
							(mid 0.137521 0.162921)
							(end 0.1524 0.127)
						)
					)
					(width 0)
					(fill yes)
				)
			)
		)
	)
	(footprint ""
		(layer "F.Cu")
		(at 51.7398 -99.7204 180)
		(property "Reference" "Q232"
			(at 0 0 180)
			(layer "F.SilkS")
			(hide yes)
			(effects
				(font
					(size 1.27 1.27)
				)
			)
		)
		(property "Value" "2N7002K-2-GP"
			(at 0.127 -8.9662 180)
			(unlocked yes)
			(layer "F.Fab")
			(hide yes)
			(effects
				(font
					(size 1.016 1.016)
					(thickness 0.1524)
				)
			)
		)
		(property "Device Type" "SOT23DGS2D4H44"
			(at 0.127 -10.4902 180)
			(unlocked yes)
			(layer "F.Fab")
			(hide yes)
			(effects
				(font
					(size 1.016 1.016)
					(thickness 0.1524)
				)
			)
		)
		(duplicate_pad_numbers_are_jumpers no)
		(fp_line
			(start 1.651 1.778)
			(end 1.651 -1.778)
			(stroke
				(width 0.1524)
				(type default)
			)
			(layer "F.SilkS")
		)
		(fp_line
			(start 1.651 -1.778)
			(end -1.651 -1.778)
			(stroke
				(width 0.1524)
				(type default)
			)
			(layer "F.SilkS")
		)
		(fp_line
			(start -1.651 1.778)
			(end 1.651 1.778)
			(stroke
				(width 0.1524)
				(type default)
			)
			(layer "F.SilkS")
		)
		(fp_line
			(start -1.651 -1.778)
			(end -1.651 1.778)
			(stroke
				(width 0.1524)
				(type default)
			)
			(layer "F.SilkS")
		)
		(fp_poly
			(pts
				(xy -1.778 1.8796) (xy -1.778 -1.8796) (xy 1.778 -1.8796) (xy 1.778 1.8796)
			)
			(stroke
				(width 0)
				(type default)
			)
			(fill no)
			(layer "F.CrtYd")
		)
		(fp_poly
			(pts
				(xy -1.778 1.8796) (xy -1.778 -1.8796) (xy 1.778 -1.8796) (xy 1.778 1.8796)
			)
			(stroke
				(width 0)
				(type default)
			)
			(fill no)
			(layer "F.Fab")
		)
		(pad "D" smd custom
			(at 0 -0.9525 180)
			(size 0.1905 0.1905)
			(layers "F.Cu" "F.Mask" "F.Paste")
			(net "FLT_HDD13_N")
			(options
				(clearance outline)
				(anchor circle)
			)
			(primitives
				(gr_poly
					(pts
						(arc
							(start -0.1778 0.5715)
							(mid -0.321484 0.511984)
							(end -0.381 0.3683)
						)
						(arc
							(start -0.381 -0.3683)
							(mid -0.321484 -0.511984)
							(end -0.1778 -0.5715)
						)
						(arc
							(start 0.1778 -0.5715)
							(mid 0.321484 -0.511984)
							(end 0.381 -0.3683)
						)
						(arc
							(start 0.381 0.3683)
							(mid 0.321484 0.511984)
							(end 0.1778 0.5715)
						)
					)
					(width 0)
					(fill yes)
				)
			)
		)
		(pad "G" smd custom
			(at -0.98425 0.9525 180)
			(size 0.1905 0.1905)
			(layers "F.Cu" "F.Mask" "F.Paste")
			(net "DRIVE_B_13_FLT_LED")
			(options
				(clearance outline)
				(anchor circle)
			)
			(primitives
				(gr_poly
					(pts
						(arc
							(start -0.1778 0.5715)
							(mid -0.321484 0.511984)
							(end -0.381 0.3683)
						)
						(arc
							(start -0.381 -0.3683)
							(mid -0.321484 -0.511984)
							(end -0.1778 -0.5715)
						)
						(arc
							(start 0.1778 -0.5715)
							(mid 0.321484 -0.511984)
							(end 0.381 -0.3683)
						)
						(arc
							(start 0.381 0.3683)
							(mid 0.321484 0.511984)
							(end 0.1778 0.5715)
						)
					)
					(width 0)
					(fill yes)
				)
			)
		)
		(pad "S" smd custom
			(at 0.98425 0.9525 180)
			(size 0.1905 0.1905)
			(layers "F.Cu" "F.Mask" "F.Paste")
			(net "GND")
			(options
				(clearance outline)
				(anchor circle)
			)
			(primitives
				(gr_poly
					(pts
						(arc
							(start -0.1778 0.5715)
							(mid -0.321484 0.511984)
							(end -0.381 0.3683)
						)
						(arc
							(start -0.381 -0.3683)
							(mid -0.321484 -0.511984)
							(end -0.1778 -0.5715)
						)
						(arc
							(start 0.1778 -0.5715)
							(mid 0.321484 -0.511984)
							(end 0.381 -0.3683)
						)
						(arc
							(start 0.381 0.3683)
							(mid 0.321484 0.511984)
							(end 0.1778 0.5715)
						)
					)
					(width 0)
					(fill yes)
				)
			)
		)
	)
	(footprint ""
		(layer "F.Cu")
		(at 190.213488 -130.21945 90)
		(property "Reference" "C249"
			(at 0 0 90)
			(layer "F.SilkS")
			(hide yes)
			(effects
				(font
					(size 1.27 1.27)
				)
			)
		)
		(property "Value" "SCD01U16V1KX-GP"
			(at -2.8321 -1.7399 90)
			(unlocked yes)
			(layer "F.Fab")
			(hide yes)
			(effects
				(font
					(size 1.016 1.016)
					(thickness 0.1524)
				)
			)
		)
		(property "Device Type" "C0201H13"
			(at -2.8321 -3.2639 90)
			(unlocked yes)
			(layer "F.Fab")
			(hide yes)
			(effects
				(font
					(size 1.016 1.016)
					(thickness 0.1524)
				)
			)
		)
		(duplicate_pad_numbers_are_jumpers no)
		(fp_rect
			(start -0.2794 0.6477)
			(end 0.2794 -0.6477)
			(stroke
				(width 0)
				(type default)
			)
			(fill no)
			(layer "F.CrtYd")
		)
		(fp_rect
			(start -0.2794 0.6477)
			(end 0.2794 -0.6477)
			(stroke
				(width 0)
				(type default)
			)
			(fill no)
			(layer "F.Fab")
		)
		(pad "1" smd custom
			(at 0 -0.2794 90)
			(size 0.0762 0.0762)
			(layers "F.Cu" "F.Mask" "F.Paste")
			(net "SAS_HDD_RX_N17")
			(options
				(clearance outline)
				(anchor circle)
			)
			(primitives
				(gr_poly
					(pts
						(arc
							(start 0.1524 -0.127)
							(mid 0.137521 -0.162921)
							(end 0.1016 -0.1778)
						)
						(arc
							(start -0.1016 -0.1778)
							(mid -0.137521 -0.162921)
							(end -0.1524 -0.127)
						)
						(arc
							(start -0.1524 0.127)
							(mid -0.137521 0.162921)
							(end -0.1016 0.1778)
						)
						(arc
							(start 0.1016 0.1778)
							(mid 0.137521 0.162921)
							(end 0.1524 0.127)
						)
					)
					(width 0)
					(fill yes)
				)
			)
		)
		(pad "2" smd custom
			(at 0 0.2794 90)
			(size 0.0762 0.0762)
			(layers "F.Cu" "F.Mask" "F.Paste")
			(net "PHY_SCC_B_TO_DRV_B_17_DN")
			(options
				(clearance outline)
				(anchor circle)
			)
			(primitives
				(gr_poly
					(pts
						(arc
							(start 0.1524 -0.127)
							(mid 0.137521 -0.162921)
							(end 0.1016 -0.1778)
						)
						(arc
							(start -0.1016 -0.1778)
							(mid -0.137521 -0.162921)
							(end -0.1524 -0.127)
						)
						(arc
							(start -0.1524 0.127)
							(mid -0.137521 0.162921)
							(end -0.1016 0.1778)
						)
						(arc
							(start 0.1016 0.1778)
							(mid 0.137521 0.162921)
							(end 0.1524 0.127)
						)
					)
					(width 0)
					(fill yes)
				)
			)
		)
	)
	(footprint ""
		(layer "F.Cu")
		(at 67.69989 -335.399888)
		(property "Reference" "BUS1"
			(at 0 0 0)
			(layer "F.SilkS")
			(hide yes)
			(effects
				(font
					(size 1.27 1.27)
				)
			)
		)
		(property "Value" "FCI-CONN56-4R-GP"
			(at -15.9385 -18.8976 0)
			(unlocked yes)
			(layer "F.Fab")
			(hide yes)
			(effects
				(font
					(size 1.016 1.016)
					(thickness 0.1524)
				)
			)
		)
		(property "Device Type" "PREFIT-56P-775146-1H510"
			(at -15.9385 -20.4216 0)
			(unlocked yes)
			(layer "F.Fab")
			(hide yes)
			(effects
				(font
					(size 1.016 1.016)
					(thickness 0.1524)
				)
			)
		)
		(duplicate_pad_numbers_are_jumpers no)
		(fp_line
			(start -7.874 -3.7338)
			(end -5.334 -3.7338)
			(stroke
				(width 0.1524)
				(type default)
			)
			(layer "F.SilkS")
		)
		(fp_line
			(start -7.874 3.7338)
			(end -7.874 -3.7338)
			(stroke
				(width 0.1524)
				(type default)
			)
			(layer "F.SilkS")
		)
		(fp_line
			(start -5.334 -11.3538)
			(end 67.564 -11.3538)
			(stroke
				(width 0.1524)
				(type default)
			)
			(layer "F.SilkS")
		)
		(fp_line
			(start -5.334 -3.7338)
			(end -5.334 -11.3538)
			(stroke
				(width 0.1524)
				(type default)
			)
			(layer "F.SilkS")
		)
		(fp_line
			(start 67.564 -11.3538)
			(end 67.564 -3.7338)
			(stroke
				(width 0.1524)
				(type default)
			)
			(layer "F.SilkS")
		)
		(fp_line
			(start 67.564 -3.7338)
			(end 70.104 -3.7338)
			(stroke
				(width 0.1524)
				(type default)
			)
			(layer "F.SilkS")
		)
		(fp_line
			(start 70.104 -3.7338)
			(end 70.104 3.7338)
			(stroke
				(width 0.1524)
				(type default)
			)
			(layer "F.SilkS")
		)
		(fp_line
			(start 70.104 3.7338)
			(end -7.874 3.7338)
			(stroke
				(width 0.1524)
				(type default)
			)
			(layer "F.SilkS")
		)
		(fp_poly
			(pts
				(arc
					(start 5.842 -7.366)
					(mid 5.588 -7.112)
					(end 5.334 -7.366)
				)
				(arc
					(start 5.334 -7.874)
					(mid 5.588 -8.128)
					(end 5.842 -7.874)
				)
			)
			(stroke
				(width 0)
				(type default)
			)
			(fill yes)
			(layer "F.SilkS")
		)
		(fp_poly
			(pts
				(arc
					(start 5.842 -4.826)
					(mid 5.588 -4.572)
					(end 5.334 -4.826)
				)
				(arc
					(start 5.334 -5.334)
					(mid 5.588 -5.588)
					(end 5.842 -5.334)
				)
			)
			(stroke
				(width 0)
				(type default)
			)
			(fill yes)
			(layer "F.SilkS")
		)
		(fp_poly
			(pts
				(arc
					(start 5.842 -2.286)
					(mid 5.588 -2.032)
					(end 5.334 -2.286)
				)
				(arc
					(start 5.334 -2.794)
					(mid 5.588 -3.048)
					(end 5.842 -2.794)
				)
			)
			(stroke
				(width 0)
				(type default)
			)
			(fill yes)
			(layer "F.SilkS")
		)
		(fp_poly
			(pts
				(arc
					(start 5.842 0.254)
					(mid 5.588 0.508)
					(end 5.334 0.254)
				)
				(arc
					(start 5.334 -0.254)
					(mid 5.588 -0.508)
					(end 5.842 -0.254)
				)
			)
			(stroke
				(width 0)
				(type default)
			)
			(fill yes)
			(layer "F.SilkS")
		)
		(fp_poly
			(pts
				(xy -7.874 3.7338) (xy -7.874 0.00635)
				(arc
					(start -6.985 0.00635)
					(mid -5.08 1.905011)
					(end -3.175 0.00635)
				)
				(arc
					(start -1.5621 0.00635)
					(mid 0 1.562113)
					(end 1.5621 0.00635)
				)
				(xy 5.0546 0.00635) (xy 5.0546 0.9652) (xy 56.21528 0.9652) (xy 56.21528 -8.5852) (xy 36.6522 -8.5852)
				(xy 36.6522 -10.1854) (xy 25.9334 -10.1854) (xy 25.9334 -8.5852) (xy 5.0546 -8.5852) (xy 5.0546 -0.00635)
				(arc
					(start 1.5621 -0.00635)
					(mid 0 -1.562113)
					(end -1.5621 -0.00635)
				)
				(arc
					(start -3.175 -0.00635)
					(mid -5.08 -1.905011)
					(end -6.985 -0.00635)
				)
				(xy -7.874 -0.00635) (xy -7.874 -3.7338) (xy -5.334 -3.7338) (xy -5.334 -11.3538) (xy 67.564 -11.3538)
				(xy 67.564 -3.7338) (xy 70.104 -3.7338) (xy 70.104 3.7338)
			)
			(stroke
				(width 0)
				(type default)
			)
			(fill yes)
			(layer "F.SilkS")
		)
		(fp_rect
			(start 1.27 5.715)
			(end 60.96 -13.335)
			(stroke
				(width 0)
				(type default)
			)
			(fill no)
			(layer "B.CrtYd")
		)
		(fp_poly
			(pts
				(xy -5.08 -11.0998) (xy -5.08 -3.4798) (xy -7.62 -3.4798) (xy -7.62 3.4798) (xy 69.85 3.4798) (xy 69.85 -3.4798)
				(xy 67.31 -3.4798) (xy 67.31 -11.0998)
			)
			(stroke
				(width 0)
				(type default)
			)
			(fill no)
			(layer "F.CrtYd")
		)
		(fp_poly
			(pts
				(xy -12.6238 8.4836) (xy -12.6238 -8.4836) (xy -10.0838 -8.4836) (xy -10.0838 -16.1036) (xy 72.3138 -16.1036)
				(xy 72.3138 -8.4836) (xy 74.8538 -8.4836) (xy 74.8538 0) (xy 70.358 0) (xy 70.358 -11.6078) (xy -8.128 -11.6078)
				(xy -8.128 3.9878) (xy 70.358 3.9878) (xy 70.358 0.0127) (xy 74.8538 0.0127) (xy 74.8538 8.4836)
			)
			(stroke
				(width 0)
				(type default)
			)
			(fill no)
			(layer "F.CrtYd")
		)
		(fp_poly
			(pts
				(xy -8.128 3.9878) (xy -8.128 -11.6078) (xy 70.358 -11.6078) (xy 70.358 0) (xy 69.85 0) (xy 69.85 -3.4798)
				(xy 67.31 -3.4798) (xy 67.31 -11.0998) (xy -5.08 -11.0998) (xy -5.08 -3.4798) (xy -7.62 -3.4798)
				(xy -7.62 3.4798) (xy 69.85 3.4798) (xy 69.85 0.0127) (xy 70.358 0.0127) (xy 70.358 3.9878)
			)
			(stroke
				(width 0)
				(type default)
			)
			(fill no)
			(layer "F.CrtYd")
		)
		(fp_rect
			(start -3.7338 10.7188)
			(end 65.9638 -18.3388)
			(stroke
				(width 0)
				(type default)
			)
			(fill no)
			(layer "B.Fab")
		)
		(fp_rect
			(start 1.27 5.715)
			(end 60.96 -13.335)
			(stroke
				(width 0)
				(type default)
			)
			(fill no)
			(layer "B.Fab")
		)
		(fp_rect
			(start -8.128 3.9878)
			(end 70.358 -11.6078)
			(stroke
				(width 0)
				(type default)
			)
			(fill no)
			(layer "F.Fab")
		)
		(fp_poly
			(pts
				(xy -17.6276 13.4874) (xy -17.6276 -13.4874) (xy -15.0876 -13.4874) (xy -15.0876 -21.1074) (xy 77.3176 -21.1074)
				(xy 77.3176 -13.4874) (xy 79.8576 -13.4874) (xy 79.8576 13.4874)
			)
			(stroke
				(width 0)
				(type default)
			)
			(fill no)
			(layer "F.Fab")
		)
		(fp_poly
			(pts
				(xy -12.6238 8.4836) (xy -12.6238 -8.4836) (xy -10.0838 -8.4836) (xy -10.0838 -16.1036) (xy 72.3138 -16.1036)
				(xy 72.3138 -8.4836) (xy 74.8538 -8.4836) (xy 74.8538 8.4836)
			)
			(stroke
				(width 0)
				(type default)
			)
			(fill no)
			(layer "F.Fab")
		)
		(fp_text user "Press Fit"
			(at 26.2382 -9.2964 0)
			(unlocked yes)
			(layer "F.SilkS")
			(effects
				(font
					(size 1.016 1.016)
					(thickness 0.1524)
				)
				(justify left)
			)
		)
		(fp_text user "Can not place BGA,CSP,Wave Solder Component"
			(at 6.3627 9.4361 0)
			(unlocked yes)
			(layer "B.Fab")
			(effects
				(font
					(size 1.016 1.016)
					(thickness 0.1524)
				)
				(justify left)
			)
		)
		(fp_text user "Can not place BGA,CSP,Wave Solder Component"
			(at 6.16585 12.22375 0)
			(unlocked yes)
			(layer "F.Fab")
			(effects
				(font
					(size 1.016 1.016)
					(thickness 0.1524)
				)
				(justify left)
			)
		)
		(fp_text user "High Limit 2mm"
			(at 22.8727 7.3025 0)
			(unlocked yes)
			(layer "F.Fab")
			(effects
				(font
					(size 1.016 1.016)
					(thickness 0.1524)
				)
				(justify left)
			)
		)
		(pad "" np_thru_hole circle
			(at -5.08 0)
			(size 0.254 0.254)
			(drill 3.2004)
			(layers "*.Cu" "*.Mask")
			(clearance 1.8288)
			(thermal_gap 1.8288)
		)
		(pad "" np_thru_hole circle
			(at 0 0)
			(size 0.254 0.254)
			(drill 2.5146)
			(layers "*.Cu" "*.Mask")
			(clearance 1.4859)
			(thermal_gap 1.4859)
		)
		(pad "" np_thru_hole circle
			(at 62.23 0)
			(size 0.254 0.254)
			(drill 2.5146)
			(layers "*.Cu" "*.Mask")
			(clearance 1.4859)
			(thermal_gap 1.4859)
		)
		(pad "" np_thru_hole circle
			(at 67.31 0)
			(size 0.254 0.254)
			(drill 3.2004)
			(layers "*.Cu" "*.Mask")
			(clearance 1.8288)
			(thermal_gap 1.8288)
		)
		(pad "P1_1" thru_hole circle
			(at 6.99008 0)
			(size 1.4224 1.4224)
			(drill 1.01981)
			(layers "*.Cu" "*.Mask")
			(remove_unused_layers no)
			(net "GND")
			(clearance 0.1651)
			(thermal_gap 0.1651)
		)
		(pad "P1_2" thru_hole circle
			(at 6.99008 -2.54)
			(size 1.4224 1.4224)
			(drill 1.01981)
			(layers "*.Cu" "*.Mask")
			(remove_unused_layers no)
			(net "GND")
			(clearance 0.1651)
			(thermal_gap 0.1651)
		)
		(pad "P1_3" thru_hole circle
			(at 6.99008 -5.08)
			(size 1.4224 1.4224)
			(drill 1.01981)
			(layers "*.Cu" "*.Mask")
			(remove_unused_layers no)
			(net "GND")
			(clearance 0.1651)
			(thermal_gap 0.1651)
		)
		(pad "P1_4" thru_hole circle
			(at 6.99008 -7.62)
			(size 1.4224 1.4224)
			(drill 1.01981)
			(layers "*.Cu" "*.Mask")
			(remove_unused_layers no)
			(net "GND")
			(clearance 0.1651)
			(thermal_gap 0.1651)
		)
		(pad "P1_5" thru_hole circle
			(at 9.53008 0)
			(size 1.4224 1.4224)
			(drill 1.01981)
			(layers "*.Cu" "*.Mask")
			(remove_unused_layers no)
			(net "GND")
			(clearance 0.1651)
			(thermal_gap 0.1651)
		)
		(pad "P1_6" thru_hole circle
			(at 9.53008 -2.54)
			(size 1.4224 1.4224)
			(drill 1.01981)
			(layers "*.Cu" "*.Mask")
			(remove_unused_layers no)
			(net "GND")
			(clearance 0.1651)
			(thermal_gap 0.1651)
		)
		(pad "P1_7" thru_hole circle
			(at 9.53008 -5.08)
			(size 1.4224 1.4224)
			(drill 1.01981)
			(layers "*.Cu" "*.Mask")
			(remove_unused_layers no)
			(net "GND")
			(clearance 0.1651)
			(thermal_gap 0.1651)
		)
		(pad "P1_8" thru_hole circle
			(at 9.53008 -7.62)
			(size 1.4224 1.4224)
			(drill 1.01981)
			(layers "*.Cu" "*.Mask")
			(remove_unused_layers no)
			(net "GND")
			(clearance 0.1651)
			(thermal_gap 0.1651)
		)
		(pad "P2_1" thru_hole circle
			(at 14.61008 0)
			(size 1.4224 1.4224)
			(drill 1.01981)
			(layers "*.Cu" "*.Mask")
			(remove_unused_layers no)
			(net "GND")
			(clearance 0.1651)
			(thermal_gap 0.1651)
		)
		(pad "P2_2" thru_hole circle
			(at 14.61008 -2.54)
			(size 1.4224 1.4224)
			(drill 1.01981)
			(layers "*.Cu" "*.Mask")
			(remove_unused_layers no)
			(net "GND")
			(clearance 0.1651)
			(thermal_gap 0.1651)
		)
		(pad "P2_3" thru_hole circle
			(at 14.61008 -5.08)
			(size 1.4224 1.4224)
			(drill 1.01981)
			(layers "*.Cu" "*.Mask")
			(remove_unused_layers no)
			(net "GND")
			(clearance 0.1651)
			(thermal_gap 0.1651)
		)
		(pad "P2_4" thru_hole circle
			(at 14.61008 -7.62)
			(size 1.4224 1.4224)
			(drill 1.01981)
			(layers "*.Cu" "*.Mask")
			(remove_unused_layers no)
			(net "GND")
			(clearance 0.1651)
			(thermal_gap 0.1651)
		)
		(pad "P2_5" thru_hole circle
			(at 17.15008 0)
			(size 1.4224 1.4224)
			(drill 1.01981)
			(layers "*.Cu" "*.Mask")
			(remove_unused_layers no)
			(net "GND")
			(clearance 0.1651)
			(thermal_gap 0.1651)
		)
		(pad "P2_6" thru_hole circle
			(at 17.15008 -2.54)
			(size 1.4224 1.4224)
			(drill 1.01981)
			(layers "*.Cu" "*.Mask")
			(remove_unused_layers no)
			(net "GND")
			(clearance 0.1651)
			(thermal_gap 0.1651)
		)
		(pad "P2_7" thru_hole circle
			(at 17.15008 -5.08)
			(size 1.4224 1.4224)
			(drill 1.01981)
			(layers "*.Cu" "*.Mask")
			(remove_unused_layers no)
			(net "GND")
			(clearance 0.1651)
			(thermal_gap 0.1651)
		)
		(pad "P2_8" thru_hole circle
			(at 17.15008 -7.62)
			(size 1.4224 1.4224)
			(drill 1.01981)
			(layers "*.Cu" "*.Mask")
			(remove_unused_layers no)
			(net "GND")
			(clearance 0.1651)
			(thermal_gap 0.1651)
		)
		(pad "P3_1" thru_hole circle
			(at 22.23008 0)
			(size 1.4224 1.4224)
			(drill 1.01981)
			(layers "*.Cu" "*.Mask")
			(remove_unused_layers no)
			(net "GND")
			(clearance 0.1651)
			(thermal_gap 0.1651)
		)
		(pad "P3_2" thru_hole circle
			(at 22.23008 -2.54)
			(size 1.4224 1.4224)
			(drill 1.01981)
			(layers "*.Cu" "*.Mask")
			(remove_unused_layers no)
			(net "GND")
			(clearance 0.1651)
			(thermal_gap 0.1651)
		)
		(pad "P3_3" thru_hole circle
			(at 22.23008 -5.08)
			(size 1.4224 1.4224)
			(drill 1.01981)
			(layers "*.Cu" "*.Mask")
			(remove_unused_layers no)
			(net "GND")
			(clearance 0.1651)
			(thermal_gap 0.1651)
		)
		(pad "P3_4" thru_hole circle
			(at 22.23008 -7.62)
			(size 1.4224 1.4224)
			(drill 1.01981)
			(layers "*.Cu" "*.Mask")
			(remove_unused_layers no)
			(net "GND")
			(clearance 0.1651)
			(thermal_gap 0.1651)
		)
		(pad "P3_5" thru_hole circle
			(at 24.77008 0)
			(size 1.4224 1.4224)
			(drill 1.01981)
			(layers "*.Cu" "*.Mask")
			(remove_unused_layers no)
			(net "GND")
			(clearance 0.1651)
			(thermal_gap 0.1651)
		)
		(pad "P3_6" thru_hole circle
			(at 24.77008 -2.54)
			(size 1.4224 1.4224)
			(drill 1.01981)
			(layers "*.Cu" "*.Mask")
			(remove_unused_layers no)
			(net "GND")
			(clearance 0.1651)
			(thermal_gap 0.1651)
		)
		(pad "P3_7" thru_hole circle
			(at 24.77008 -5.08)
			(size 1.4224 1.4224)
			(drill 1.01981)
			(layers "*.Cu" "*.Mask")
			(remove_unused_layers no)
			(net "GND")
			(clearance 0.1651)
			(thermal_gap 0.1651)
		)
		(pad "P3_8" thru_hole circle
			(at 24.77008 -7.62)
			(size 1.4224 1.4224)
			(drill 1.01981)
			(layers "*.Cu" "*.Mask")
			(remove_unused_layers no)
			(net "GND")
			(clearance 0.1651)
			(thermal_gap 0.1651)
		)
		(pad "P4_1" thru_hole circle
			(at 29.85008 0)
			(size 1.4224 1.4224)
			(drill 1.01981)
			(layers "*.Cu" "*.Mask")
			(remove_unused_layers no)
			(net "GND")
			(clearance 0.1651)
			(thermal_gap 0.1651)
		)
		(pad "P4_2" thru_hole circle
			(at 29.85008 -2.54)
			(size 1.4224 1.4224)
			(drill 1.01981)
			(layers "*.Cu" "*.Mask")
			(remove_unused_layers no)
			(net "GND")
			(clearance 0.1651)
			(thermal_gap 0.1651)
		)
		(pad "P4_3" thru_hole circle
			(at 29.85008 -5.08)
			(size 1.4224 1.4224)
			(drill 1.01981)
			(layers "*.Cu" "*.Mask")
			(remove_unused_layers no)
			(net "GND")
			(clearance 0.1651)
			(thermal_gap 0.1651)
		)
		(pad "P4_4" thru_hole circle
			(at 29.85008 -7.62)
			(size 1.4224 1.4224)
			(drill 1.01981)
			(layers "*.Cu" "*.Mask")
			(remove_unused_layers no)
			(net "GND")
			(clearance 0.1651)
			(thermal_gap 0.1651)
		)
		(pad "P4_5" thru_hole circle
			(at 32.39008 0)
			(size 1.4224 1.4224)
			(drill 1.01981)
			(layers "*.Cu" "*.Mask")
			(remove_unused_layers no)
			(net "GND")
			(clearance 0.1651)
			(thermal_gap 0.1651)
		)
		(pad "P4_6" thru_hole circle
			(at 32.39008 -2.54)
			(size 1.4224 1.4224)
			(drill 1.01981)
			(layers "*.Cu" "*.Mask")
			(remove_unused_layers no)
			(net "GND")
			(clearance 0.1651)
			(thermal_gap 0.1651)
		)
		(pad "P4_7" thru_hole circle
			(at 32.39008 -5.08)
			(size 1.4224 1.4224)
			(drill 1.01981)
			(layers "*.Cu" "*.Mask")
			(remove_unused_layers no)
			(net "GND")
			(clearance 0.1651)
			(thermal_gap 0.1651)
		)
		(pad "P4_8" thru_hole circle
			(at 32.39008 -7.62)
			(size 1.4224 1.4224)
			(drill 1.01981)
			(layers "*.Cu" "*.Mask")
			(remove_unused_layers no)
			(net "GND")
			(clearance 0.1651)
			(thermal_gap 0.1651)
		)
		(pad "P5_1" thru_hole circle
			(at 37.47008 0)
			(size 1.4224 1.4224)
			(drill 1.01981)
			(layers "*.Cu" "*.Mask")
			(remove_unused_layers no)
			(net "P12V_CLIP")
			(clearance 0.1651)
			(thermal_gap 0.1651)
		)
		(pad "P5_2" thru_hole circle
			(at 37.47008 -2.54)
			(size 1.4224 1.4224)
			(drill 1.01981)
			(layers "*.Cu" "*.Mask")
			(remove_unused_layers no)
			(net "P12V_CLIP")
			(clearance 0.1651)
			(thermal_gap 0.1651)
		)
		(pad "P5_3" thru_hole circle
			(at 37.47008 -5.08)
			(size 1.4224 1.4224)
			(drill 1.01981)
			(layers "*.Cu" "*.Mask")
			(remove_unused_layers no)
			(net "P12V_CLIP")
			(clearance 0.1651)
			(thermal_gap 0.1651)
		)
		(pad "P5_4" thru_hole circle
			(at 37.47008 -7.62)
			(size 1.4224 1.4224)
			(drill 1.01981)
			(layers "*.Cu" "*.Mask")
			(remove_unused_layers no)
			(net "P12V_CLIP")
			(clearance 0.1651)
			(thermal_gap 0.1651)
		)
		(pad "P5_5" thru_hole circle
			(at 40.01008 0)
			(size 1.4224 1.4224)
			(drill 1.01981)
			(layers "*.Cu" "*.Mask")
			(remove_unused_layers no)
			(net "P12V_CLIP")
			(clearance 0.1651)
			(thermal_gap 0.1651)
		)
		(pad "P5_6" thru_hole circle
			(at 40.01008 -2.54)
			(size 1.4224 1.4224)
			(drill 1.01981)
			(layers "*.Cu" "*.Mask")
			(remove_unused_layers no)
			(net "P12V_CLIP")
			(clearance 0.1651)
			(thermal_gap 0.1651)
		)
		(pad "P5_7" thru_hole circle
			(at 40.01008 -5.08)
			(size 1.4224 1.4224)
			(drill 1.01981)
			(layers "*.Cu" "*.Mask")
			(remove_unused_layers no)
			(net "P12V_CLIP")
			(clearance 0.1651)
			(thermal_gap 0.1651)
		)
		(pad "P5_8" thru_hole circle
			(at 40.01008 -7.62)
			(size 1.4224 1.4224)
			(drill 1.01981)
			(layers "*.Cu" "*.Mask")
			(remove_unused_layers no)
			(net "P12V_CLIP")
			(clearance 0.1651)
			(thermal_gap 0.1651)
		)
		(pad "P6_1" thru_hole circle
			(at 45.09008 0)
			(size 1.4224 1.4224)
			(drill 1.01981)
			(layers "*.Cu" "*.Mask")
			(remove_unused_layers no)
			(net "P12V_CLIP")
			(clearance 0.1651)
			(thermal_gap 0.1651)
		)
		(pad "P6_2" thru_hole circle
			(at 45.09008 -2.54)
			(size 1.4224 1.4224)
			(drill 1.01981)
			(layers "*.Cu" "*.Mask")
			(remove_unused_layers no)
			(net "P12V_CLIP")
			(clearance 0.1651)
			(thermal_gap 0.1651)
		)
		(pad "P6_3" thru_hole circle
			(at 45.09008 -5.08)
			(size 1.4224 1.4224)
			(drill 1.01981)
			(layers "*.Cu" "*.Mask")
			(remove_unused_layers no)
			(net "P12V_CLIP")
			(clearance 0.1651)
			(thermal_gap 0.1651)
		)
		(pad "P6_4" thru_hole circle
			(at 45.09008 -7.62)
			(size 1.4224 1.4224)
			(drill 1.01981)
			(layers "*.Cu" "*.Mask")
			(remove_unused_layers no)
			(net "P12V_CLIP")
			(clearance 0.1651)
			(thermal_gap 0.1651)
		)
		(pad "P6_5" thru_hole circle
			(at 47.63008 0)
			(size 1.4224 1.4224)
			(drill 1.01981)
			(layers "*.Cu" "*.Mask")
			(remove_unused_layers no)
			(net "P12V_CLIP")
			(clearance 0.1651)
			(thermal_gap 0.1651)
		)
		(pad "P6_6" thru_hole circle
			(at 47.63008 -2.54)
			(size 1.4224 1.4224)
			(drill 1.01981)
			(layers "*.Cu" "*.Mask")
			(remove_unused_layers no)
			(net "P12V_CLIP")
			(clearance 0.1651)
			(thermal_gap 0.1651)
		)
		(pad "P6_7" thru_hole circle
			(at 47.63008 -5.08)
			(size 1.4224 1.4224)
			(drill 1.01981)
			(layers "*.Cu" "*.Mask")
			(remove_unused_layers no)
			(net "P12V_CLIP")
			(clearance 0.1651)
			(thermal_gap 0.1651)
		)
		(pad "P6_8" thru_hole circle
			(at 47.63008 -7.62)
			(size 1.4224 1.4224)
			(drill 1.01981)
			(layers "*.Cu" "*.Mask")
			(remove_unused_layers no)
			(net "P12V_CLIP")
			(clearance 0.1651)
			(thermal_gap 0.1651)
		)
		(pad "P7_1" thru_hole circle
			(at 52.71008 0)
			(size 1.4224 1.4224)
			(drill 1.01981)
			(layers "*.Cu" "*.Mask")
			(remove_unused_layers no)
			(net "P12V_CLIP")
			(clearance 0.1651)
			(thermal_gap 0.1651)
		)
		(pad "P7_2" thru_hole circle
			(at 52.71008 -2.54)
			(size 1.4224 1.4224)
			(drill 1.01981)
			(layers "*.Cu" "*.Mask")
			(remove_unused_layers no)
			(net "P12V_CLIP")
			(clearance 0.1651)
			(thermal_gap 0.1651)
		)
		(pad "P7_3" thru_hole circle
			(at 52.71008 -5.08)
			(size 1.4224 1.4224)
			(drill 1.01981)
			(layers "*.Cu" "*.Mask")
			(remove_unused_layers no)
			(net "P12V_CLIP")
			(clearance 0.1651)
			(thermal_gap 0.1651)
		)
		(pad "P7_4" thru_hole circle
			(at 52.71008 -7.62)
			(size 1.4224 1.4224)
			(drill 1.01981)
			(layers "*.Cu" "*.Mask")
			(remove_unused_layers no)
			(net "P12V_CLIP")
			(clearance 0.1651)
			(thermal_gap 0.1651)
		)
		(pad "P7_5" thru_hole circle
			(at 55.25008 0)
			(size 1.4224 1.4224)
			(drill 1.01981)
			(layers "*.Cu" "*.Mask")
			(remove_unused_layers no)
			(net "P12V_CLIP")
			(clearance 0.1651)
			(thermal_gap 0.1651)
		)
		(pad "P7_6" thru_hole circle
			(at 55.25008 -2.54)
			(size 1.4224 1.4224)
			(drill 1.01981)
			(layers "*.Cu" "*.Mask")
			(remove_unused_layers no)
			(net "P12V_CLIP")
			(clearance 0.1651)
			(thermal_gap 0.1651)
		)
		(pad "P7_7" thru_hole circle
			(at 55.25008 -5.08)
			(size 1.4224 1.4224)
			(drill 1.01981)
			(layers "*.Cu" "*.Mask")
			(remove_unused_layers no)
			(net "P12V_CLIP")
			(clearance 0.1651)
			(thermal_gap 0.1651)
		)
		(pad "P7_8" thru_hole circle
			(at 55.25008 -7.62)
			(size 1.4224 1.4224)
			(drill 1.01981)
			(layers "*.Cu" "*.Mask")
			(remove_unused_layers no)
			(net "P12V_CLIP")
			(clearance 0.1651)
			(thermal_gap 0.1651)
		)
		(zone
			(layers "F.Cu" "B.Cu" "In1.Cu" "In2.Cu" "In3.Cu" "In4.Cu" "In5.Cu" "In6.Cu")
			(hatch none 0.5)
			(connect_pads
				(clearance 0)
			)
			(min_thickness 0.25)
			(keepout
				(tracks not_allowed)
				(vias allowed)
				(pads allowed)
				(copperpour not_allowed)
				(footprints allowed)
			)
			(placement
				(enabled no)
				(sheetname "")
			)
			(fill
				(thermal_gap 0.5)
				(thermal_bridge_width 0.5)
				(island_removal_mode 0)
			)
			(polygon
				(pts
					(arc
						(start 69.26199 -335.399888)
						(mid 66.13779 -335.399888)
						(end 69.26199 -335.399888)
					)
				)
			)
		)
		(zone
			(layers "F.Cu" "B.Cu" "In1.Cu" "In2.Cu" "In3.Cu" "In4.Cu" "In5.Cu" "In6.Cu")
			(hatch none 0.5)
			(connect_pads
				(clearance 0)
			)
			(min_thickness 0.25)
			(keepout
				(tracks not_allowed)
				(vias allowed)
				(pads allowed)
				(copperpour not_allowed)
				(footprints allowed)
			)
			(placement
				(enabled no)
				(sheetname "")
			)
			(fill
				(thermal_gap 0.5)
				(thermal_bridge_width 0.5)
				(island_removal_mode 0)
			)
			(polygon
				(pts
					(arc
						(start 131.49199 -335.399888)
						(mid 128.36779 -335.399888)
						(end 131.49199 -335.399888)
					)
				)
			)
		)
		(zone
			(layers "F.Cu" "B.Cu" "In1.Cu" "In2.Cu" "In3.Cu" "In4.Cu" "In5.Cu" "In6.Cu")
			(hatch none 0.5)
			(connect_pads
				(clearance 0)
			)
			(min_thickness 0.25)
			(keepout
				(tracks not_allowed)
				(vias allowed)
				(pads allowed)
				(copperpour not_allowed)
				(footprints allowed)
			)
			(placement
				(enabled no)
				(sheetname "")
			)
			(fill
				(thermal_gap 0.5)
				(thermal_bridge_width 0.5)
				(island_removal_mode 0)
			)
			(polygon
				(pts
					(arc
						(start 64.52489 -335.399888)
						(mid 60.71489 -335.399888)
						(end 64.52489 -335.399888)
					)
				)
			)
		)
		(zone
			(layers "F.Cu" "B.Cu" "In1.Cu" "In2.Cu" "In3.Cu" "In4.Cu" "In5.Cu" "In6.Cu")
			(hatch none 0.5)
			(connect_pads
				(clearance 0)
			)
			(min_thickness 0.25)
			(keepout
				(tracks not_allowed)
				(vias allowed)
				(pads allowed)
				(copperpour not_allowed)
				(footprints allowed)
			)
			(placement
				(enabled no)
				(sheetname "")
			)
			(fill
				(thermal_gap 0.5)
				(thermal_bridge_width 0.5)
				(island_removal_mode 0)
			)
			(polygon
				(pts
					(arc
						(start 136.91489 -335.399888)
						(mid 133.10489 -335.399888)
						(end 136.91489 -335.399888)
					)
				)
			)
		)
	)
	(footprint ""
		(layer "F.Cu")
		(at 54.102 -13.0048 -90)
		(property "Reference" "D25"
			(at 0 0 270)
			(layer "F.SilkS")
			(hide yes)
			(effects
				(font
					(size 1.27 1.27)
				)
			)
		)
		(property "Value" "RB551V30-GP"
			(at 0 -6.7818 270)
			(unlocked yes)
			(layer "F.Fab")
			(hide yes)
			(effects
				(font
					(size 1.016 1.016)
					(thickness 0.1524)
				)
			)
		)
		(property "Device Type" "SOD323AKH38"
			(at 0 -8.6868 270)
			(unlocked yes)
			(layer "F.Fab")
			(hide yes)
			(effects
				(font
					(size 1.016 1.016)
					(thickness 0.1524)
				)
			)
		)
		(duplicate_pad_numbers_are_jumpers no)
		(fp_line
			(start -0.889 2.159)
			(end -0.889 -1.9304)
			(stroke
				(width 0.1524)
				(type default)
			)
			(layer "F.SilkS")
		)
		(fp_line
			(start 0.889 2.159)
			(end -0.889 2.159)
			(stroke
				(width 0.1524)
				(type default)
			)
			(layer "F.SilkS")
		)
		(fp_line
			(start 0.762 2.0574)
			(end -0.762 2.0574)
			(stroke
				(width 0.508)
				(type default)
			)
			(layer "F.SilkS")
		)
		(fp_line
			(start -0.889 -1.9304)
			(end 0.889 -1.9304)
			(stroke
				(width 0.1524)
				(type default)
			)
			(layer "F.SilkS")
		)
		(fp_line
			(start 0.889 -1.9304)
			(end 0.889 2.159)
			(stroke
				(width 0.1524)
				(type default)
			)
			(layer "F.SilkS")
		)
		(fp_rect
			(start -1.016 2.3114)
			(end 1.016 -2.0066)
			(stroke
				(width 0)
				(type default)
			)
			(fill no)
			(layer "F.CrtYd")
		)
		(fp_poly
			(pts
				(xy -1.016 -2.0066) (xy 1.016 -2.0066) (xy 1.016 2.3114) (xy -1.016 2.3114)
			)
			(stroke
				(width 0)
				(type default)
			)
			(fill no)
			(layer "F.Fab")
		)
		(pad "A" smd rect
			(at 0 -1.143 270)
			(size 0.5588 1.016)
			(layers "F.Cu" "F.Mask" "F.Paste")
			(net "SW_HDD_R25")
		)
		(pad "K" smd rect
			(at 0 1.143 270)
			(size 0.5588 1.016)
			(layers "F.Cu" "F.Mask" "F.Paste")
			(net "SW_HDD_N25")
		)
	)
	(footprint ""
		(layer "F.Cu")
		(at 333.502 -274.955 180)
		(property "Reference" "C113"
			(at 0 0 180)
			(layer "F.SilkS")
			(hide yes)
			(effects
				(font
					(size 1.27 1.27)
				)
			)
		)
		(property "Value" "SC4D7U25V5KX-1-GP"
			(at -0.0762 -6.1214 180)
			(unlocked yes)
			(layer "F.Fab")
			(hide yes)
			(effects
				(font
					(size 1.016 1.016)
					(thickness 0.1524)
				)
			)
		)
		(property "Device Type" "C805H58"
			(at -0.0762 -8.1534 180)
			(unlocked yes)
			(layer "F.Fab")
			(hide yes)
			(effects
				(font
					(size 1.016 1.016)
					(thickness 0.1524)
				)
			)
		)
		(duplicate_pad_numbers_are_jumpers no)
		(fp_line
			(start 0.635 0)
			(end -0.635 0)
			(stroke
				(width 0.508)
				(type default)
			)
			(layer "F.SilkS")
		)
		(fp_rect
			(start -0.9652 1.778)
			(end 0.9652 -1.778)
			(stroke
				(width 0)
				(type default)
			)
			(fill no)
			(layer "F.CrtYd")
		)
		(fp_poly
			(pts
				(xy -0.9652 -1.778) (xy 0.9652 -1.778) (xy 0.9652 1.778) (xy -0.9652 1.778)
			)
			(stroke
				(width 0)
				(type default)
			)
			(fill no)
			(layer "F.Fab")
		)
		(pad "1" smd rect
			(at 0 -0.9652 180)
			(size 1.397 1.143)
			(layers "F.Cu" "F.Mask" "F.Paste")
			(net "P12V_HDD6")
		)
		(pad "2" smd rect
			(at 0 0.9652 180)
			(size 1.397 1.143)
			(layers "F.Cu" "F.Mask" "F.Paste")
			(net "GND")
		)
	)
	(footprint ""
		(layer "F.Cu")
		(at 50.419 -150.622 90)
		(property "Reference" "R370"
			(at 0 0 90)
			(layer "F.SilkS")
			(hide yes)
			(effects
				(font
					(size 1.27 1.27)
				)
			)
		)
		(property "Value" "2R6F-GP"
			(at -0.0508 -4.8514 90)
			(unlocked yes)
			(layer "F.Fab")
			(hide yes)
			(effects
				(font
					(size 1.016 1.016)
					(thickness 0.1524)
				)
			)
		)
		(property "Device Type" "R1206H26"
			(at 0 -6.3754 90)
			(unlocked yes)
			(layer "F.Fab")
			(hide yes)
			(effects
				(font
					(size 1.016 1.016)
					(thickness 0.1524)
				)
			)
		)
		(duplicate_pad_numbers_are_jumpers no)
		(fp_line
			(start 1.016 -2.2352)
			(end 1.016 2.2352)
			(stroke
				(width 0.1524)
				(type default)
			)
			(layer "F.SilkS")
		)
		(fp_line
			(start -1.016 -2.2352)
			(end 1.016 -2.2352)
			(stroke
				(width 0.1524)
				(type default)
			)
			(layer "F.SilkS")
		)
		(fp_line
			(start 1.016 2.2352)
			(end -1.016 2.2352)
			(stroke
				(width 0.1524)
				(type default)
			)
			(layer "F.SilkS")
		)
		(fp_line
			(start -1.016 2.2352)
			(end -1.016 -2.2352)
			(stroke
				(width 0.1524)
				(type default)
			)
			(layer "F.SilkS")
		)
		(fp_rect
			(start -1.0922 2.3114)
			(end 1.0922 -2.3114)
			(stroke
				(width 0)
				(type default)
			)
			(fill no)
			(layer "F.CrtYd")
		)
		(fp_poly
			(pts
				(xy -1.0922 -2.3114) (xy 1.0922 -2.3114) (xy 1.0922 2.3114) (xy -1.0922 2.3114)
			)
			(stroke
				(width 0)
				(type default)
			)
			(fill no)
			(layer "F.Fab")
		)
		(pad "1" smd rect
			(at 0 -1.397 90)
			(size 1.651 1.27)
			(layers "F.Cu" "F.Mask" "F.Paste")
			(net "P12V_HDD13")
		)
		(pad "2" smd rect
			(at 0 1.397 90)
			(size 1.651 1.27)
			(layers "F.Cu" "F.Mask" "F.Paste")
			(net "12V_PRE_13")
		)
	)
	(footprint ""
		(layer "F.Cu")
		(at 239.071658 -133.101842 90)
		(property "Reference" "R417"
			(at 0 0 90)
			(layer "F.SilkS")
			(hide yes)
			(effects
				(font
					(size 1.27 1.27)
				)
			)
		)
		(property "Value" "1KR2J-1-GP"
			(at 0.064008 -3.993896 90)
			(unlocked yes)
			(layer "F.Fab")
			(hide yes)
			(effects
				(font
					(size 1.016 1.016)
					(thickness 0.1524)
				)
			)
		)
		(property "Device Type" "R402H16"
			(at 0.064008 -5.517896 90)
			(unlocked yes)
			(layer "F.Fab")
			(hide yes)
			(effects
				(font
					(size 1.016 1.016)
					(thickness 0.1524)
				)
			)
		)
		(duplicate_pad_numbers_are_jumpers no)
		(fp_line
			(start 0.508 -0.9398)
			(end -0.508 -0.9398)
			(stroke
				(width 0.1524)
				(type default)
			)
			(layer "F.SilkS")
		)
		(fp_line
			(start -0.508 -0.9398)
			(end -0.508 0.9398)
			(stroke
				(width 0.1524)
				(type default)
			)
			(layer "F.SilkS")
		)
		(fp_rect
			(start -0.508 0.9398)
			(end 0.508 -0.9398)
			(stroke
				(width 0)
				(type default)
			)
			(fill no)
			(layer "F.CrtYd")
		)
		(fp_rect
			(start -0.508 0.9398)
			(end 0.508 -0.9398)
			(stroke
				(width 0)
				(type default)
			)
			(fill no)
			(layer "F.Fab")
		)
		(pad "1" smd custom
			(at 0 -0.4445 90)
			(size 0.1397 0.1397)
			(layers "F.Cu" "F.Mask" "F.Paste")
			(net "P3V3_STBY_B")
			(options
				(clearance outline)
				(anchor circle)
			)
			(primitives
				(gr_poly
					(pts
						(arc
							(start -0.1778 -0.2794)
							(mid -0.249642 -0.249642)
							(end -0.2794 -0.1778)
						)
						(arc
							(start -0.2794 0.1778)
							(mid -0.249642 0.249642)
							(end -0.1778 0.2794)
						)
						(arc
							(start 0.1778 0.2794)
							(mid 0.249642 0.249642)
							(end 0.2794 0.1778)
						)
						(arc
							(start 0.2794 -0.1778)
							(mid 0.249642 -0.249642)
							(end 0.1778 -0.2794)
						)
					)
					(width 0)
					(fill yes)
				)
			)
		)
		(pad "2" smd custom
			(at 0 0.4445 90)
			(size 0.1397 0.1397)
			(layers "F.Cu" "F.Mask" "F.Paste")
			(net "I2C_DPB_B_SCL_BUF")
			(options
				(clearance outline)
				(anchor circle)
			)
			(primitives
				(gr_poly
					(pts
						(arc
							(start -0.1778 -0.2794)
							(mid -0.249642 -0.249642)
							(end -0.2794 -0.1778)
						)
						(arc
							(start -0.2794 0.1778)
							(mid -0.249642 0.249642)
							(end -0.1778 0.2794)
						)
						(arc
							(start 0.1778 0.2794)
							(mid 0.249642 0.249642)
							(end 0.2794 0.1778)
						)
						(arc
							(start 0.2794 -0.1778)
							(mid 0.249642 -0.249642)
							(end 0.1778 -0.2794)
						)
					)
					(width 0)
					(fill yes)
				)
			)
		)
	)
	(footprint ""
		(layer "F.Cu")
		(at 370.205 -27.813 -90)
		(property "Reference" "R797"
			(at 0 0 270)
			(layer "F.SilkS")
			(hide yes)
			(effects
				(font
					(size 1.27 1.27)
				)
			)
		)
		(property "Value" "300KR2F-GP"
			(at 0.064008 -3.993896 270)
			(unlocked yes)
			(layer "F.Fab")
			(hide yes)
			(effects
				(font
					(size 1.016 1.016)
					(thickness 0.1524)
				)
			)
		)
		(property "Device Type" "R402H16"
			(at 0.064008 -5.517896 270)
			(unlocked yes)
			(layer "F.Fab")
			(hide yes)
			(effects
				(font
					(size 1.016 1.016)
					(thickness 0.1524)
				)
			)
		)
		(duplicate_pad_numbers_are_jumpers no)
		(fp_line
			(start -0.508 -0.9398)
			(end -0.508 0.9398)
			(stroke
				(width 0.1524)
				(type default)
			)
			(layer "F.SilkS")
		)
		(fp_line
			(start 0.508 -0.9398)
			(end -0.508 -0.9398)
			(stroke
				(width 0.1524)
				(type default)
			)
			(layer "F.SilkS")
		)
		(fp_rect
			(start -0.508 0.9398)
			(end 0.508 -0.9398)
			(stroke
				(width 0)
				(type default)
			)
			(fill no)
			(layer "F.CrtYd")
		)
		(fp_rect
			(start -0.508 0.9398)
			(end 0.508 -0.9398)
			(stroke
				(width 0)
				(type default)
			)
			(fill no)
			(layer "F.Fab")
		)
		(pad "1" smd custom
			(at 0 -0.4445 270)
			(size 0.1397 0.1397)
			(layers "F.Cu" "F.Mask" "F.Paste")
			(net "SW_HDD_N31")
			(options
				(clearance outline)
				(anchor circle)
			)
			(primitives
				(gr_poly
					(pts
						(arc
							(start -0.1778 -0.2794)
							(mid -0.249642 -0.249642)
							(end -0.2794 -0.1778)
						)
						(arc
							(start -0.2794 0.1778)
							(mid -0.249642 0.249642)
							(end -0.1778 0.2794)
						)
						(arc
							(start 0.1778 0.2794)
							(mid 0.249642 0.249642)
							(end 0.2794 0.1778)
						)
						(arc
							(start 0.2794 -0.1778)
							(mid 0.249642 -0.249642)
							(end 0.1778 -0.2794)
						)
					)
					(width 0)
					(fill yes)
				)
			)
		)
		(pad "2" smd custom
			(at 0 0.4445 270)
			(size 0.1397 0.1397)
			(layers "F.Cu" "F.Mask" "F.Paste")
			(net "P12V_B")
			(options
				(clearance outline)
				(anchor circle)
			)
			(primitives
				(gr_poly
					(pts
						(arc
							(start -0.1778 -0.2794)
							(mid -0.249642 -0.249642)
							(end -0.2794 -0.1778)
						)
						(arc
							(start -0.2794 0.1778)
							(mid -0.249642 0.249642)
							(end -0.1778 0.2794)
						)
						(arc
							(start 0.1778 0.2794)
							(mid 0.249642 0.249642)
							(end 0.2794 0.1778)
						)
						(arc
							(start 0.2794 -0.1778)
							(mid 0.249642 -0.249642)
							(end 0.1778 -0.2794)
						)
					)
					(width 0)
					(fill yes)
				)
			)
		)
	)
	(footprint ""
		(layer "F.Cu")
		(at 463.411824 -223.027748 90)
		(property "Reference" "C661"
			(at 0 0 90)
			(layer "F.SilkS")
			(hide yes)
			(effects
				(font
					(size 1.27 1.27)
				)
			)
		)
		(property "Value" "SCD1U16V2KX-3GP"
			(at 1.1811 -2.7051 90)
			(unlocked yes)
			(layer "F.Fab")
			(hide yes)
			(effects
				(font
					(size 1.016 1.016)
					(thickness 0.1524)
				)
			)
		)
		(property "Device Type" "C402H22"
			(at 1.1811 -4.2291 90)
			(unlocked yes)
			(layer "F.Fab")
			(hide yes)
			(effects
				(font
					(size 1.016 1.016)
					(thickness 0.1524)
				)
			)
		)
		(duplicate_pad_numbers_are_jumpers no)
		(fp_rect
			(start -0.4318 0.9525)
			(end 0.4318 -0.9525)
			(stroke
				(width 0)
				(type default)
			)
			(fill no)
			(layer "F.CrtYd")
		)
		(fp_rect
			(start -0.4318 0.9525)
			(end 0.4318 -0.9525)
			(stroke
				(width 0)
				(type default)
			)
			(fill no)
			(layer "F.Fab")
		)
		(pad "1" smd custom
			(at 0 -0.4445 90)
			(size 0.1524 0.1524)
			(layers "F.Cu" "F.Mask" "F.Paste")
			(net "P5V_B_3_VBST_RC")
			(options
				(clearance outline)
				(anchor circle)
			)
			(primitives
				(gr_poly
					(pts
						(arc
							(start 0.3048 -0.2032)
							(mid 0.275042 -0.275042)
							(end 0.2032 -0.3048)
						)
						(arc
							(start -0.2032 -0.3048)
							(mid -0.275042 -0.275042)
							(end -0.3048 -0.2032)
						)
						(arc
							(start -0.3048 0.2032)
							(mid -0.275042 0.275042)
							(end -0.2032 0.3048)
						)
						(arc
							(start 0.2032 0.3048)
							(mid 0.275042 0.275042)
							(end 0.3048 0.2032)
						)
					)
					(width 0)
					(fill yes)
				)
			)
		)
		(pad "2" smd custom
			(at 0 0.4445 90)
			(size 0.1524 0.1524)
			(layers "F.Cu" "F.Mask" "F.Paste")
			(net "P5V_B_3_LL")
			(options
				(clearance outline)
				(anchor circle)
			)
			(primitives
				(gr_poly
					(pts
						(arc
							(start 0.3048 -0.2032)
							(mid 0.275042 -0.275042)
							(end 0.2032 -0.3048)
						)
						(arc
							(start -0.2032 -0.3048)
							(mid -0.275042 -0.275042)
							(end -0.3048 -0.2032)
						)
						(arc
							(start -0.3048 0.2032)
							(mid -0.275042 0.275042)
							(end -0.2032 0.3048)
						)
						(arc
							(start 0.2032 0.3048)
							(mid 0.275042 0.275042)
							(end 0.3048 0.2032)
						)
					)
					(width 0)
					(fill yes)
				)
			)
		)
	)
	(footprint ""
		(layer "F.Cu")
		(at 107.099862 -23.999952)
		(property "Reference" ""
			(at 0 0 0)
			(layer "F.SilkS")
			(hide yes)
			(effects
				(font
					(size 1.27 1.27)
				)
			)
		)
		(property "Value" "*"
			(at -6.3373 -0.4572 0)
			(unlocked yes)
			(layer "F.Fab")
			(hide yes)
			(effects
				(font
					(size 1.016 1.016)
					(thickness 0.1524)
				)
			)
		)
		(duplicate_pad_numbers_are_jumpers no)
		(fp_poly
			(pts
				(arc
					(start 5.0673 0)
					(mid -5.0673 0)
					(end 5.0673 0)
				)
			)
			(stroke
				(width 0)
				(type default)
			)
			(fill no)
			(layer "B.CrtYd")
		)
		(fp_poly
			(pts
				(arc
					(start 5.0673 0)
					(mid -5.0673 0)
					(end 5.0673 0)
				)
			)
			(stroke
				(width 0)
				(type default)
			)
			(fill no)
			(layer "F.CrtYd")
		)
		(fp_poly
			(pts
				(arc
					(start 5.0673 0)
					(mid -5.0673 0)
					(end 5.0673 0)
				)
			)
			(stroke
				(width 0)
				(type default)
			)
			(fill no)
			(layer "B.Fab")
		)
		(fp_poly
			(pts
				(arc
					(start 5.0673 0)
					(mid -5.0673 0)
					(end 5.0673 0)
				)
			)
			(stroke
				(width 0)
				(type default)
			)
			(fill no)
			(layer "F.Fab")
		)
		(pad "1" thru_hole circle
			(at 0 0)
			(size 9.525 9.525)
			(drill 3.556)
			(layers "*.Cu" "*.Mask")
			(remove_unused_layers no)
			(net "Net_36")
			(clearance -2.4765)
			(thermal_gap 0.3048)
			(padstack
				(mode front_inner_back)
				(layer "Inner"
					(shape circle)
					(size 3.9624 3.9624)
					(clearance 0.3048)
				)
				(layer "B.Cu"
					(shape circle)
					(size 9.525 9.525)
					(clearance -2.4765)
				)
			)
		)
		(zone
			(layers "F.Cu" "B.Cu" "In1.Cu" "In2.Cu" "In3.Cu" "In4.Cu" "In5.Cu" "In6.Cu")
			(hatch none 0.5)
			(connect_pads
				(clearance 0)
			)
			(min_thickness 0.25)
			(keepout
				(tracks not_allowed)
				(vias allowed)
				(pads allowed)
				(copperpour not_allowed)
				(footprints allowed)
			)
			(placement
				(enabled no)
				(sheetname "")
			)
			(fill
				(thermal_gap 0.5)
				(thermal_bridge_width 0.5)
				(island_removal_mode 0)
			)
			(polygon
				(pts
					(arc
						(start 111.862362 -23.999952)
						(mid 102.337362 -23.999952)
						(end 111.862362 -23.999952)
					)
				)
			)
		)
	)
	(footprint ""
		(layer "F.Cu")
		(at 394.589 -44.958 180)
		(property "Reference" "C450"
			(at 0 0 180)
			(layer "F.SilkS")
			(hide yes)
			(effects
				(font
					(size 1.27 1.27)
				)
			)
		)
		(property "Value" "SC4D7U25V5KX-1-GP"
			(at -0.0762 -6.1214 180)
			(unlocked yes)
			(layer "F.Fab")
			(hide yes)
			(effects
				(font
					(size 1.016 1.016)
					(thickness 0.1524)
				)
			)
		)
		(property "Device Type" "C805H58"
			(at -0.0762 -8.1534 180)
			(unlocked yes)
			(layer "F.Fab")
			(hide yes)
			(effects
				(font
					(size 1.016 1.016)
					(thickness 0.1524)
				)
			)
		)
		(duplicate_pad_numbers_are_jumpers no)
		(fp_line
			(start 0.635 0)
			(end -0.635 0)
			(stroke
				(width 0.508)
				(type default)
			)
			(layer "F.SilkS")
		)
		(fp_rect
			(start -0.9652 1.778)
			(end 0.9652 -1.778)
			(stroke
				(width 0)
				(type default)
			)
			(fill no)
			(layer "F.CrtYd")
		)
		(fp_poly
			(pts
				(xy -0.9652 -1.778) (xy 0.9652 -1.778) (xy 0.9652 1.778) (xy -0.9652 1.778)
			)
			(stroke
				(width 0)
				(type default)
			)
			(fill no)
			(layer "F.Fab")
		)
		(pad "1" smd rect
			(at 0 -0.9652 180)
			(size 1.397 1.143)
			(layers "F.Cu" "F.Mask" "F.Paste")
			(net "P12V_HDD32")
		)
		(pad "2" smd rect
			(at 0 0.9652 180)
			(size 1.397 1.143)
			(layers "F.Cu" "F.Mask" "F.Paste")
			(net "GND")
		)
	)
	(footprint ""
		(layer "F.Cu")
		(at 429.514 -23.876 -90)
		(property "Reference" "Q171"
			(at 0 0 270)
			(layer "F.SilkS")
			(hide yes)
			(effects
				(font
					(size 1.27 1.27)
				)
			)
		)
		(property "Value" "AO4406AL-GP"
			(at -3.707384 -1.5367 270)
			(unlocked yes)
			(layer "F.Fab")
			(hide yes)
			(effects
				(font
					(size 1.016 1.016)
					(thickness 0.1524)
				)
			)
		)
		(property "Device Type" "SOIC8H69"
			(at -3.707384 -3.0607 270)
			(unlocked yes)
			(layer "F.Fab")
			(hide yes)
			(effects
				(font
					(size 1.016 1.016)
					(thickness 0.1524)
				)
			)
		)
		(duplicate_pad_numbers_are_jumpers no)
		(fp_line
			(start -2.6289 3.4417)
			(end -2.6289 1.4732)
			(stroke
				(width 0.381)
				(type default)
			)
			(layer "F.SilkS")
		)
		(fp_line
			(start -2.7432 1.4224)
			(end -2.6416 1.4224)
			(stroke
				(width 0.1524)
				(type default)
			)
			(layer "F.SilkS")
		)
		(fp_line
			(start -2.7432 1.4224)
			(end 2.1336 1.4224)
			(stroke
				(width 0.1524)
				(type default)
			)
			(layer "F.SilkS")
		)
		(fp_line
			(start 2.1336 1.4224)
			(end 2.1336 -1.4224)
			(stroke
				(width 0.1524)
				(type default)
			)
			(layer "F.SilkS")
		)
		(fp_line
			(start -2.1844 -0.0508)
			(end -2.7178 0.508)
			(stroke
				(width 0.1524)
				(type default)
			)
			(layer "F.SilkS")
		)
		(fp_line
			(start -2.7178 -0.508)
			(end -2.1844 -0.0508)
			(stroke
				(width 0.1524)
				(type default)
			)
			(layer "F.SilkS")
		)
		(fp_line
			(start -2.7432 -1.4224)
			(end -2.7432 1.4224)
			(stroke
				(width 0.1524)
				(type default)
			)
			(layer "F.SilkS")
		)
		(fp_line
			(start 2.1336 -1.4224)
			(end -2.7432 -1.4224)
			(stroke
				(width 0.1524)
				(type default)
			)
			(layer "F.SilkS")
		)
		(fp_poly
			(pts
				(xy -2.2098 -1.4224) (xy -2.2098 1.4224) (xy 2.2098 1.4224) (xy 2.2098 -1.4224)
			)
			(stroke
				(width 0)
				(type default)
			)
			(fill yes)
			(layer "F.SilkS")
		)
		(fp_rect
			(start -2.450084 2.999994)
			(end 2.450084 -2.999994)
			(stroke
				(width 0)
				(type default)
			)
			(fill no)
			(layer "F.CrtYd")
		)
		(fp_poly
			(pts
				(xy -2.8194 3.6322) (xy -2.8194 -3.6322) (xy 2.8194 -3.6322) (xy 2.8194 1.18364) (xy 2.450084 1.18364)
				(xy 2.450084 -2.999994) (xy -2.450084 -2.999994) (xy -2.450084 2.999994) (xy 2.450084 2.999994)
				(xy 2.450084 1.18618) (xy 2.8194 1.18618) (xy 2.8194 3.6322)
			)
			(stroke
				(width 0)
				(type default)
			)
			(fill no)
			(layer "F.CrtYd")
		)
		(fp_rect
			(start -2.8194 3.6322)
			(end 2.8194 -3.6322)
			(stroke
				(width 0)
				(type default)
			)
			(fill no)
			(layer "F.Fab")
		)
		(pad "1" smd rect
			(at -1.905 2.54 270)
			(size 0.635 1.651)
			(layers "F.Cu" "F.Mask" "F.Paste")
			(net "P5V_HDD33")
		)
		(pad "2" smd rect
			(at -0.635 2.54 270)
			(size 0.635 1.651)
			(layers "F.Cu" "F.Mask" "F.Paste")
			(net "P5V_HDD33")
		)
		(pad "3" smd rect
			(at 0.635 2.54 270)
			(size 0.635 1.651)
			(layers "F.Cu" "F.Mask" "F.Paste")
			(net "P5V_HDD33")
		)
		(pad "4" smd rect
			(at 1.905 2.54 270)
			(size 0.635 1.651)
			(layers "F.Cu" "F.Mask" "F.Paste")
			(net "SW_HDD_P33")
		)
		(pad "5" smd rect
			(at 1.905 -2.54 270)
			(size 0.635 1.651)
			(layers "F.Cu" "F.Mask" "F.Paste")
			(net "P5V_B_4")
		)
		(pad "6" smd rect
			(at 0.635 -2.54 270)
			(size 0.635 1.651)
			(layers "F.Cu" "F.Mask" "F.Paste")
			(net "P5V_B_4")
		)
		(pad "7" smd rect
			(at -0.635 -2.54 270)
			(size 0.635 1.651)
			(layers "F.Cu" "F.Mask" "F.Paste")
			(net "P5V_B_4")
		)
		(pad "8" smd rect
			(at -1.905 -2.54 270)
			(size 0.635 1.651)
			(layers "F.Cu" "F.Mask" "F.Paste")
			(net "P5V_B_4")
		)
	)
	(footprint ""
		(layer "F.Cu")
		(at 176.022 -361.696)
		(property "Reference" "C548"
			(at 0 0 0)
			(layer "F.SilkS")
			(hide yes)
			(effects
				(font
					(size 1.27 1.27)
				)
			)
		)
		(property "Value" "SCD1U25V2KX-2-GP"
			(at 1.1811 -2.7051 0)
			(unlocked yes)
			(layer "F.Fab")
			(hide yes)
			(effects
				(font
					(size 1.016 1.016)
					(thickness 0.1524)
				)
			)
		)
		(property "Device Type" "C402H22"
			(at 1.1811 -4.2291 0)
			(unlocked yes)
			(layer "F.Fab")
			(hide yes)
			(effects
				(font
					(size 1.016 1.016)
					(thickness 0.1524)
				)
			)
		)
		(duplicate_pad_numbers_are_jumpers no)
		(fp_rect
			(start -0.4318 0.9525)
			(end 0.4318 -0.9525)
			(stroke
				(width 0)
				(type default)
			)
			(fill no)
			(layer "F.CrtYd")
		)
		(fp_rect
			(start -0.4318 0.9525)
			(end 0.4318 -0.9525)
			(stroke
				(width 0)
				(type default)
			)
			(fill no)
			(layer "F.Fab")
		)
		(pad "1" smd custom
			(at 0 -0.4445)
			(size 0.1524 0.1524)
			(layers "F.Cu" "F.Mask" "F.Paste")
			(net "MB0_ISTART_R")
			(options
				(clearance outline)
				(anchor circle)
			)
			(primitives
				(gr_poly
					(pts
						(arc
							(start 0.3048 -0.2032)
							(mid 0.275042 -0.275042)
							(end 0.2032 -0.3048)
						)
						(arc
							(start -0.2032 -0.3048)
							(mid -0.275042 -0.275042)
							(end -0.3048 -0.2032)
						)
						(arc
							(start -0.3048 0.2032)
							(mid -0.275042 0.275042)
							(end -0.2032 0.3048)
						)
						(arc
							(start 0.2032 0.3048)
							(mid 0.275042 0.275042)
							(end 0.3048 0.2032)
						)
					)
					(width 0)
					(fill yes)
				)
			)
		)
		(pad "2" smd custom
			(at 0 0.4445)
			(size 0.1524 0.1524)
			(layers "F.Cu" "F.Mask" "F.Paste")
			(net "AGND_CURRENT_MON")
			(options
				(clearance outline)
				(anchor circle)
			)
			(primitives
				(gr_poly
					(pts
						(arc
							(start 0.3048 -0.2032)
							(mid 0.275042 -0.275042)
							(end 0.2032 -0.3048)
						)
						(arc
							(start -0.2032 -0.3048)
							(mid -0.275042 -0.275042)
							(end -0.3048 -0.2032)
						)
						(arc
							(start -0.3048 0.2032)
							(mid -0.275042 0.275042)
							(end -0.2032 0.3048)
						)
						(arc
							(start 0.2032 0.3048)
							(mid 0.275042 0.275042)
							(end 0.3048 0.2032)
						)
					)
					(width 0)
					(fill yes)
				)
			)
		)
	)
	(footprint ""
		(layer "F.Cu")
		(at 249.33148 -217.1827 180)
		(property "Reference" "U13"
			(at 0 0 180)
			(layer "F.SilkS")
			(hide yes)
			(effects
				(font
					(size 1.27 1.27)
				)
			)
		)
		(property "Value" "24LC64-I-SN-GP"
			(at -3.707384 -1.5367 180)
			(unlocked yes)
			(layer "F.Fab")
			(hide yes)
			(effects
				(font
					(size 1.016 1.016)
					(thickness 0.1524)
				)
			)
		)
		(property "Device Type" "SOIC8H69"
			(at -3.707384 -3.0607 180)
			(unlocked yes)
			(layer "F.Fab")
			(hide yes)
			(effects
				(font
					(size 1.016 1.016)
					(thickness 0.1524)
				)
			)
		)
		(duplicate_pad_numbers_are_jumpers no)
		(fp_line
			(start 2.1336 1.4224)
			(end 2.1336 -1.4224)
			(stroke
				(width 0.1524)
				(type default)
			)
			(layer "F.SilkS")
		)
		(fp_line
			(start 2.1336 -1.4224)
			(end -2.7432 -1.4224)
			(stroke
				(width 0.1524)
				(type default)
			)
			(layer "F.SilkS")
		)
		(fp_line
			(start -2.1844 -0.0508)
			(end -2.7178 0.508)
			(stroke
				(width 0.1524)
				(type default)
			)
			(layer "F.SilkS")
		)
		(fp_line
			(start -2.6289 3.4417)
			(end -2.6289 1.4732)
			(stroke
				(width 0.381)
				(type default)
			)
			(layer "F.SilkS")
		)
		(fp_line
			(start -2.7178 -0.508)
			(end -2.1844 -0.0508)
			(stroke
				(width 0.1524)
				(type default)
			)
			(layer "F.SilkS")
		)
		(fp_line
			(start -2.7432 1.4224)
			(end 2.1336 1.4224)
			(stroke
				(width 0.1524)
				(type default)
			)
			(layer "F.SilkS")
		)
		(fp_line
			(start -2.7432 1.4224)
			(end -2.6416 1.4224)
			(stroke
				(width 0.1524)
				(type default)
			)
			(layer "F.SilkS")
		)
		(fp_line
			(start -2.7432 -1.4224)
			(end -2.7432 1.4224)
			(stroke
				(width 0.1524)
				(type default)
			)
			(layer "F.SilkS")
		)
		(fp_poly
			(pts
				(xy -2.2098 -1.4224) (xy -2.2098 1.4224) (xy 2.2098 1.4224) (xy 2.2098 -1.4224)
			)
			(stroke
				(width 0)
				(type default)
			)
			(fill yes)
			(layer "F.SilkS")
		)
		(fp_rect
			(start -2.450084 2.999994)
			(end 2.450084 -2.999994)
			(stroke
				(width 0)
				(type default)
			)
			(fill no)
			(layer "F.CrtYd")
		)
		(fp_poly
			(pts
				(xy -2.8194 3.6322) (xy -2.8194 -3.6322) (xy 2.8194 -3.6322) (xy 2.8194 1.18364) (xy 2.450084 1.18364)
				(xy 2.450084 -2.999994) (xy -2.450084 -2.999994) (xy -2.450084 2.999994) (xy 2.450084 2.999994)
				(xy 2.450084 1.18618) (xy 2.8194 1.18618) (xy 2.8194 3.6322)
			)
			(stroke
				(width 0)
				(type default)
			)
			(fill no)
			(layer "F.CrtYd")
		)
		(fp_rect
			(start -2.8194 3.6322)
			(end 2.8194 -3.6322)
			(stroke
				(width 0)
				(type default)
			)
			(fill no)
			(layer "F.Fab")
		)
		(pad "1" smd rect
			(at -1.905 2.54 180)
			(size 0.635 1.651)
			(layers "F.Cu" "F.Mask" "F.Paste")
			(net "EEPROM_A0")
		)
		(pad "2" smd rect
			(at -0.635 2.54 180)
			(size 0.635 1.651)
			(layers "F.Cu" "F.Mask" "F.Paste")
			(net "EEPROM_A1")
		)
		(pad "3" smd rect
			(at 0.635 2.54 180)
			(size 0.635 1.651)
			(layers "F.Cu" "F.Mask" "F.Paste")
			(net "EEPROM_A2")
		)
		(pad "4" smd rect
			(at 1.905 2.54 180)
			(size 0.635 1.651)
			(layers "F.Cu" "F.Mask" "F.Paste")
			(net "GND")
		)
		(pad "5" smd rect
			(at 1.905 -2.54 180)
			(size 0.635 1.651)
			(layers "F.Cu" "F.Mask" "F.Paste")
			(net "EEPROM_SDA")
		)
		(pad "6" smd rect
			(at 0.635 -2.54 180)
			(size 0.635 1.651)
			(layers "F.Cu" "F.Mask" "F.Paste")
			(net "EEPROM_SCL")
		)
		(pad "7" smd rect
			(at -0.635 -2.54 180)
			(size 0.635 1.651)
			(layers "F.Cu" "F.Mask" "F.Paste")
			(net "EEPROM_WP")
		)
		(pad "8" smd rect
			(at -1.905 -2.54 180)
			(size 0.635 1.651)
			(layers "F.Cu" "F.Mask" "F.Paste")
			(net "P3V3_STBY_B")
		)
	)
	(footprint ""
		(layer "F.Cu")
		(at 127.113284 -14.660626 90)
		(property "Reference" "C380"
			(at 0 0 90)
			(layer "F.SilkS")
			(hide yes)
			(effects
				(font
					(size 1.27 1.27)
				)
			)
		)
		(property "Value" "SCD01U16V1KX-GP"
			(at -2.8321 -1.7399 90)
			(unlocked yes)
			(layer "F.Fab")
			(hide yes)
			(effects
				(font
					(size 1.016 1.016)
					(thickness 0.1524)
				)
			)
		)
		(property "Device Type" "C0201H13"
			(at -2.8321 -3.2639 90)
			(unlocked yes)
			(layer "F.Fab")
			(hide yes)
			(effects
				(font
					(size 1.016 1.016)
					(thickness 0.1524)
				)
			)
		)
		(duplicate_pad_numbers_are_jumpers no)
		(fp_rect
			(start -0.2794 0.6477)
			(end 0.2794 -0.6477)
			(stroke
				(width 0)
				(type default)
			)
			(fill no)
			(layer "F.CrtYd")
		)
		(fp_rect
			(start -0.2794 0.6477)
			(end 0.2794 -0.6477)
			(stroke
				(width 0)
				(type default)
			)
			(fill no)
			(layer "F.Fab")
		)
		(pad "1" smd custom
			(at 0 -0.2794 90)
			(size 0.0762 0.0762)
			(layers "F.Cu" "F.Mask" "F.Paste")
			(net "SAS_HDD_RX_P27")
			(options
				(clearance outline)
				(anchor circle)
			)
			(primitives
				(gr_poly
					(pts
						(arc
							(start 0.1524 -0.127)
							(mid 0.137521 -0.162921)
							(end 0.1016 -0.1778)
						)
						(arc
							(start -0.1016 -0.1778)
							(mid -0.137521 -0.162921)
							(end -0.1524 -0.127)
						)
						(arc
							(start -0.1524 0.127)
							(mid -0.137521 0.162921)
							(end -0.1016 0.1778)
						)
						(arc
							(start 0.1016 0.1778)
							(mid 0.137521 0.162921)
							(end 0.1524 0.127)
						)
					)
					(width 0)
					(fill yes)
				)
			)
		)
		(pad "2" smd custom
			(at 0 0.2794 90)
			(size 0.0762 0.0762)
			(layers "F.Cu" "F.Mask" "F.Paste")
			(net "PHY_SCC_B_TO_DRV_B_27_DP")
			(options
				(clearance outline)
				(anchor circle)
			)
			(primitives
				(gr_poly
					(pts
						(arc
							(start 0.1524 -0.127)
							(mid 0.137521 -0.162921)
							(end 0.1016 -0.1778)
						)
						(arc
							(start -0.1016 -0.1778)
							(mid -0.137521 -0.162921)
							(end -0.1524 -0.127)
						)
						(arc
							(start -0.1524 0.127)
							(mid -0.137521 0.162921)
							(end -0.1016 0.1778)
						)
						(arc
							(start 0.1016 0.1778)
							(mid 0.137521 0.162921)
							(end 0.1524 0.127)
						)
					)
					(width 0)
					(fill yes)
				)
			)
		)
	)
	(footprint ""
		(layer "F.Cu")
		(at 176.276 -19.939 -90)
		(property "Reference" "R744"
			(at 0 0 270)
			(layer "F.SilkS")
			(hide yes)
			(effects
				(font
					(size 1.27 1.27)
				)
			)
		)
		(property "Value" "4K7R2J-2-GP"
			(at 0.064008 -3.993896 270)
			(unlocked yes)
			(layer "F.Fab")
			(hide yes)
			(effects
				(font
					(size 1.016 1.016)
					(thickness 0.1524)
				)
			)
		)
		(property "Device Type" "R402H16"
			(at 0.064008 -5.517896 270)
			(unlocked yes)
			(layer "F.Fab")
			(hide yes)
			(effects
				(font
					(size 1.016 1.016)
					(thickness 0.1524)
				)
			)
		)
		(duplicate_pad_numbers_are_jumpers no)
		(fp_line
			(start -0.508 -0.9398)
			(end -0.508 0.9398)
			(stroke
				(width 0.1524)
				(type default)
			)
			(layer "F.SilkS")
		)
		(fp_line
			(start 0.508 -0.9398)
			(end -0.508 -0.9398)
			(stroke
				(width 0.1524)
				(type default)
			)
			(layer "F.SilkS")
		)
		(fp_rect
			(start -0.508 0.9398)
			(end 0.508 -0.9398)
			(stroke
				(width 0)
				(type default)
			)
			(fill no)
			(layer "F.CrtYd")
		)
		(fp_rect
			(start -0.508 0.9398)
			(end 0.508 -0.9398)
			(stroke
				(width 0)
				(type default)
			)
			(fill no)
			(layer "F.Fab")
		)
		(pad "1" smd custom
			(at 0 -0.4445 270)
			(size 0.1397 0.1397)
			(layers "F.Cu" "F.Mask" "F.Paste")
			(net "P12V_B")
			(options
				(clearance outline)
				(anchor circle)
			)
			(primitives
				(gr_poly
					(pts
						(arc
							(start -0.1778 -0.2794)
							(mid -0.249642 -0.249642)
							(end -0.2794 -0.1778)
						)
						(arc
							(start -0.2794 0.1778)
							(mid -0.249642 0.249642)
							(end -0.1778 0.2794)
						)
						(arc
							(start 0.1778 0.2794)
							(mid 0.249642 0.249642)
							(end 0.2794 0.1778)
						)
						(arc
							(start 0.2794 -0.1778)
							(mid 0.249642 -0.249642)
							(end 0.1778 -0.2794)
						)
					)
					(width 0)
					(fill yes)
				)
			)
		)
		(pad "2" smd custom
			(at 0 0.4445 270)
			(size 0.1397 0.1397)
			(layers "F.Cu" "F.Mask" "F.Paste")
			(net "SW_HDD_P29")
			(options
				(clearance outline)
				(anchor circle)
			)
			(primitives
				(gr_poly
					(pts
						(arc
							(start -0.1778 -0.2794)
							(mid -0.249642 -0.249642)
							(end -0.2794 -0.1778)
						)
						(arc
							(start -0.2794 0.1778)
							(mid -0.249642 0.249642)
							(end -0.1778 0.2794)
						)
						(arc
							(start 0.1778 0.2794)
							(mid 0.249642 0.249642)
							(end 0.2794 0.1778)
						)
						(arc
							(start 0.2794 -0.1778)
							(mid 0.249642 -0.249642)
							(end 0.1778 -0.2794)
						)
					)
					(width 0)
					(fill yes)
				)
			)
		)
	)
	(footprint ""
		(layer "F.Cu")
		(at 141.097 -260.858)
		(property "Reference" "Q16"
			(at 0 0 0)
			(layer "F.SilkS")
			(hide yes)
			(effects
				(font
					(size 1.27 1.27)
				)
			)
		)
		(property "Value" "AO4407AL-GP"
			(at -3.707384 -1.5367 0)
			(unlocked yes)
			(layer "F.Fab")
			(hide yes)
			(effects
				(font
					(size 1.016 1.016)
					(thickness 0.1524)
				)
			)
		)
		(property "Device Type" "SOIC8H69"
			(at -3.707384 -3.0607 0)
			(unlocked yes)
			(layer "F.Fab")
			(hide yes)
			(effects
				(font
					(size 1.016 1.016)
					(thickness 0.1524)
				)
			)
		)
		(duplicate_pad_numbers_are_jumpers no)
		(fp_line
			(start -2.7432 -1.4224)
			(end -2.7432 1.4224)
			(stroke
				(width 0.1524)
				(type default)
			)
			(layer "F.SilkS")
		)
		(fp_line
			(start -2.7432 1.4224)
			(end -2.6416 1.4224)
			(stroke
				(width 0.1524)
				(type default)
			)
			(layer "F.SilkS")
		)
		(fp_line
			(start -2.7432 1.4224)
			(end 2.1336 1.4224)
			(stroke
				(width 0.1524)
				(type default)
			)
			(layer "F.SilkS")
		)
		(fp_line
			(start -2.7178 -0.508)
			(end -2.1844 -0.0508)
			(stroke
				(width 0.1524)
				(type default)
			)
			(layer "F.SilkS")
		)
		(fp_line
			(start -2.6289 3.4417)
			(end -2.6289 1.4732)
			(stroke
				(width 0.381)
				(type default)
			)
			(layer "F.SilkS")
		)
		(fp_line
			(start -2.1844 -0.0508)
			(end -2.7178 0.508)
			(stroke
				(width 0.1524)
				(type default)
			)
			(layer "F.SilkS")
		)
		(fp_line
			(start 2.1336 -1.4224)
			(end -2.7432 -1.4224)
			(stroke
				(width 0.1524)
				(type default)
			)
			(layer "F.SilkS")
		)
		(fp_line
			(start 2.1336 1.4224)
			(end 2.1336 -1.4224)
			(stroke
				(width 0.1524)
				(type default)
			)
			(layer "F.SilkS")
		)
		(fp_poly
			(pts
				(xy -2.2098 -1.4224) (xy -2.2098 1.4224) (xy 2.2098 1.4224) (xy 2.2098 -1.4224)
			)
			(stroke
				(width 0)
				(type default)
			)
			(fill yes)
			(layer "F.SilkS")
		)
		(fp_rect
			(start -2.450084 2.999994)
			(end 2.450084 -2.999994)
			(stroke
				(width 0)
				(type default)
			)
			(fill no)
			(layer "F.CrtYd")
		)
		(fp_poly
			(pts
				(xy -2.8194 3.6322) (xy -2.8194 -3.6322) (xy 2.8194 -3.6322) (xy 2.8194 1.18364) (xy 2.450084 1.18364)
				(xy 2.450084 -2.999994) (xy -2.450084 -2.999994) (xy -2.450084 2.999994) (xy 2.450084 2.999994)
				(xy 2.450084 1.18618) (xy 2.8194 1.18618) (xy 2.8194 3.6322)
			)
			(stroke
				(width 0)
				(type default)
			)
			(fill no)
			(layer "F.CrtYd")
		)
		(fp_rect
			(start -2.8194 3.6322)
			(end 2.8194 -3.6322)
			(stroke
				(width 0)
				(type default)
			)
			(fill no)
			(layer "F.Fab")
		)
		(pad "1" smd rect
			(at -1.905 2.54)
			(size 0.635 1.651)
			(layers "F.Cu" "F.Mask" "F.Paste")
			(net "P12V_B")
		)
		(pad "2" smd rect
			(at -0.635 2.54)
			(size 0.635 1.651)
			(layers "F.Cu" "F.Mask" "F.Paste")
			(net "P12V_B")
		)
		(pad "3" smd rect
			(at 0.635 2.54)
			(size 0.635 1.651)
			(layers "F.Cu" "F.Mask" "F.Paste")
			(net "P12V_B")
		)
		(pad "4" smd rect
			(at 1.905 2.54)
			(size 0.635 1.651)
			(layers "F.Cu" "F.Mask" "F.Paste")
			(net "SW_HDD_N4")
		)
		(pad "5" smd rect
			(at 1.905 -2.54)
			(size 0.635 1.651)
			(layers "F.Cu" "F.Mask" "F.Paste")
			(net "P12V_HDD4")
		)
		(pad "6" smd rect
			(at 0.635 -2.54)
			(size 0.635 1.651)
			(layers "F.Cu" "F.Mask" "F.Paste")
			(net "P12V_HDD4")
		)
		(pad "7" smd rect
			(at -0.635 -2.54)
			(size 0.635 1.651)
			(layers "F.Cu" "F.Mask" "F.Paste")
			(net "P12V_HDD4")
		)
		(pad "8" smd rect
			(at -1.905 -2.54)
			(size 0.635 1.651)
			(layers "F.Cu" "F.Mask" "F.Paste")
			(net "P12V_HDD4")
		)
	)
	(footprint ""
		(layer "F.Cu")
		(at 208.90738 -247.88622 180)
		(property "Reference" "R38"
			(at 0 0 180)
			(layer "F.SilkS")
			(hide yes)
			(effects
				(font
					(size 1.27 1.27)
				)
			)
		)
		(property "Value" "4K7R2F-GP"
			(at 0.064008 -3.993896 180)
			(unlocked yes)
			(layer "F.Fab")
			(hide yes)
			(effects
				(font
					(size 1.016 1.016)
					(thickness 0.1524)
				)
			)
		)
		(property "Device Type" "R402H16"
			(at 0.064008 -5.517896 180)
			(unlocked yes)
			(layer "F.Fab")
			(hide yes)
			(effects
				(font
					(size 1.016 1.016)
					(thickness 0.1524)
				)
			)
		)
		(duplicate_pad_numbers_are_jumpers no)
		(fp_line
			(start 0.508 -0.9398)
			(end -0.508 -0.9398)
			(stroke
				(width 0.1524)
				(type default)
			)
			(layer "F.SilkS")
		)
		(fp_line
			(start -0.508 -0.9398)
			(end -0.508 0.9398)
			(stroke
				(width 0.1524)
				(type default)
			)
			(layer "F.SilkS")
		)
		(fp_rect
			(start -0.508 0.9398)
			(end 0.508 -0.9398)
			(stroke
				(width 0)
				(type default)
			)
			(fill no)
			(layer "F.CrtYd")
		)
		(fp_rect
			(start -0.508 0.9398)
			(end 0.508 -0.9398)
			(stroke
				(width 0)
				(type default)
			)
			(fill no)
			(layer "F.Fab")
		)
		(pad "1" smd custom
			(at 0 -0.4445 180)
			(size 0.1397 0.1397)
			(layers "F.Cu" "F.Mask" "F.Paste")
			(net "IO_EXP4_A2")
			(options
				(clearance outline)
				(anchor circle)
			)
			(primitives
				(gr_poly
					(pts
						(arc
							(start -0.1778 -0.2794)
							(mid -0.249642 -0.249642)
							(end -0.2794 -0.1778)
						)
						(arc
							(start -0.2794 0.1778)
							(mid -0.249642 0.249642)
							(end -0.1778 0.2794)
						)
						(arc
							(start 0.1778 0.2794)
							(mid 0.249642 0.249642)
							(end 0.2794 0.1778)
						)
						(arc
							(start 0.2794 -0.1778)
							(mid 0.249642 -0.249642)
							(end 0.1778 -0.2794)
						)
					)
					(width 0)
					(fill yes)
				)
			)
		)
		(pad "2" smd custom
			(at 0 0.4445 180)
			(size 0.1397 0.1397)
			(layers "F.Cu" "F.Mask" "F.Paste")
			(net "GND")
			(options
				(clearance outline)
				(anchor circle)
			)
			(primitives
				(gr_poly
					(pts
						(arc
							(start -0.1778 -0.2794)
							(mid -0.249642 -0.249642)
							(end -0.2794 -0.1778)
						)
						(arc
							(start -0.2794 0.1778)
							(mid -0.249642 0.249642)
							(end -0.1778 0.2794)
						)
						(arc
							(start 0.1778 0.2794)
							(mid 0.249642 0.249642)
							(end 0.2794 0.1778)
						)
						(arc
							(start 0.2794 -0.1778)
							(mid 0.249642 -0.249642)
							(end 0.1778 -0.2794)
						)
					)
					(width 0)
					(fill yes)
				)
			)
		)
	)
	(footprint ""
		(layer "F.Cu")
		(at 449.78955 -248.750074 -90)
		(property "Reference" "VIA22"
			(at 0 0 270)
			(layer "F.SilkS")
			(hide yes)
			(effects
				(font
					(size 1.27 1.27)
				)
			)
		)
		(property "Value" "100OHM-8L-2D36MM-L16-GP"
			(at -3.4036 -0.4572 270)
			(unlocked yes)
			(layer "F.Fab")
			(hide yes)
			(effects
				(font
					(size 1.016 1.016)
					(thickness 0.1524)
				)
			)
		)
		(property "Device Type" "VIA-PCIE-4P-427097"
			(at -3.4036 -1.9812 270)
			(unlocked yes)
			(layer "F.Fab")
			(hide yes)
			(effects
				(font
					(size 1.016 1.016)
					(thickness 0.1524)
				)
			)
		)
		(duplicate_pad_numbers_are_jumpers no)
		(fp_rect
			(start -2.1336 0.4826)
			(end 2.1336 -0.4826)
			(stroke
				(width 0)
				(type default)
			)
			(fill no)
			(layer "F.CrtYd")
		)
		(fp_rect
			(start -2.1336 0.4826)
			(end 2.1336 -0.4826)
			(stroke
				(width 0)
				(type default)
			)
			(fill no)
			(layer "F.Fab")
		)
		(pad "1" thru_hole circle
			(at -1.651 0 270)
			(size 0.508 0.508)
			(drill 0.254)
			(layers "*.Cu" "*.Mask")
			(remove_unused_layers no)
			(net "GND")
			(clearance 0.2286)
			(thermal_gap 0.2286)
		)
		(pad "2" thru_hole circle
			(at -0.635 0 270)
			(size 0.508 0.508)
			(drill 0.254)
			(layers "*.Cu" "*.Mask")
			(remove_unused_layers no)
			(net "PHY_DRV_B_TO_SCC_B_10_DP")
			(clearance 0.2286)
			(thermal_gap 0.2286)
		)
		(pad "3" thru_hole circle
			(at 0.635 0 270)
			(size 0.508 0.508)
			(drill 0.254)
			(layers "*.Cu" "*.Mask")
			(remove_unused_layers no)
			(net "PHY_DRV_B_TO_SCC_B_10_DN")
			(clearance 0.2286)
			(thermal_gap 0.2286)
		)
		(pad "4" thru_hole circle
			(at 1.651 0 270)
			(size 0.508 0.508)
			(drill 0.254)
			(layers "*.Cu" "*.Mask")
			(remove_unused_layers no)
			(net "GND")
			(clearance 0.2286)
			(thermal_gap 0.2286)
		)
	)
	(footprint ""
		(layer "F.Cu")
		(at 441.349892 -65.39992)
		(property "Reference" "LED23"
			(at 0 0 0)
			(layer "F.SilkS")
			(hide yes)
			(effects
				(font
					(size 1.27 1.27)
				)
			)
		)
		(property "Value" "LED-BY-19-GP"
			(at -2.132076 1.414018 0)
			(unlocked yes)
			(layer "F.Fab")
			(hide yes)
			(effects
				(font
					(size 1.016 1.016)
					(thickness 0.1524)
				)
			)
		)
		(property "Device Type" "LED-1615-4PH26"
			(at -2.132076 -0.109982 0)
			(unlocked yes)
			(layer "F.Fab")
			(hide yes)
			(effects
				(font
					(size 1.016 1.016)
					(thickness 0.1524)
				)
			)
		)
		(duplicate_pad_numbers_are_jumpers no)
		(fp_line
			(start -1.2954 0.254)
			(end -1.2954 1.6002)
			(stroke
				(width 0.508)
				(type default)
			)
			(layer "F.SilkS")
		)
		(fp_line
			(start -1.2954 1.6002)
			(end 1.2954 1.6002)
			(stroke
				(width 0.508)
				(type default)
			)
			(layer "F.SilkS")
		)
		(fp_line
			(start -1.1176 -1.4224)
			(end 1.1176 -1.4224)
			(stroke
				(width 0.1524)
				(type default)
			)
			(layer "F.SilkS")
		)
		(fp_line
			(start -1.1176 1.4224)
			(end -1.1176 -1.4224)
			(stroke
				(width 0.1524)
				(type default)
			)
			(layer "F.SilkS")
		)
		(fp_line
			(start 1.1176 -1.4224)
			(end 1.1176 1.4224)
			(stroke
				(width 0.1524)
				(type default)
			)
			(layer "F.SilkS")
		)
		(fp_line
			(start 1.1176 1.4224)
			(end -1.1176 1.4224)
			(stroke
				(width 0.1524)
				(type default)
			)
			(layer "F.SilkS")
		)
		(fp_line
			(start 1.2954 1.6002)
			(end 1.2954 0.254)
			(stroke
				(width 0.508)
				(type default)
			)
			(layer "F.SilkS")
		)
		(fp_rect
			(start -0.7493 0.8001)
			(end 0.7493 -0.8001)
			(stroke
				(width 0)
				(type default)
			)
			(fill no)
			(layer "F.CrtYd")
		)
		(fp_poly
			(pts
				(xy -1.3716 1.6764) (xy -1.3716 -1.6764) (xy 1.3716 -1.6764) (xy 1.3716 0.0635) (xy 0.7493 0.0635)
				(xy 0.7493 -0.8001) (xy -0.7493 -0.8001) (xy -0.7493 0.8001) (xy 0.7493 0.8001) (xy 0.7493 0.0762)
				(xy 1.3716 0.0762) (xy 1.3716 1.6764)
			)
			(stroke
				(width 0)
				(type default)
			)
			(fill no)
			(layer "F.CrtYd")
		)
		(fp_rect
			(start -1.3716 1.6764)
			(end 1.3716 -1.6764)
			(stroke
				(width 0)
				(type default)
			)
			(fill no)
			(layer "F.Fab")
		)
		(pad "1" smd rect
			(at 0.50038 -0.73025)
			(size 0.7112 0.8636)
			(layers "F.Cu" "F.Mask" "F.Paste")
			(net "DRV_ACT_22")
		)
		(pad "2" smd rect
			(at -0.50038 -0.73025)
			(size 0.7112 0.8636)
			(layers "F.Cu" "F.Mask" "F.Paste")
			(net "FLT_HDD22")
		)
		(pad "3" smd rect
			(at 0.50038 0.73025)
			(size 0.7112 0.8636)
			(layers "F.Cu" "F.Mask" "F.Paste")
			(net "DRV_ACT_22_N")
		)
		(pad "4" smd rect
			(at -0.50038 0.73025)
			(size 0.7112 0.8636)
			(layers "F.Cu" "F.Mask" "F.Paste")
			(net "FLT_HDD22_N")
		)
	)
	(footprint ""
		(layer "F.Cu")
		(at 447.834512 -244.660674 -90)
		(property "Reference" "C159"
			(at 0 0 270)
			(layer "F.SilkS")
			(hide yes)
			(effects
				(font
					(size 1.27 1.27)
				)
			)
		)
		(property "Value" "SCD01U16V1KX-GP"
			(at -2.8321 -1.7399 270)
			(unlocked yes)
			(layer "F.Fab")
			(hide yes)
			(effects
				(font
					(size 1.016 1.016)
					(thickness 0.1524)
				)
			)
		)
		(property "Device Type" "C0201H13"
			(at -2.8321 -3.2639 270)
			(unlocked yes)
			(layer "F.Fab")
			(hide yes)
			(effects
				(font
					(size 1.016 1.016)
					(thickness 0.1524)
				)
			)
		)
		(duplicate_pad_numbers_are_jumpers no)
		(fp_rect
			(start -0.2794 0.6477)
			(end 0.2794 -0.6477)
			(stroke
				(width 0)
				(type default)
			)
			(fill no)
			(layer "F.CrtYd")
		)
		(fp_rect
			(start -0.2794 0.6477)
			(end 0.2794 -0.6477)
			(stroke
				(width 0)
				(type default)
			)
			(fill no)
			(layer "F.Fab")
		)
		(pad "1" smd custom
			(at 0 -0.2794 270)
			(size 0.0762 0.0762)
			(layers "F.Cu" "F.Mask" "F.Paste")
			(net "SAS_HDD_RX_P10")
			(options
				(clearance outline)
				(anchor circle)
			)
			(primitives
				(gr_poly
					(pts
						(arc
							(start 0.1524 -0.127)
							(mid 0.137521 -0.162921)
							(end 0.1016 -0.1778)
						)
						(arc
							(start -0.1016 -0.1778)
							(mid -0.137521 -0.162921)
							(end -0.1524 -0.127)
						)
						(arc
							(start -0.1524 0.127)
							(mid -0.137521 0.162921)
							(end -0.1016 0.1778)
						)
						(arc
							(start 0.1016 0.1778)
							(mid 0.137521 0.162921)
							(end 0.1524 0.127)
						)
					)
					(width 0)
					(fill yes)
				)
			)
		)
		(pad "2" smd custom
			(at 0 0.2794 270)
			(size 0.0762 0.0762)
			(layers "F.Cu" "F.Mask" "F.Paste")
			(net "PHY_SCC_B_TO_DRV_B_10_DP")
			(options
				(clearance outline)
				(anchor circle)
			)
			(primitives
				(gr_poly
					(pts
						(arc
							(start 0.1524 -0.127)
							(mid 0.137521 -0.162921)
							(end 0.1016 -0.1778)
						)
						(arc
							(start -0.1016 -0.1778)
							(mid -0.137521 -0.162921)
							(end -0.1524 -0.127)
						)
						(arc
							(start -0.1524 0.127)
							(mid -0.137521 0.162921)
							(end -0.1016 0.1778)
						)
						(arc
							(start 0.1016 0.1778)
							(mid 0.137521 0.162921)
							(end 0.1524 0.127)
						)
					)
					(width 0)
					(fill yes)
				)
			)
		)
	)
	(footprint ""
		(layer "F.Cu")
		(at 67.31 -32.8168 180)
		(property "Reference" "R649"
			(at 0 0 180)
			(layer "F.SilkS")
			(hide yes)
			(effects
				(font
					(size 1.27 1.27)
				)
			)
		)
		(property "Value" "220R3F-1-GP"
			(at -0.0254 -2.5146 180)
			(unlocked yes)
			(layer "F.Fab")
			(hide yes)
			(effects
				(font
					(size 1.016 1.016)
					(thickness 0.1524)
				)
			)
		)
		(property "Device Type" "R603H22"
			(at -0.0254 -4.0386 180)
			(unlocked yes)
			(layer "F.Fab")
			(hide yes)
			(effects
				(font
					(size 1.016 1.016)
					(thickness 0.1524)
				)
			)
		)
		(duplicate_pad_numbers_are_jumpers no)
		(fp_line
			(start 0.2032 0)
			(end 0.4826 0)
			(stroke
				(width 0.2032)
				(type default)
			)
			(layer "F.SilkS")
		)
		(fp_line
			(start -0.4826 0)
			(end -0.2032 0)
			(stroke
				(width 0.2032)
				(type default)
			)
			(layer "F.SilkS")
		)
		(fp_rect
			(start -0.5842 1.3335)
			(end 0.5842 -1.3335)
			(stroke
				(width 0)
				(type default)
			)
			(fill no)
			(layer "F.CrtYd")
		)
		(fp_rect
			(start -0.5842 1.3335)
			(end 0.5842 -1.3335)
			(stroke
				(width 0)
				(type default)
			)
			(fill no)
			(layer "F.Fab")
		)
		(pad "1" smd custom
			(at 0 -0.762 180)
			(size 0.2159 0.2159)
			(layers "F.Cu" "F.Mask" "F.Paste")
			(net "HDD_PRSNT_25")
			(options
				(clearance outline)
				(anchor circle)
			)
			(primitives
				(gr_poly
					(pts
						(arc
							(start -0.3302 -0.4318)
							(mid -0.402042 -0.402042)
							(end -0.4318 -0.3302)
						)
						(arc
							(start -0.4318 0.3302)
							(mid -0.402042 0.402042)
							(end -0.3302 0.4318)
						)
						(arc
							(start 0.3302 0.4318)
							(mid 0.402042 0.402042)
							(end 0.4318 0.3302)
						)
						(arc
							(start 0.4318 -0.3302)
							(mid 0.402042 -0.402042)
							(end 0.3302 -0.4318)
						)
					)
					(width 0)
					(fill yes)
				)
			)
		)
		(pad "2" smd custom
			(at 0 0.762 180)
			(size 0.2159 0.2159)
			(layers "F.Cu" "F.Mask" "F.Paste")
			(net "DRIVE_B_25_INS")
			(options
				(clearance outline)
				(anchor circle)
			)
			(primitives
				(gr_poly
					(pts
						(arc
							(start -0.3302 -0.4318)
							(mid -0.402042 -0.402042)
							(end -0.4318 -0.3302)
						)
						(arc
							(start -0.4318 0.3302)
							(mid -0.402042 0.402042)
							(end -0.3302 0.4318)
						)
						(arc
							(start 0.3302 0.4318)
							(mid 0.402042 0.402042)
							(end 0.4318 0.3302)
						)
						(arc
							(start 0.4318 -0.3302)
							(mid 0.402042 -0.402042)
							(end 0.3302 -0.4318)
						)
					)
					(width 0)
					(fill yes)
				)
			)
		)
	)
	(footprint ""
		(layer "F.Cu")
		(at 234.2134 -192.786 180)
		(property "Reference" "R512"
			(at 0 0 180)
			(layer "F.SilkS")
			(hide yes)
			(effects
				(font
					(size 1.27 1.27)
				)
			)
		)
		(property "Value" "100KR2F-L1-GP"
			(at 0.064008 -3.993896 180)
			(unlocked yes)
			(layer "F.Fab")
			(hide yes)
			(effects
				(font
					(size 1.016 1.016)
					(thickness 0.1524)
				)
			)
		)
		(property "Device Type" "R402H16"
			(at 0.064008 -5.517896 180)
			(unlocked yes)
			(layer "F.Fab")
			(hide yes)
			(effects
				(font
					(size 1.016 1.016)
					(thickness 0.1524)
				)
			)
		)
		(duplicate_pad_numbers_are_jumpers no)
		(fp_line
			(start 0.508 -0.9398)
			(end -0.508 -0.9398)
			(stroke
				(width 0.1524)
				(type default)
			)
			(layer "F.SilkS")
		)
		(fp_line
			(start -0.508 -0.9398)
			(end -0.508 0.9398)
			(stroke
				(width 0.1524)
				(type default)
			)
			(layer "F.SilkS")
		)
		(fp_rect
			(start -0.508 0.9398)
			(end 0.508 -0.9398)
			(stroke
				(width 0)
				(type default)
			)
			(fill no)
			(layer "F.CrtYd")
		)
		(fp_rect
			(start -0.508 0.9398)
			(end 0.508 -0.9398)
			(stroke
				(width 0)
				(type default)
			)
			(fill no)
			(layer "F.Fab")
		)
		(pad "1" smd custom
			(at 0 -0.4445 180)
			(size 0.1397 0.1397)
			(layers "F.Cu" "F.Mask" "F.Paste")
			(net "GPIO_VCC_U9")
			(options
				(clearance outline)
				(anchor circle)
			)
			(primitives
				(gr_poly
					(pts
						(arc
							(start -0.1778 -0.2794)
							(mid -0.249642 -0.249642)
							(end -0.2794 -0.1778)
						)
						(arc
							(start -0.2794 0.1778)
							(mid -0.249642 0.249642)
							(end -0.1778 0.2794)
						)
						(arc
							(start 0.1778 0.2794)
							(mid 0.249642 0.249642)
							(end 0.2794 0.1778)
						)
						(arc
							(start 0.2794 -0.1778)
							(mid 0.249642 -0.249642)
							(end 0.1778 -0.2794)
						)
					)
					(width 0)
					(fill yes)
				)
			)
		)
		(pad "2" smd custom
			(at 0 0.4445 180)
			(size 0.1397 0.1397)
			(layers "F.Cu" "F.Mask" "F.Paste")
			(net "GND")
			(options
				(clearance outline)
				(anchor circle)
			)
			(primitives
				(gr_poly
					(pts
						(arc
							(start -0.1778 -0.2794)
							(mid -0.249642 -0.249642)
							(end -0.2794 -0.1778)
						)
						(arc
							(start -0.2794 0.1778)
							(mid -0.249642 0.249642)
							(end -0.1778 0.2794)
						)
						(arc
							(start 0.1778 0.2794)
							(mid 0.249642 0.249642)
							(end 0.2794 0.1778)
						)
						(arc
							(start 0.2794 -0.1778)
							(mid 0.249642 -0.249642)
							(end 0.1778 -0.2794)
						)
					)
					(width 0)
					(fill yes)
				)
			)
		)
	)
	(footprint ""
		(layer "F.Cu")
		(at 304.138076 -327.858882)
		(property "Reference" "R97"
			(at 0 0 0)
			(layer "F.SilkS")
			(hide yes)
			(effects
				(font
					(size 1.27 1.27)
				)
			)
		)
		(property "Value" "100KR2F-L1-GP"
			(at 0.064008 -3.993896 0)
			(unlocked yes)
			(layer "F.Fab")
			(hide yes)
			(effects
				(font
					(size 1.016 1.016)
					(thickness 0.1524)
				)
			)
		)
		(property "Device Type" "R402H16"
			(at 0.064008 -5.517896 0)
			(unlocked yes)
			(layer "F.Fab")
			(hide yes)
			(effects
				(font
					(size 1.016 1.016)
					(thickness 0.1524)
				)
			)
		)
		(duplicate_pad_numbers_are_jumpers no)
		(fp_line
			(start -0.508 -0.9398)
			(end -0.508 0.9398)
			(stroke
				(width 0.1524)
				(type default)
			)
			(layer "F.SilkS")
		)
		(fp_line
			(start 0.508 -0.9398)
			(end -0.508 -0.9398)
			(stroke
				(width 0.1524)
				(type default)
			)
			(layer "F.SilkS")
		)
		(fp_rect
			(start -0.508 0.9398)
			(end 0.508 -0.9398)
			(stroke
				(width 0)
				(type default)
			)
			(fill no)
			(layer "F.CrtYd")
		)
		(fp_rect
			(start -0.508 0.9398)
			(end 0.508 -0.9398)
			(stroke
				(width 0)
				(type default)
			)
			(fill no)
			(layer "F.Fab")
		)
		(pad "1" smd custom
			(at 0 -0.4445)
			(size 0.1397 0.1397)
			(layers "F.Cu" "F.Mask" "F.Paste")
			(net "PWM_BMC_A_ZONE_C")
			(options
				(clearance outline)
				(anchor circle)
			)
			(primitives
				(gr_poly
					(pts
						(arc
							(start -0.1778 -0.2794)
							(mid -0.249642 -0.249642)
							(end -0.2794 -0.1778)
						)
						(arc
							(start -0.2794 0.1778)
							(mid -0.249642 0.249642)
							(end -0.1778 0.2794)
						)
						(arc
							(start 0.1778 0.2794)
							(mid 0.249642 0.249642)
							(end 0.2794 0.1778)
						)
						(arc
							(start 0.2794 -0.1778)
							(mid 0.249642 -0.249642)
							(end 0.1778 -0.2794)
						)
					)
					(width 0)
					(fill yes)
				)
			)
		)
		(pad "2" smd custom
			(at 0 0.4445)
			(size 0.1397 0.1397)
			(layers "F.Cu" "F.Mask" "F.Paste")
			(net "GND")
			(options
				(clearance outline)
				(anchor circle)
			)
			(primitives
				(gr_poly
					(pts
						(arc
							(start -0.1778 -0.2794)
							(mid -0.249642 -0.249642)
							(end -0.2794 -0.1778)
						)
						(arc
							(start -0.2794 0.1778)
							(mid -0.249642 0.249642)
							(end -0.1778 0.2794)
						)
						(arc
							(start 0.1778 0.2794)
							(mid 0.249642 0.249642)
							(end 0.2794 0.1778)
						)
						(arc
							(start 0.2794 -0.1778)
							(mid 0.249642 -0.249642)
							(end 0.1778 -0.2794)
						)
					)
					(width 0)
					(fill yes)
				)
			)
		)
	)
	(footprint ""
		(layer "F.Cu")
		(at 353.1616 -146.6342)
		(property "Reference" "C281"
			(at 0 0 0)
			(layer "F.SilkS")
			(hide yes)
			(effects
				(font
					(size 1.27 1.27)
				)
			)
		)
		(property "Value" "SCD01U50V2KX-1GP"
			(at 1.1811 -2.7051 0)
			(unlocked yes)
			(layer "F.Fab")
			(hide yes)
			(effects
				(font
					(size 1.016 1.016)
					(thickness 0.1524)
				)
			)
		)
		(property "Device Type" "C402H22"
			(at 1.1811 -4.2291 0)
			(unlocked yes)
			(layer "F.Fab")
			(hide yes)
			(effects
				(font
					(size 1.016 1.016)
					(thickness 0.1524)
				)
			)
		)
		(duplicate_pad_numbers_are_jumpers no)
		(fp_rect
			(start -0.4318 0.9525)
			(end 0.4318 -0.9525)
			(stroke
				(width 0)
				(type default)
			)
			(fill no)
			(layer "F.CrtYd")
		)
		(fp_rect
			(start -0.4318 0.9525)
			(end 0.4318 -0.9525)
			(stroke
				(width 0)
				(type default)
			)
			(fill no)
			(layer "F.Fab")
		)
		(pad "1" smd custom
			(at 0 -0.4445)
			(size 0.1524 0.1524)
			(layers "F.Cu" "F.Mask" "F.Paste")
			(net "HDD_PRSNT_19")
			(options
				(clearance outline)
				(anchor circle)
			)
			(primitives
				(gr_poly
					(pts
						(arc
							(start 0.3048 -0.2032)
							(mid 0.275042 -0.275042)
							(end 0.2032 -0.3048)
						)
						(arc
							(start -0.2032 -0.3048)
							(mid -0.275042 -0.275042)
							(end -0.3048 -0.2032)
						)
						(arc
							(start -0.3048 0.2032)
							(mid -0.275042 0.275042)
							(end -0.2032 0.3048)
						)
						(arc
							(start 0.2032 0.3048)
							(mid 0.275042 0.275042)
							(end 0.3048 0.2032)
						)
					)
					(width 0)
					(fill yes)
				)
			)
		)
		(pad "2" smd custom
			(at 0 0.4445)
			(size 0.1524 0.1524)
			(layers "F.Cu" "F.Mask" "F.Paste")
			(net "GND")
			(options
				(clearance outline)
				(anchor circle)
			)
			(primitives
				(gr_poly
					(pts
						(arc
							(start 0.3048 -0.2032)
							(mid 0.275042 -0.275042)
							(end 0.2032 -0.3048)
						)
						(arc
							(start -0.2032 -0.3048)
							(mid -0.275042 -0.275042)
							(end -0.3048 -0.2032)
						)
						(arc
							(start -0.3048 0.2032)
							(mid -0.275042 0.275042)
							(end -0.2032 0.3048)
						)
						(arc
							(start 0.2032 0.3048)
							(mid 0.275042 0.275042)
							(end 0.3048 0.2032)
						)
					)
					(width 0)
					(fill yes)
				)
			)
		)
	)
	(footprint ""
		(layer "F.Cu")
		(at 236.093 -194.01028 90)
		(property "Reference" "C16"
			(at 0 0 90)
			(layer "F.SilkS")
			(hide yes)
			(effects
				(font
					(size 1.27 1.27)
				)
			)
		)
		(property "Value" "SCD1U16V2KX-3GP"
			(at 1.1811 -2.7051 90)
			(unlocked yes)
			(layer "F.Fab")
			(hide yes)
			(effects
				(font
					(size 1.016 1.016)
					(thickness 0.1524)
				)
			)
		)
		(property "Device Type" "C402H22"
			(at 1.1811 -4.2291 90)
			(unlocked yes)
			(layer "F.Fab")
			(hide yes)
			(effects
				(font
					(size 1.016 1.016)
					(thickness 0.1524)
				)
			)
		)
		(duplicate_pad_numbers_are_jumpers no)
		(fp_rect
			(start -0.4318 0.9525)
			(end 0.4318 -0.9525)
			(stroke
				(width 0)
				(type default)
			)
			(fill no)
			(layer "F.CrtYd")
		)
		(fp_rect
			(start -0.4318 0.9525)
			(end 0.4318 -0.9525)
			(stroke
				(width 0)
				(type default)
			)
			(fill no)
			(layer "F.Fab")
		)
		(pad "1" smd custom
			(at 0 -0.4445 90)
			(size 0.1524 0.1524)
			(layers "F.Cu" "F.Mask" "F.Paste")
			(net "GPIO_VCC_U9")
			(options
				(clearance outline)
				(anchor circle)
			)
			(primitives
				(gr_poly
					(pts
						(arc
							(start 0.3048 -0.2032)
							(mid 0.275042 -0.275042)
							(end 0.2032 -0.3048)
						)
						(arc
							(start -0.2032 -0.3048)
							(mid -0.275042 -0.275042)
							(end -0.3048 -0.2032)
						)
						(arc
							(start -0.3048 0.2032)
							(mid -0.275042 0.275042)
							(end -0.2032 0.3048)
						)
						(arc
							(start 0.2032 0.3048)
							(mid 0.275042 0.275042)
							(end 0.3048 0.2032)
						)
					)
					(width 0)
					(fill yes)
				)
			)
		)
		(pad "2" smd custom
			(at 0 0.4445 90)
			(size 0.1524 0.1524)
			(layers "F.Cu" "F.Mask" "F.Paste")
			(net "GND")
			(options
				(clearance outline)
				(anchor circle)
			)
			(primitives
				(gr_poly
					(pts
						(arc
							(start 0.3048 -0.2032)
							(mid 0.275042 -0.275042)
							(end 0.2032 -0.3048)
						)
						(arc
							(start -0.2032 -0.3048)
							(mid -0.275042 -0.275042)
							(end -0.3048 -0.2032)
						)
						(arc
							(start -0.3048 0.2032)
							(mid -0.275042 0.275042)
							(end -0.2032 0.3048)
						)
						(arc
							(start 0.2032 0.3048)
							(mid 0.275042 0.275042)
							(end 0.3048 0.2032)
						)
					)
					(width 0)
					(fill yes)
				)
			)
		)
	)
	(footprint ""
		(layer "F.Cu")
		(at 445.60236 -244.884194 90)
		(property "Reference" "VIA21"
			(at 0 0 90)
			(layer "F.SilkS")
			(hide yes)
			(effects
				(font
					(size 1.27 1.27)
				)
			)
		)
		(property "Value" "100OHM-8L-2D36MM-L18-GP"
			(at 3.8989 0.5715 90)
			(unlocked yes)
			(layer "F.Fab")
			(hide yes)
			(effects
				(font
					(size 1.016 1.016)
					(thickness 0.1524)
				)
			)
		)
		(property "Device Type" "VIA-PCIE-4P-414097"
			(at 3.8989 -0.9525 90)
			(unlocked yes)
			(layer "F.Fab")
			(hide yes)
			(effects
				(font
					(size 1.016 1.016)
					(thickness 0.1524)
				)
			)
		)
		(duplicate_pad_numbers_are_jumpers no)
		(fp_rect
			(start -2.0701 0.4826)
			(end 2.0701 -0.4826)
			(stroke
				(width 0)
				(type default)
			)
			(fill no)
			(layer "F.CrtYd")
		)
		(fp_rect
			(start -2.0701 0.4826)
			(end 2.0701 -0.4826)
			(stroke
				(width 0)
				(type default)
			)
			(fill no)
			(layer "F.Fab")
		)
		(pad "1" thru_hole circle
			(at -1.5875 0 90)
			(size 0.508 0.508)
			(drill 0.254)
			(layers "*.Cu" "*.Mask")
			(remove_unused_layers no)
			(net "GND")
			(clearance 0.2286)
			(thermal_gap 0.2286)
		)
		(pad "2" thru_hole circle
			(at -0.5715 0 90)
			(size 0.508 0.508)
			(drill 0.254)
			(layers "*.Cu" "*.Mask")
			(remove_unused_layers no)
			(net "PHY_SCC_B_TO_DRV_B_10_DP")
			(clearance 0.2286)
			(thermal_gap 0.2286)
		)
		(pad "3" thru_hole circle
			(at 0.5715 0 90)
			(size 0.508 0.508)
			(drill 0.254)
			(layers "*.Cu" "*.Mask")
			(remove_unused_layers no)
			(net "PHY_SCC_B_TO_DRV_B_10_DN")
			(clearance 0.2286)
			(thermal_gap 0.2286)
		)
		(pad "4" thru_hole circle
			(at 1.5875 0 90)
			(size 0.508 0.508)
			(drill 0.254)
			(layers "*.Cu" "*.Mask")
			(remove_unused_layers no)
			(net "GND")
			(clearance 0.2286)
			(thermal_gap 0.2286)
		)
	)
	(footprint ""
		(layer "F.Cu")
		(at 147.599908 -379.899926 180)
		(property "Reference" "FAN2"
			(at 0 0 180)
			(layer "F.SilkS")
			(hide yes)
			(effects
				(font
					(size 1.27 1.27)
				)
			)
		)
		(property "Value" "MLX-CONN10D-7-GP"
			(at -15.641574 4.697984 180)
			(unlocked yes)
			(layer "F.Fab")
			(hide yes)
			(effects
				(font
					(size 1.016 1.016)
					(thickness 0.1524)
				)
			)
		)
		(property "Device Type" "15-24-6103"
			(at -15.641574 3.173984 180)
			(unlocked yes)
			(layer "F.Fab")
			(hide yes)
			(effects
				(font
					(size 1.016 1.016)
					(thickness 0.1524)
				)
			)
		)
		(duplicate_pad_numbers_are_jumpers no)
		(fp_line
			(start 14.0462 8.1534)
			(end -14.0462 8.1534)
			(stroke
				(width 0.1524)
				(type default)
			)
			(layer "F.SilkS")
		)
		(fp_line
			(start 14.0462 -6.4516)
			(end 14.0462 8.1534)
			(stroke
				(width 0.1524)
				(type default)
			)
			(layer "F.SilkS")
		)
		(fp_line
			(start 9.9314 -6.4516)
			(end 14.0462 -6.4516)
			(stroke
				(width 0.1524)
				(type default)
			)
			(layer "F.SilkS")
		)
		(fp_line
			(start 9.9314 -14.3256)
			(end 9.9314 -6.4516)
			(stroke
				(width 0.1524)
				(type default)
			)
			(layer "F.SilkS")
		)
		(fp_line
			(start -9.9314 -6.4516)
			(end -9.9314 -14.3256)
			(stroke
				(width 0.1524)
				(type default)
			)
			(layer "F.SilkS")
		)
		(fp_line
			(start -9.9314 -14.3256)
			(end 9.9314 -14.3256)
			(stroke
				(width 0.1524)
				(type default)
			)
			(layer "F.SilkS")
		)
		(fp_line
			(start -14.0462 8.1534)
			(end -14.0462 -6.4516)
			(stroke
				(width 0.1524)
				(type default)
			)
			(layer "F.SilkS")
		)
		(fp_line
			(start -14.0462 -6.4516)
			(end -9.9314 -6.4516)
			(stroke
				(width 0.1524)
				(type default)
			)
			(layer "F.SilkS")
		)
		(fp_circle
			(center 8.400034 -7.29996)
			(end 6.761734 -7.29996)
			(stroke
				(width 0.3048)
				(type default)
			)
			(fill no)
			(layer "F.SilkS")
		)
		(fp_circle
			(center 8.400034 -12.800076)
			(end 6.761734 -12.800076)
			(stroke
				(width 0.3048)
				(type default)
			)
			(fill no)
			(layer "F.SilkS")
		)
		(fp_circle
			(center 4.19989 -7.29996)
			(end 2.56159 -7.29996)
			(stroke
				(width 0.3048)
				(type default)
			)
			(fill no)
			(layer "F.SilkS")
		)
		(fp_circle
			(center 4.19989 -12.800076)
			(end 2.56159 -12.800076)
			(stroke
				(width 0.3048)
				(type default)
			)
			(fill no)
			(layer "F.SilkS")
		)
		(fp_circle
			(center 0 -7.29996)
			(end -1.6383 -7.29996)
			(stroke
				(width 0.3048)
				(type default)
			)
			(fill no)
			(layer "F.SilkS")
		)
		(fp_circle
			(center 0 -12.800076)
			(end -1.6383 -12.800076)
			(stroke
				(width 0.3048)
				(type default)
			)
			(fill no)
			(layer "F.SilkS")
		)
		(fp_circle
			(center -4.19989 -7.29996)
			(end -5.83819 -7.29996)
			(stroke
				(width 0.3048)
				(type default)
			)
			(fill no)
			(layer "F.SilkS")
		)
		(fp_circle
			(center -4.19989 -12.800076)
			(end -5.83819 -12.800076)
			(stroke
				(width 0.3048)
				(type default)
			)
			(fill no)
			(layer "F.SilkS")
		)
		(fp_circle
			(center -8.400034 -7.29996)
			(end -10.038334 -7.29996)
			(stroke
				(width 0.3048)
				(type default)
			)
			(fill no)
			(layer "F.SilkS")
		)
		(fp_circle
			(center -8.400034 -12.800076)
			(end -10.038334 -12.800076)
			(stroke
				(width 0.3048)
				(type default)
			)
			(fill no)
			(layer "F.SilkS")
		)
		(fp_poly
			(pts
				(xy -13.7922 7.8994) (xy -13.7922 -6.1976) (xy -9.2964 -6.1976) (xy -9.2964 -13.6906) (xy 9.2964 -13.6906)
				(xy 9.2964 -6.1976) (xy 13.7922 -6.1976) (xy 13.7922 7.8994)
			)
			(stroke
				(width 0)
				(type default)
			)
			(fill no)
			(layer "F.CrtYd")
		)
		(fp_poly
			(pts
				(xy -14.3002 8.4074) (xy -14.3002 -6.7056) (xy -10.1854 -6.7056) (xy -10.1854 -14.5796) (xy 10.1854 -14.5796)
				(xy 10.1854 -6.7056) (xy 14.3002 -6.7056) (xy 14.3002 -0.00635) (xy 13.7922 -0.00635) (xy 13.7922 -6.1976)
				(xy 9.2964 -6.1976) (xy 9.2964 -13.6906) (xy -9.2964 -13.6906) (xy -9.2964 -6.1976) (xy -13.7922 -6.1976)
				(xy -13.7922 7.8994) (xy 13.7922 7.8994) (xy 13.7922 0.00635) (xy 14.3002 0.00635) (xy 14.3002 8.4074)
			)
			(stroke
				(width 0)
				(type default)
			)
			(fill no)
			(layer "F.CrtYd")
		)
		(fp_poly
			(pts
				(xy -14.3002 8.4074) (xy -14.3002 -6.7056) (xy -10.1854 -6.7056) (xy -10.1854 -14.5796) (xy 10.1854 -14.5796)
				(xy 10.1854 -6.7056) (xy 14.3002 -6.7056) (xy 14.3002 8.4074)
			)
			(stroke
				(width 0)
				(type default)
			)
			(fill no)
			(layer "F.Fab")
		)
		(pad "" np_thru_hole circle
			(at -8.400034 0 180)
			(size 0.254 0.254)
			(drill 3.0226)
			(layers "*.Cu" "*.Mask")
			(clearance 1.7399)
			(thermal_gap 1.7399)
		)
		(pad "" np_thru_hole circle
			(at 8.400034 0 180)
			(size 0.254 0.254)
			(drill 3.0226)
			(layers "*.Cu" "*.Mask")
			(clearance 1.7399)
			(thermal_gap 1.7399)
		)
		(pad "1" thru_hole circle
			(at 8.400034 -7.29996 180)
			(size 2.5654 2.5654)
			(drill 1.8034)
			(layers "*.Cu" "*.Mask")
			(remove_unused_layers no)
			(net "FAN_1_TACH0")
			(clearance 0.127)
			(thermal_gap 0.127)
		)
		(pad "2" thru_hole circle
			(at 8.400034 -12.800076 180)
			(size 2.5654 2.5654)
			(drill 1.8034)
			(layers "*.Cu" "*.Mask")
			(remove_unused_layers no)
			(net "FAN_1_TACH1")
			(clearance 0.127)
			(thermal_gap 0.127)
		)
		(pad "3" thru_hole circle
			(at 4.19989 -7.29996 180)
			(size 2.5654 2.5654)
			(drill 1.8034)
			(layers "*.Cu" "*.Mask")
			(remove_unused_layers no)
			(net "FAN_1_PWM")
			(clearance 0.127)
			(thermal_gap 0.127)
		)
		(pad "4" thru_hole circle
			(at 4.19989 -12.800076 180)
			(size 2.5654 2.5654)
			(drill 1.8034)
			(layers "*.Cu" "*.Mask")
			(remove_unused_layers no)
			(net "FAN_1_PWM")
			(clearance 0.127)
			(thermal_gap 0.127)
		)
		(pad "5" thru_hole circle
			(at 0 -7.29996 180)
			(size 2.5654 2.5654)
			(drill 1.8034)
			(layers "*.Cu" "*.Mask")
			(remove_unused_layers no)
			(net "FAN_1_INS_N")
			(clearance 0.127)
			(thermal_gap 0.127)
		)
		(pad "6" thru_hole circle
			(at 0 -12.800076 180)
			(size 2.5654 2.5654)
			(drill 1.8034)
			(layers "*.Cu" "*.Mask")
			(remove_unused_layers no)
			(net "Net_1775")
			(clearance 0.127)
			(thermal_gap 0.127)
		)
		(pad "7" thru_hole circle
			(at -4.19989 -7.29996 180)
			(size 2.5654 2.5654)
			(drill 1.8034)
			(layers "*.Cu" "*.Mask")
			(remove_unused_layers no)
			(net "P12V_FAN1")
			(clearance 0.127)
			(thermal_gap 0.127)
		)
		(pad "8" thru_hole circle
			(at -4.19989 -12.800076 180)
			(size 2.5654 2.5654)
			(drill 1.8034)
			(layers "*.Cu" "*.Mask")
			(remove_unused_layers no)
			(net "P12V_FAN1")
			(clearance 0.127)
			(thermal_gap 0.127)
		)
		(pad "9" thru_hole circle
			(at -8.400034 -7.29996 180)
			(size 2.5654 2.5654)
			(drill 1.8034)
			(layers "*.Cu" "*.Mask")
			(remove_unused_layers no)
			(net "GND")
			(clearance 0.127)
			(thermal_gap 0.127)
		)
		(pad "10" thru_hole circle
			(at -8.400034 -12.800076 180)
			(size 2.5654 2.5654)
			(drill 1.8034)
			(layers "*.Cu" "*.Mask")
			(remove_unused_layers no)
			(net "GND")
			(clearance 0.127)
			(thermal_gap 0.127)
		)
		(zone
			(layers "F.Cu" "B.Cu" "In1.Cu" "In2.Cu" "In3.Cu" "In4.Cu" "In5.Cu" "In6.Cu")
			(hatch none 0.5)
			(connect_pads
				(clearance 0)
			)
			(min_thickness 0.25)
			(keepout
				(tracks not_allowed)
				(vias allowed)
				(pads allowed)
				(copperpour not_allowed)
				(footprints allowed)
			)
			(placement
				(enabled no)
				(sheetname "")
			)
			(fill
				(thermal_gap 0.5)
				(thermal_bridge_width 0.5)
				(island_removal_mode 0)
			)
			(polygon
				(pts
					(arc
						(start 141.015974 -379.899926)
						(mid 137.383774 -379.899926)
						(end 141.015974 -379.899926)
					)
				)
			)
		)
		(zone
			(layers "F.Cu" "B.Cu" "In1.Cu" "In2.Cu" "In3.Cu" "In4.Cu" "In5.Cu" "In6.Cu")
			(hatch none 0.5)
			(connect_pads
				(clearance 0)
			)
			(min_thickness 0.25)
			(keepout
				(tracks not_allowed)
				(vias allowed)
				(pads allowed)
				(copperpour not_allowed)
				(footprints allowed)
			)
			(placement
				(enabled no)
				(sheetname "")
			)
			(fill
				(thermal_gap 0.5)
				(thermal_bridge_width 0.5)
				(island_removal_mode 0)
			)
			(polygon
				(pts
					(arc
						(start 157.816042 -379.899926)
						(mid 154.183842 -379.899926)
						(end 157.816042 -379.899926)
					)
				)
			)
		)
	)
	(footprint ""
		(layer "F.Cu")
		(at 141.097 -255.524 90)
		(property "Reference" "C91"
			(at 0 0 90)
			(layer "F.SilkS")
			(hide yes)
			(effects
				(font
					(size 1.27 1.27)
				)
			)
		)
		(property "Value" "SCD033U25V2KX-GP"
			(at 1.1811 -2.7051 90)
			(unlocked yes)
			(layer "F.Fab")
			(hide yes)
			(effects
				(font
					(size 1.016 1.016)
					(thickness 0.1524)
				)
			)
		)
		(property "Device Type" "C402H22"
			(at 1.1811 -4.2291 90)
			(unlocked yes)
			(layer "F.Fab")
			(hide yes)
			(effects
				(font
					(size 1.016 1.016)
					(thickness 0.1524)
				)
			)
		)
		(duplicate_pad_numbers_are_jumpers no)
		(fp_rect
			(start -0.4318 0.9525)
			(end 0.4318 -0.9525)
			(stroke
				(width 0)
				(type default)
			)
			(fill no)
			(layer "F.CrtYd")
		)
		(fp_rect
			(start -0.4318 0.9525)
			(end 0.4318 -0.9525)
			(stroke
				(width 0)
				(type default)
			)
			(fill no)
			(layer "F.Fab")
		)
		(pad "1" smd custom
			(at 0 -0.4445 90)
			(size 0.1524 0.1524)
			(layers "F.Cu" "F.Mask" "F.Paste")
			(net "P12V_B")
			(options
				(clearance outline)
				(anchor circle)
			)
			(primitives
				(gr_poly
					(pts
						(arc
							(start 0.3048 -0.2032)
							(mid 0.275042 -0.275042)
							(end 0.2032 -0.3048)
						)
						(arc
							(start -0.2032 -0.3048)
							(mid -0.275042 -0.275042)
							(end -0.3048 -0.2032)
						)
						(arc
							(start -0.3048 0.2032)
							(mid -0.275042 0.275042)
							(end -0.2032 0.3048)
						)
						(arc
							(start 0.2032 0.3048)
							(mid 0.275042 0.275042)
							(end 0.3048 0.2032)
						)
					)
					(width 0)
					(fill yes)
				)
			)
		)
		(pad "2" smd custom
			(at 0 0.4445 90)
			(size 0.1524 0.1524)
			(layers "F.Cu" "F.Mask" "F.Paste")
			(net "SW_HDD_N4")
			(options
				(clearance outline)
				(anchor circle)
			)
			(primitives
				(gr_poly
					(pts
						(arc
							(start 0.3048 -0.2032)
							(mid 0.275042 -0.275042)
							(end 0.2032 -0.3048)
						)
						(arc
							(start -0.2032 -0.3048)
							(mid -0.275042 -0.275042)
							(end -0.3048 -0.2032)
						)
						(arc
							(start -0.3048 0.2032)
							(mid -0.275042 0.275042)
							(end -0.2032 0.3048)
						)
						(arc
							(start 0.2032 0.3048)
							(mid 0.275042 0.275042)
							(end 0.3048 0.2032)
						)
					)
					(width 0)
					(fill yes)
				)
			)
		)
	)
	(footprint ""
		(layer "F.Cu")
		(at 178.0032 -33.782 -90)
		(property "Reference" "C407"
			(at 0 0 270)
			(layer "F.SilkS")
			(hide yes)
			(effects
				(font
					(size 1.27 1.27)
				)
			)
		)
		(property "Value" "SC1U16V3KX-5GP"
			(at 0 -2.8194 270)
			(unlocked yes)
			(layer "F.Fab")
			(hide yes)
			(effects
				(font
					(size 1.016 1.016)
					(thickness 0.1524)
				)
			)
		)
		(property "Device Type" "C603H36"
			(at 0 -4.3434 270)
			(unlocked yes)
			(layer "F.Fab")
			(hide yes)
			(effects
				(font
					(size 1.016 1.016)
					(thickness 0.1524)
				)
			)
		)
		(duplicate_pad_numbers_are_jumpers no)
		(fp_line
			(start 0.508 0)
			(end -0.508 0)
			(stroke
				(width 0.2032)
				(type default)
			)
			(layer "F.SilkS")
		)
		(fp_rect
			(start -0.5842 1.3335)
			(end 0.5842 -1.3335)
			(stroke
				(width 0)
				(type default)
			)
			(fill no)
			(layer "F.CrtYd")
		)
		(fp_rect
			(start -0.5842 1.3335)
			(end 0.5842 -1.3335)
			(stroke
				(width 0)
				(type default)
			)
			(fill no)
			(layer "F.Fab")
		)
		(pad "1" smd custom
			(at 0 -0.762 270)
			(size 0.2159 0.2159)
			(layers "F.Cu" "F.Mask" "F.Paste")
			(net "P5V_HDD29")
			(options
				(clearance outline)
				(anchor circle)
			)
			(primitives
				(gr_poly
					(pts
						(arc
							(start -0.3302 -0.4318)
							(mid -0.402042 -0.402042)
							(end -0.4318 -0.3302)
						)
						(arc
							(start -0.4318 0.3302)
							(mid -0.402042 0.402042)
							(end -0.3302 0.4318)
						)
						(arc
							(start 0.3302 0.4318)
							(mid 0.402042 0.402042)
							(end 0.4318 0.3302)
						)
						(arc
							(start 0.4318 -0.3302)
							(mid 0.402042 -0.402042)
							(end 0.3302 -0.4318)
						)
					)
					(width 0)
					(fill yes)
				)
			)
		)
		(pad "2" smd custom
			(at 0 0.762 270)
			(size 0.2159 0.2159)
			(layers "F.Cu" "F.Mask" "F.Paste")
			(net "GND")
			(options
				(clearance outline)
				(anchor circle)
			)
			(primitives
				(gr_poly
					(pts
						(arc
							(start -0.3302 -0.4318)
							(mid -0.402042 -0.402042)
							(end -0.4318 -0.3302)
						)
						(arc
							(start -0.4318 0.3302)
							(mid -0.402042 0.402042)
							(end -0.3302 0.4318)
						)
						(arc
							(start 0.3302 0.4318)
							(mid 0.402042 0.402042)
							(end 0.4318 0.3302)
						)
						(arc
							(start 0.4318 -0.3302)
							(mid 0.402042 -0.402042)
							(end 0.3302 -0.4318)
						)
					)
					(width 0)
					(fill yes)
				)
			)
		)
	)
	(footprint ""
		(layer "F.Cu")
		(at 144.653 -246.634)
		(property "Reference" "R235"
			(at 0 0 0)
			(layer "F.SilkS")
			(hide yes)
			(effects
				(font
					(size 1.27 1.27)
				)
			)
		)
		(property "Value" "0R2J-2-GP"
			(at 0.064008 -3.993896 0)
			(unlocked yes)
			(layer "F.Fab")
			(hide yes)
			(effects
				(font
					(size 1.016 1.016)
					(thickness 0.1524)
				)
			)
		)
		(property "Device Type" "R402H16"
			(at 0.064008 -5.517896 0)
			(unlocked yes)
			(layer "F.Fab")
			(hide yes)
			(effects
				(font
					(size 1.016 1.016)
					(thickness 0.1524)
				)
			)
		)
		(duplicate_pad_numbers_are_jumpers no)
		(fp_line
			(start -0.508 -0.9398)
			(end -0.508 0.9398)
			(stroke
				(width 0.1524)
				(type default)
			)
			(layer "F.SilkS")
		)
		(fp_line
			(start 0.508 -0.9398)
			(end -0.508 -0.9398)
			(stroke
				(width 0.1524)
				(type default)
			)
			(layer "F.SilkS")
		)
		(fp_rect
			(start -0.508 0.9398)
			(end 0.508 -0.9398)
			(stroke
				(width 0)
				(type default)
			)
			(fill no)
			(layer "F.CrtYd")
		)
		(fp_rect
			(start -0.508 0.9398)
			(end 0.508 -0.9398)
			(stroke
				(width 0)
				(type default)
			)
			(fill no)
			(layer "F.Fab")
		)
		(pad "1" smd custom
			(at 0 -0.4445)
			(size 0.1397 0.1397)
			(layers "F.Cu" "F.Mask" "F.Paste")
			(net "SW_HDD_G4")
			(options
				(clearance outline)
				(anchor circle)
			)
			(primitives
				(gr_poly
					(pts
						(arc
							(start -0.1778 -0.2794)
							(mid -0.249642 -0.249642)
							(end -0.2794 -0.1778)
						)
						(arc
							(start -0.2794 0.1778)
							(mid -0.249642 0.249642)
							(end -0.1778 0.2794)
						)
						(arc
							(start 0.1778 0.2794)
							(mid 0.249642 0.249642)
							(end 0.2794 0.1778)
						)
						(arc
							(start 0.2794 -0.1778)
							(mid 0.249642 -0.249642)
							(end 0.1778 -0.2794)
						)
					)
					(width 0)
					(fill yes)
				)
			)
		)
		(pad "2" smd custom
			(at 0 0.4445)
			(size 0.1397 0.1397)
			(layers "F.Cu" "F.Mask" "F.Paste")
			(net "SW_HDD_R4")
			(options
				(clearance outline)
				(anchor circle)
			)
			(primitives
				(gr_poly
					(pts
						(arc
							(start -0.1778 -0.2794)
							(mid -0.249642 -0.249642)
							(end -0.2794 -0.1778)
						)
						(arc
							(start -0.2794 0.1778)
							(mid -0.249642 0.249642)
							(end -0.1778 0.2794)
						)
						(arc
							(start 0.1778 0.2794)
							(mid 0.249642 0.249642)
							(end 0.2794 0.1778)
						)
						(arc
							(start 0.2794 -0.1778)
							(mid 0.249642 -0.249642)
							(end 0.1778 -0.2794)
						)
					)
					(width 0)
					(fill yes)
				)
			)
		)
	)
	(footprint ""
		(layer "F.Cu")
		(at 174.625 -132.588 180)
		(property "Reference" "D17"
			(at 0 0 180)
			(layer "F.SilkS")
			(hide yes)
			(effects
				(font
					(size 1.27 1.27)
				)
			)
		)
		(property "Value" "RB551V30-GP"
			(at 0 -6.7818 180)
			(unlocked yes)
			(layer "F.Fab")
			(hide yes)
			(effects
				(font
					(size 1.016 1.016)
					(thickness 0.1524)
				)
			)
		)
		(property "Device Type" "SOD323AKH38"
			(at 0 -8.6868 180)
			(unlocked yes)
			(layer "F.Fab")
			(hide yes)
			(effects
				(font
					(size 1.016 1.016)
					(thickness 0.1524)
				)
			)
		)
		(duplicate_pad_numbers_are_jumpers no)
		(fp_line
			(start 0.889 2.159)
			(end -0.889 2.159)
			(stroke
				(width 0.1524)
				(type default)
			)
			(layer "F.SilkS")
		)
		(fp_line
			(start 0.889 -1.9304)
			(end 0.889 2.159)
			(stroke
				(width 0.1524)
				(type default)
			)
			(layer "F.SilkS")
		)
		(fp_line
			(start 0.762 2.0574)
			(end -0.762 2.0574)
			(stroke
				(width 0.508)
				(type default)
			)
			(layer "F.SilkS")
		)
		(fp_line
			(start -0.889 2.159)
			(end -0.889 -1.9304)
			(stroke
				(width 0.1524)
				(type default)
			)
			(layer "F.SilkS")
		)
		(fp_line
			(start -0.889 -1.9304)
			(end 0.889 -1.9304)
			(stroke
				(width 0.1524)
				(type default)
			)
			(layer "F.SilkS")
		)
		(fp_rect
			(start -1.016 2.3114)
			(end 1.016 -2.0066)
			(stroke
				(width 0)
				(type default)
			)
			(fill no)
			(layer "F.CrtYd")
		)
		(fp_poly
			(pts
				(xy -1.016 -2.0066) (xy 1.016 -2.0066) (xy 1.016 2.3114) (xy -1.016 2.3114)
			)
			(stroke
				(width 0)
				(type default)
			)
			(fill no)
			(layer "F.Fab")
		)
		(pad "A" smd rect
			(at 0 -1.143 180)
			(size 0.5588 1.016)
			(layers "F.Cu" "F.Mask" "F.Paste")
			(net "SW_HDD_R17")
		)
		(pad "K" smd rect
			(at 0 1.143 180)
			(size 0.5588 1.016)
			(layers "F.Cu" "F.Mask" "F.Paste")
			(net "SW_HDD_N17")
		)
	)
	(footprint ""
		(layer "F.Cu")
		(at 332.359 -36.83 180)
		(property "Reference" "C421"
			(at 0 0 180)
			(layer "F.SilkS")
			(hide yes)
			(effects
				(font
					(size 1.27 1.27)
				)
			)
		)
		(property "Value" "SC10U16V6KX-2GP"
			(at -0.0762 -5.1308 180)
			(unlocked yes)
			(layer "F.Fab")
			(hide yes)
			(effects
				(font
					(size 1.016 1.016)
					(thickness 0.1524)
				)
			)
		)
		(property "Device Type" "C1206H71"
			(at -0.127 -6.6548 180)
			(unlocked yes)
			(layer "F.Fab")
			(hide yes)
			(effects
				(font
					(size 1.016 1.016)
					(thickness 0.1524)
				)
			)
		)
		(duplicate_pad_numbers_are_jumpers no)
		(fp_line
			(start 1.016 2.2352)
			(end -1.016 2.2352)
			(stroke
				(width 0.1524)
				(type default)
			)
			(layer "F.SilkS")
		)
		(fp_line
			(start 1.016 0.8382)
			(end 1.016 2.2352)
			(stroke
				(width 0.1524)
				(type default)
			)
			(layer "F.SilkS")
		)
		(fp_line
			(start 1.016 -2.2352)
			(end 1.016 -0.8382)
			(stroke
				(width 0.1524)
				(type default)
			)
			(layer "F.SilkS")
		)
		(fp_line
			(start -1.016 2.2352)
			(end -1.016 0.8382)
			(stroke
				(width 0.1524)
				(type default)
			)
			(layer "F.SilkS")
		)
		(fp_line
			(start -1.016 -0.8382)
			(end -1.016 -2.2352)
			(stroke
				(width 0.1524)
				(type default)
			)
			(layer "F.SilkS")
		)
		(fp_line
			(start -1.016 -2.2352)
			(end 1.016 -2.2352)
			(stroke
				(width 0.1524)
				(type default)
			)
			(layer "F.SilkS")
		)
		(fp_rect
			(start -1.0922 2.3114)
			(end 1.0922 -2.3114)
			(stroke
				(width 0)
				(type default)
			)
			(fill no)
			(layer "F.CrtYd")
		)
		(fp_poly
			(pts
				(xy 1.0922 -2.3114) (xy 1.0922 2.3114) (xy -1.0922 2.3114) (xy -1.0922 -2.3114)
			)
			(stroke
				(width 0)
				(type default)
			)
			(fill no)
			(layer "F.Fab")
		)
		(pad "1" smd rect
			(at 0 -1.397 180)
			(size 1.651 1.27)
			(layers "F.Cu" "F.Mask" "F.Paste")
			(net "P5V_HDD30")
		)
		(pad "2" smd rect
			(at 0 1.397 180)
			(size 1.651 1.27)
			(layers "F.Cu" "F.Mask" "F.Paste")
			(net "GND")
		)
	)
	(footprint ""
		(layer "F.Cu")
		(at 52.29606 -120.444006 -90)
		(property "Reference" "R1117"
			(at 0 0 270)
			(layer "F.SilkS")
			(hide yes)
			(effects
				(font
					(size 1.27 1.27)
				)
			)
		)
		(property "Value" "0R2J-2-GP"
			(at 0.064008 -3.993896 270)
			(unlocked yes)
			(layer "F.Fab")
			(hide yes)
			(effects
				(font
					(size 1.016 1.016)
					(thickness 0.1524)
				)
			)
		)
		(property "Device Type" "R402H16"
			(at 0.064008 -5.517896 270)
			(unlocked yes)
			(layer "F.Fab")
			(hide yes)
			(effects
				(font
					(size 1.016 1.016)
					(thickness 0.1524)
				)
			)
		)
		(duplicate_pad_numbers_are_jumpers no)
		(fp_line
			(start -0.508 -0.9398)
			(end -0.508 0.9398)
			(stroke
				(width 0.1524)
				(type default)
			)
			(layer "F.SilkS")
		)
		(fp_line
			(start 0.508 -0.9398)
			(end -0.508 -0.9398)
			(stroke
				(width 0.1524)
				(type default)
			)
			(layer "F.SilkS")
		)
		(fp_rect
			(start -0.508 0.9398)
			(end 0.508 -0.9398)
			(stroke
				(width 0)
				(type default)
			)
			(fill no)
			(layer "F.CrtYd")
		)
		(fp_rect
			(start -0.508 0.9398)
			(end 0.508 -0.9398)
			(stroke
				(width 0)
				(type default)
			)
			(fill no)
			(layer "F.Fab")
		)
		(pad "1" smd custom
			(at 0 -0.4445 270)
			(size 0.1397 0.1397)
			(layers "F.Cu" "F.Mask" "F.Paste")
			(net "P12V_B_PGOOD")
			(options
				(clearance outline)
				(anchor circle)
			)
			(primitives
				(gr_poly
					(pts
						(arc
							(start -0.1778 -0.2794)
							(mid -0.249642 -0.249642)
							(end -0.2794 -0.1778)
						)
						(arc
							(start -0.2794 0.1778)
							(mid -0.249642 0.249642)
							(end -0.1778 0.2794)
						)
						(arc
							(start 0.1778 0.2794)
							(mid 0.249642 0.249642)
							(end 0.2794 0.1778)
						)
						(arc
							(start 0.2794 -0.1778)
							(mid 0.249642 -0.249642)
							(end 0.1778 -0.2794)
						)
					)
					(width 0)
					(fill yes)
				)
			)
		)
		(pad "2" smd custom
			(at 0 0.4445 270)
			(size 0.1397 0.1397)
			(layers "F.Cu" "F.Mask" "F.Paste")
			(net "P5V_B_2_EN_R")
			(options
				(clearance outline)
				(anchor circle)
			)
			(primitives
				(gr_poly
					(pts
						(arc
							(start -0.1778 -0.2794)
							(mid -0.249642 -0.249642)
							(end -0.2794 -0.1778)
						)
						(arc
							(start -0.2794 0.1778)
							(mid -0.249642 0.249642)
							(end -0.1778 0.2794)
						)
						(arc
							(start 0.1778 0.2794)
							(mid 0.249642 0.249642)
							(end 0.2794 0.1778)
						)
						(arc
							(start 0.2794 -0.1778)
							(mid 0.249642 -0.249642)
							(end 0.1778 -0.2794)
						)
					)
					(width 0)
					(fill yes)
				)
			)
		)
	)
	(footprint ""
		(layer "F.Cu")
		(at 35.687 -266.065 90)
		(property "Reference" "R902"
			(at 0 0 90)
			(layer "F.SilkS")
			(hide yes)
			(effects
				(font
					(size 1.27 1.27)
				)
			)
		)
		(property "Value" "220R3F-1-GP"
			(at -0.0254 -2.5146 90)
			(unlocked yes)
			(layer "F.Fab")
			(hide yes)
			(effects
				(font
					(size 1.016 1.016)
					(thickness 0.1524)
				)
			)
		)
		(property "Device Type" "R603H22"
			(at -0.0254 -4.0386 90)
			(unlocked yes)
			(layer "F.Fab")
			(hide yes)
			(effects
				(font
					(size 1.016 1.016)
					(thickness 0.1524)
				)
			)
		)
		(duplicate_pad_numbers_are_jumpers no)
		(fp_line
			(start 0.2032 0)
			(end 0.4826 0)
			(stroke
				(width 0.2032)
				(type default)
			)
			(layer "F.SilkS")
		)
		(fp_line
			(start -0.4826 0)
			(end -0.2032 0)
			(stroke
				(width 0.2032)
				(type default)
			)
			(layer "F.SilkS")
		)
		(fp_rect
			(start -0.5842 1.3335)
			(end 0.5842 -1.3335)
			(stroke
				(width 0)
				(type default)
			)
			(fill no)
			(layer "F.CrtYd")
		)
		(fp_rect
			(start -0.5842 1.3335)
			(end 0.5842 -1.3335)
			(stroke
				(width 0)
				(type default)
			)
			(fill no)
			(layer "F.Fab")
		)
		(pad "1" smd custom
			(at 0 -0.762 90)
			(size 0.2159 0.2159)
			(layers "F.Cu" "F.Mask" "F.Paste")
			(net "HDD_PRSNT_0")
			(options
				(clearance outline)
				(anchor circle)
			)
			(primitives
				(gr_poly
					(pts
						(arc
							(start -0.3302 -0.4318)
							(mid -0.402042 -0.402042)
							(end -0.4318 -0.3302)
						)
						(arc
							(start -0.4318 0.3302)
							(mid -0.402042 0.402042)
							(end -0.3302 0.4318)
						)
						(arc
							(start 0.3302 0.4318)
							(mid 0.402042 0.402042)
							(end 0.4318 0.3302)
						)
						(arc
							(start 0.4318 -0.3302)
							(mid 0.402042 -0.402042)
							(end 0.3302 -0.4318)
						)
					)
					(width 0)
					(fill yes)
				)
			)
		)
		(pad "2" smd custom
			(at 0 0.762 90)
			(size 0.2159 0.2159)
			(layers "F.Cu" "F.Mask" "F.Paste")
			(net "DRIVE_B_0_INS")
			(options
				(clearance outline)
				(anchor circle)
			)
			(primitives
				(gr_poly
					(pts
						(arc
							(start -0.3302 -0.4318)
							(mid -0.402042 -0.402042)
							(end -0.4318 -0.3302)
						)
						(arc
							(start -0.4318 0.3302)
							(mid -0.402042 0.402042)
							(end -0.3302 0.4318)
						)
						(arc
							(start 0.3302 0.4318)
							(mid 0.402042 0.402042)
							(end 0.4318 0.3302)
						)
						(arc
							(start 0.4318 -0.3302)
							(mid 0.402042 -0.402042)
							(end 0.3302 -0.4318)
						)
					)
					(width 0)
					(fill yes)
				)
			)
		)
	)
	(footprint ""
		(layer "F.Cu")
		(at 442.686186 -121.845578)
		(property "Reference" "R1154"
			(at 0 0 0)
			(layer "F.SilkS")
			(hide yes)
			(effects
				(font
					(size 1.27 1.27)
				)
			)
		)
		(property "Value" "49K9R2F-L-GP"
			(at 0.064008 -3.993896 0)
			(unlocked yes)
			(layer "F.Fab")
			(hide yes)
			(effects
				(font
					(size 1.016 1.016)
					(thickness 0.1524)
				)
			)
		)
		(property "Device Type" "R402H16"
			(at 0.064008 -5.517896 0)
			(unlocked yes)
			(layer "F.Fab")
			(hide yes)
			(effects
				(font
					(size 1.016 1.016)
					(thickness 0.1524)
				)
			)
		)
		(duplicate_pad_numbers_are_jumpers no)
		(fp_line
			(start -0.508 -0.9398)
			(end -0.508 0.9398)
			(stroke
				(width 0.1524)
				(type default)
			)
			(layer "F.SilkS")
		)
		(fp_line
			(start 0.508 -0.9398)
			(end -0.508 -0.9398)
			(stroke
				(width 0.1524)
				(type default)
			)
			(layer "F.SilkS")
		)
		(fp_rect
			(start -0.508 0.9398)
			(end 0.508 -0.9398)
			(stroke
				(width 0)
				(type default)
			)
			(fill no)
			(layer "F.CrtYd")
		)
		(fp_rect
			(start -0.508 0.9398)
			(end 0.508 -0.9398)
			(stroke
				(width 0)
				(type default)
			)
			(fill no)
			(layer "F.Fab")
		)
		(pad "1" smd custom
			(at 0 -0.4445)
			(size 0.1397 0.1397)
			(layers "F.Cu" "F.Mask" "F.Paste")
			(net "P12V_B")
			(options
				(clearance outline)
				(anchor circle)
			)
			(primitives
				(gr_poly
					(pts
						(arc
							(start -0.1778 -0.2794)
							(mid -0.249642 -0.249642)
							(end -0.2794 -0.1778)
						)
						(arc
							(start -0.2794 0.1778)
							(mid -0.249642 0.249642)
							(end -0.1778 0.2794)
						)
						(arc
							(start 0.1778 0.2794)
							(mid 0.249642 0.249642)
							(end 0.2794 0.1778)
						)
						(arc
							(start 0.2794 -0.1778)
							(mid 0.249642 -0.249642)
							(end 0.1778 -0.2794)
						)
					)
					(width 0)
					(fill yes)
				)
			)
		)
		(pad "2" smd custom
			(at 0 0.4445)
			(size 0.1397 0.1397)
			(layers "F.Cu" "F.Mask" "F.Paste")
			(net "P5V_B_4_EN_R")
			(options
				(clearance outline)
				(anchor circle)
			)
			(primitives
				(gr_poly
					(pts
						(arc
							(start -0.1778 -0.2794)
							(mid -0.249642 -0.249642)
							(end -0.2794 -0.1778)
						)
						(arc
							(start -0.2794 0.1778)
							(mid -0.249642 0.249642)
							(end -0.1778 0.2794)
						)
						(arc
							(start 0.1778 0.2794)
							(mid 0.249642 0.249642)
							(end 0.2794 0.1778)
						)
						(arc
							(start 0.2794 -0.1778)
							(mid 0.249642 -0.249642)
							(end 0.1778 -0.2794)
						)
					)
					(width 0)
					(fill yes)
				)
			)
		)
	)
	(footprint ""
		(layer "F.Cu")
		(at 432.213004 -357.2256)
		(property "Reference" "D48"
			(at 0 0 0)
			(layer "F.SilkS")
			(hide yes)
			(effects
				(font
					(size 1.27 1.27)
				)
			)
		)
		(property "Value" "RB551V30-GP"
			(at 0 -6.7818 0)
			(unlocked yes)
			(layer "F.Fab")
			(hide yes)
			(effects
				(font
					(size 1.016 1.016)
					(thickness 0.1524)
				)
			)
		)
		(property "Device Type" "SOD323AKH38"
			(at 0 -8.6868 0)
			(unlocked yes)
			(layer "F.Fab")
			(hide yes)
			(effects
				(font
					(size 1.016 1.016)
					(thickness 0.1524)
				)
			)
		)
		(duplicate_pad_numbers_are_jumpers no)
		(fp_line
			(start -0.889 -1.9304)
			(end 0.889 -1.9304)
			(stroke
				(width 0.1524)
				(type default)
			)
			(layer "F.SilkS")
		)
		(fp_line
			(start -0.889 2.159)
			(end -0.889 -1.9304)
			(stroke
				(width 0.1524)
				(type default)
			)
			(layer "F.SilkS")
		)
		(fp_line
			(start 0.762 2.0574)
			(end -0.762 2.0574)
			(stroke
				(width 0.508)
				(type default)
			)
			(layer "F.SilkS")
		)
		(fp_line
			(start 0.889 -1.9304)
			(end 0.889 2.159)
			(stroke
				(width 0.1524)
				(type default)
			)
			(layer "F.SilkS")
		)
		(fp_line
			(start 0.889 2.159)
			(end -0.889 2.159)
			(stroke
				(width 0.1524)
				(type default)
			)
			(layer "F.SilkS")
		)
		(fp_rect
			(start -1.016 2.3114)
			(end 1.016 -2.0066)
			(stroke
				(width 0)
				(type default)
			)
			(fill no)
			(layer "F.CrtYd")
		)
		(fp_poly
			(pts
				(xy -1.016 -2.0066) (xy 1.016 -2.0066) (xy 1.016 2.3114) (xy -1.016 2.3114)
			)
			(stroke
				(width 0)
				(type default)
			)
			(fill no)
			(layer "F.Fab")
		)
		(pad "A" smd rect
			(at 0 -1.143)
			(size 0.5588 1.016)
			(layers "F.Cu" "F.Mask" "F.Paste")
			(net "GATE_FAN3")
		)
		(pad "K" smd rect
			(at 0 1.143)
			(size 0.5588 1.016)
			(layers "F.Cu" "F.Mask" "F.Paste")
			(net "GATE_FAN3_R")
		)
	)
	(footprint ""
		(layer "F.Cu")
		(at 165.42893 -362.691426 180)
		(property "Reference" "C550"
			(at 0 0 180)
			(layer "F.SilkS")
			(hide yes)
			(effects
				(font
					(size 1.27 1.27)
				)
			)
		)
		(property "Value" "SC1U16V3KX-5GP"
			(at 0 -2.8194 180)
			(unlocked yes)
			(layer "F.Fab")
			(hide yes)
			(effects
				(font
					(size 1.016 1.016)
					(thickness 0.1524)
				)
			)
		)
		(property "Device Type" "C603H36"
			(at 0 -4.3434 180)
			(unlocked yes)
			(layer "F.Fab")
			(hide yes)
			(effects
				(font
					(size 1.016 1.016)
					(thickness 0.1524)
				)
			)
		)
		(duplicate_pad_numbers_are_jumpers no)
		(fp_line
			(start 0.508 0)
			(end -0.508 0)
			(stroke
				(width 0.2032)
				(type default)
			)
			(layer "F.SilkS")
		)
		(fp_rect
			(start -0.5842 1.3335)
			(end 0.5842 -1.3335)
			(stroke
				(width 0)
				(type default)
			)
			(fill no)
			(layer "F.CrtYd")
		)
		(fp_rect
			(start -0.5842 1.3335)
			(end 0.5842 -1.3335)
			(stroke
				(width 0)
				(type default)
			)
			(fill no)
			(layer "F.Fab")
		)
		(pad "1" smd custom
			(at 0 -0.762 180)
			(size 0.2159 0.2159)
			(layers "F.Cu" "F.Mask" "F.Paste")
			(net "MB0_CM_OV_R")
			(options
				(clearance outline)
				(anchor circle)
			)
			(primitives
				(gr_poly
					(pts
						(arc
							(start -0.3302 -0.4318)
							(mid -0.402042 -0.402042)
							(end -0.4318 -0.3302)
						)
						(arc
							(start -0.4318 0.3302)
							(mid -0.402042 0.402042)
							(end -0.3302 0.4318)
						)
						(arc
							(start 0.3302 0.4318)
							(mid 0.402042 0.402042)
							(end 0.4318 0.3302)
						)
						(arc
							(start 0.4318 -0.3302)
							(mid 0.402042 -0.402042)
							(end 0.3302 -0.4318)
						)
					)
					(width 0)
					(fill yes)
				)
			)
		)
		(pad "2" smd custom
			(at 0 0.762 180)
			(size 0.2159 0.2159)
			(layers "F.Cu" "F.Mask" "F.Paste")
			(net "AGND_CURRENT_MON")
			(options
				(clearance outline)
				(anchor circle)
			)
			(primitives
				(gr_poly
					(pts
						(arc
							(start -0.3302 -0.4318)
							(mid -0.402042 -0.402042)
							(end -0.4318 -0.3302)
						)
						(arc
							(start -0.4318 0.3302)
							(mid -0.402042 0.402042)
							(end -0.3302 0.4318)
						)
						(arc
							(start 0.3302 0.4318)
							(mid 0.402042 0.402042)
							(end 0.4318 0.3302)
						)
						(arc
							(start 0.4318 -0.3302)
							(mid 0.402042 -0.402042)
							(end 0.3302 -0.4318)
						)
					)
					(width 0)
					(fill yes)
				)
			)
		)
	)
	(footprint ""
		(layer "F.Cu")
		(at 222.123 -207.01 90)
		(property "Reference" "R52"
			(at 0 0 90)
			(layer "F.SilkS")
			(hide yes)
			(effects
				(font
					(size 1.27 1.27)
				)
			)
		)
		(property "Value" "4K7R2F-GP"
			(at 0.064008 -3.993896 90)
			(unlocked yes)
			(layer "F.Fab")
			(hide yes)
			(effects
				(font
					(size 1.016 1.016)
					(thickness 0.1524)
				)
			)
		)
		(property "Device Type" "R402H16"
			(at 0.064008 -5.517896 90)
			(unlocked yes)
			(layer "F.Fab")
			(hide yes)
			(effects
				(font
					(size 1.016 1.016)
					(thickness 0.1524)
				)
			)
		)
		(duplicate_pad_numbers_are_jumpers no)
		(fp_line
			(start 0.508 -0.9398)
			(end -0.508 -0.9398)
			(stroke
				(width 0.1524)
				(type default)
			)
			(layer "F.SilkS")
		)
		(fp_line
			(start -0.508 -0.9398)
			(end -0.508 0.9398)
			(stroke
				(width 0.1524)
				(type default)
			)
			(layer "F.SilkS")
		)
		(fp_rect
			(start -0.508 0.9398)
			(end 0.508 -0.9398)
			(stroke
				(width 0)
				(type default)
			)
			(fill no)
			(layer "F.CrtYd")
		)
		(fp_rect
			(start -0.508 0.9398)
			(end 0.508 -0.9398)
			(stroke
				(width 0)
				(type default)
			)
			(fill no)
			(layer "F.Fab")
		)
		(pad "1" smd custom
			(at 0 -0.4445 90)
			(size 0.1397 0.1397)
			(layers "F.Cu" "F.Mask" "F.Paste")
			(net "IO_EXP5_A2")
			(options
				(clearance outline)
				(anchor circle)
			)
			(primitives
				(gr_poly
					(pts
						(arc
							(start -0.1778 -0.2794)
							(mid -0.249642 -0.249642)
							(end -0.2794 -0.1778)
						)
						(arc
							(start -0.2794 0.1778)
							(mid -0.249642 0.249642)
							(end -0.1778 0.2794)
						)
						(arc
							(start 0.1778 0.2794)
							(mid 0.249642 0.249642)
							(end 0.2794 0.1778)
						)
						(arc
							(start 0.2794 -0.1778)
							(mid 0.249642 -0.249642)
							(end 0.1778 -0.2794)
						)
					)
					(width 0)
					(fill yes)
				)
			)
		)
		(pad "2" smd custom
			(at 0 0.4445 90)
			(size 0.1397 0.1397)
			(layers "F.Cu" "F.Mask" "F.Paste")
			(net "GND")
			(options
				(clearance outline)
				(anchor circle)
			)
			(primitives
				(gr_poly
					(pts
						(arc
							(start -0.1778 -0.2794)
							(mid -0.249642 -0.249642)
							(end -0.2794 -0.1778)
						)
						(arc
							(start -0.2794 0.1778)
							(mid -0.249642 0.249642)
							(end -0.1778 0.2794)
						)
						(arc
							(start 0.1778 0.2794)
							(mid 0.249642 0.249642)
							(end 0.2794 0.1778)
						)
						(arc
							(start 0.2794 -0.1778)
							(mid 0.249642 -0.249642)
							(end 0.1778 -0.2794)
						)
					)
					(width 0)
					(fill yes)
				)
			)
		)
	)
	(footprint ""
		(layer "F.Cu")
		(at 160.963864 -39.705026)
		(property "Reference" "TP161"
			(at 0 0 0)
			(layer "F.SilkS")
			(hide yes)
			(effects
				(font
					(size 1.27 1.27)
				)
			)
		)
		(property "Value" "*"
			(at -0.0508 -1.6764 0)
			(unlocked yes)
			(layer "F.Fab")
			(hide yes)
			(effects
				(font
					(size 1.016 1.016)
					(thickness 0.1524)
				)
			)
		)
		(property "Device Type" "TPAD32"
			(at -0.0508 -3.2004 0)
			(unlocked yes)
			(layer "F.Fab")
			(hide yes)
			(effects
				(font
					(size 1.016 1.016)
					(thickness 0.1524)
				)
			)
		)
		(duplicate_pad_numbers_are_jumpers no)
		(fp_poly
			(pts
				(arc
					(start 0.4064 0)
					(mid -0.4064 0)
					(end 0.4064 0)
				)
			)
			(stroke
				(width 0)
				(type default)
			)
			(fill no)
			(layer "F.CrtYd")
		)
		(fp_poly
			(pts
				(arc
					(start 0.7112 0)
					(mid -0.7112 0)
					(end 0.7112 0)
				)
			)
			(stroke
				(width 0)
				(type default)
			)
			(fill no)
			(layer "F.Fab")
		)
		(pad "1" smd circle
			(at 0 0)
			(size 0.8128 0.8128)
			(layers "F.Cu" "F.Mask" "F.Paste")
			(net "ACT_HDD_28")
		)
	)
	(footprint ""
		(layer "F.Cu")
		(at 361.315 -160.401 180)
		(property "Reference" "C284"
			(at 0 0 180)
			(layer "F.SilkS")
			(hide yes)
			(effects
				(font
					(size 1.27 1.27)
				)
			)
		)
		(property "Value" "SC1U25V3KX-GP"
			(at 0 -2.8194 180)
			(unlocked yes)
			(layer "F.Fab")
			(hide yes)
			(effects
				(font
					(size 1.016 1.016)
					(thickness 0.1524)
				)
			)
		)
		(property "Device Type" "C603H36"
			(at 0 -4.3434 180)
			(unlocked yes)
			(layer "F.Fab")
			(hide yes)
			(effects
				(font
					(size 1.016 1.016)
					(thickness 0.1524)
				)
			)
		)
		(duplicate_pad_numbers_are_jumpers no)
		(fp_line
			(start 0.508 0)
			(end -0.508 0)
			(stroke
				(width 0.2032)
				(type default)
			)
			(layer "F.SilkS")
		)
		(fp_rect
			(start -0.5842 1.3335)
			(end 0.5842 -1.3335)
			(stroke
				(width 0)
				(type default)
			)
			(fill no)
			(layer "F.CrtYd")
		)
		(fp_rect
			(start -0.5842 1.3335)
			(end 0.5842 -1.3335)
			(stroke
				(width 0)
				(type default)
			)
			(fill no)
			(layer "F.Fab")
		)
		(pad "1" smd custom
			(at 0 -0.762 180)
			(size 0.2159 0.2159)
			(layers "F.Cu" "F.Mask" "F.Paste")
			(net "P12V_HDD19")
			(options
				(clearance outline)
				(anchor circle)
			)
			(primitives
				(gr_poly
					(pts
						(arc
							(start -0.3302 -0.4318)
							(mid -0.402042 -0.402042)
							(end -0.4318 -0.3302)
						)
						(arc
							(start -0.4318 0.3302)
							(mid -0.402042 0.402042)
							(end -0.3302 0.4318)
						)
						(arc
							(start 0.3302 0.4318)
							(mid 0.402042 0.402042)
							(end 0.4318 0.3302)
						)
						(arc
							(start 0.4318 -0.3302)
							(mid 0.402042 -0.402042)
							(end 0.3302 -0.4318)
						)
					)
					(width 0)
					(fill yes)
				)
			)
		)
		(pad "2" smd custom
			(at 0 0.762 180)
			(size 0.2159 0.2159)
			(layers "F.Cu" "F.Mask" "F.Paste")
			(net "GND")
			(options
				(clearance outline)
				(anchor circle)
			)
			(primitives
				(gr_poly
					(pts
						(arc
							(start -0.3302 -0.4318)
							(mid -0.402042 -0.402042)
							(end -0.4318 -0.3302)
						)
						(arc
							(start -0.4318 0.3302)
							(mid -0.402042 0.402042)
							(end -0.3302 0.4318)
						)
						(arc
							(start 0.3302 0.4318)
							(mid 0.402042 0.402042)
							(end 0.4318 0.3302)
						)
						(arc
							(start 0.4318 -0.3302)
							(mid 0.402042 -0.402042)
							(end 0.3302 -0.4318)
						)
					)
					(width 0)
					(fill yes)
				)
			)
		)
	)
	(footprint ""
		(layer "F.Cu")
		(at 280.444448 -355.415342 -90)
		(property "Reference" "R1075"
			(at 0 0 270)
			(layer "F.SilkS")
			(hide yes)
			(effects
				(font
					(size 1.27 1.27)
				)
			)
		)
		(property "Value" "0R2J-2-GP"
			(at 0.064008 -3.993896 270)
			(unlocked yes)
			(layer "F.Fab")
			(hide yes)
			(effects
				(font
					(size 1.016 1.016)
					(thickness 0.1524)
				)
			)
		)
		(property "Device Type" "R402H16"
			(at 0.064008 -5.517896 270)
			(unlocked yes)
			(layer "F.Fab")
			(hide yes)
			(effects
				(font
					(size 1.016 1.016)
					(thickness 0.1524)
				)
			)
		)
		(duplicate_pad_numbers_are_jumpers no)
		(fp_line
			(start -0.508 -0.9398)
			(end -0.508 0.9398)
			(stroke
				(width 0.1524)
				(type default)
			)
			(layer "F.SilkS")
		)
		(fp_line
			(start 0.508 -0.9398)
			(end -0.508 -0.9398)
			(stroke
				(width 0.1524)
				(type default)
			)
			(layer "F.SilkS")
		)
		(fp_rect
			(start -0.508 0.9398)
			(end 0.508 -0.9398)
			(stroke
				(width 0)
				(type default)
			)
			(fill no)
			(layer "F.CrtYd")
		)
		(fp_rect
			(start -0.508 0.9398)
			(end 0.508 -0.9398)
			(stroke
				(width 0)
				(type default)
			)
			(fill no)
			(layer "F.Fab")
		)
		(pad "1" smd custom
			(at 0 -0.4445 270)
			(size 0.1397 0.1397)
			(layers "F.Cu" "F.Mask" "F.Paste")
			(net "MAX31790_B_SDA")
			(options
				(clearance outline)
				(anchor circle)
			)
			(primitives
				(gr_poly
					(pts
						(arc
							(start -0.1778 -0.2794)
							(mid -0.249642 -0.249642)
							(end -0.2794 -0.1778)
						)
						(arc
							(start -0.2794 0.1778)
							(mid -0.249642 0.249642)
							(end -0.1778 0.2794)
						)
						(arc
							(start 0.1778 0.2794)
							(mid 0.249642 0.249642)
							(end 0.2794 0.1778)
						)
						(arc
							(start 0.2794 -0.1778)
							(mid 0.249642 -0.249642)
							(end 0.1778 -0.2794)
						)
					)
					(width 0)
					(fill yes)
				)
			)
		)
		(pad "2" smd custom
			(at 0 0.4445 270)
			(size 0.1397 0.1397)
			(layers "F.Cu" "F.Mask" "F.Paste")
			(net "I2C_DPB_B_SDA_BUF")
			(options
				(clearance outline)
				(anchor circle)
			)
			(primitives
				(gr_poly
					(pts
						(arc
							(start -0.1778 -0.2794)
							(mid -0.249642 -0.249642)
							(end -0.2794 -0.1778)
						)
						(arc
							(start -0.2794 0.1778)
							(mid -0.249642 0.249642)
							(end -0.1778 0.2794)
						)
						(arc
							(start 0.1778 0.2794)
							(mid 0.249642 0.249642)
							(end 0.2794 0.1778)
						)
						(arc
							(start 0.2794 -0.1778)
							(mid 0.249642 -0.249642)
							(end 0.1778 -0.2794)
						)
					)
					(width 0)
					(fill yes)
				)
			)
		)
	)
	(footprint ""
		(layer "F.Cu")
		(at 86.995 -272.288)
		(property "Reference" "C61"
			(at 0 0 0)
			(layer "F.SilkS")
			(hide yes)
			(effects
				(font
					(size 1.27 1.27)
				)
			)
		)
		(property "Value" "SC4D7U25V5KX-1-GP"
			(at -0.0762 -6.1214 0)
			(unlocked yes)
			(layer "F.Fab")
			(hide yes)
			(effects
				(font
					(size 1.016 1.016)
					(thickness 0.1524)
				)
			)
		)
		(property "Device Type" "C805H58"
			(at -0.0762 -8.1534 0)
			(unlocked yes)
			(layer "F.Fab")
			(hide yes)
			(effects
				(font
					(size 1.016 1.016)
					(thickness 0.1524)
				)
			)
		)
		(duplicate_pad_numbers_are_jumpers no)
		(fp_line
			(start 0.635 0)
			(end -0.635 0)
			(stroke
				(width 0.508)
				(type default)
			)
			(layer "F.SilkS")
		)
		(fp_rect
			(start -0.9652 1.778)
			(end 0.9652 -1.778)
			(stroke
				(width 0)
				(type default)
			)
			(fill no)
			(layer "F.CrtYd")
		)
		(fp_poly
			(pts
				(xy -0.9652 -1.778) (xy 0.9652 -1.778) (xy 0.9652 1.778) (xy -0.9652 1.778)
			)
			(stroke
				(width 0)
				(type default)
			)
			(fill no)
			(layer "F.Fab")
		)
		(pad "1" smd rect
			(at 0 -0.9652)
			(size 1.397 1.143)
			(layers "F.Cu" "F.Mask" "F.Paste")
			(net "P12V_HDD2")
		)
		(pad "2" smd rect
			(at 0 0.9652)
			(size 1.397 1.143)
			(layers "F.Cu" "F.Mask" "F.Paste")
			(net "GND")
		)
	)
	(footprint ""
		(layer "F.Cu")
		(at 426.879004 -364.998)
		(property "Reference" "C538"
			(at 0 0 0)
			(layer "F.SilkS")
			(hide yes)
			(effects
				(font
					(size 1.27 1.27)
				)
			)
		)
		(property "Value" "SCD1U25V2KX-2-GP"
			(at 1.1811 -2.7051 0)
			(unlocked yes)
			(layer "F.Fab")
			(hide yes)
			(effects
				(font
					(size 1.016 1.016)
					(thickness 0.1524)
				)
			)
		)
		(property "Device Type" "C402H22"
			(at 1.1811 -4.2291 0)
			(unlocked yes)
			(layer "F.Fab")
			(hide yes)
			(effects
				(font
					(size 1.016 1.016)
					(thickness 0.1524)
				)
			)
		)
		(duplicate_pad_numbers_are_jumpers no)
		(fp_rect
			(start -0.4318 0.9525)
			(end 0.4318 -0.9525)
			(stroke
				(width 0)
				(type default)
			)
			(fill no)
			(layer "F.CrtYd")
		)
		(fp_rect
			(start -0.4318 0.9525)
			(end 0.4318 -0.9525)
			(stroke
				(width 0)
				(type default)
			)
			(fill no)
			(layer "F.Fab")
		)
		(pad "1" smd custom
			(at 0 -0.4445)
			(size 0.1524 0.1524)
			(layers "F.Cu" "F.Mask" "F.Paste")
			(net "FAN_3_TACH1")
			(options
				(clearance outline)
				(anchor circle)
			)
			(primitives
				(gr_poly
					(pts
						(arc
							(start 0.3048 -0.2032)
							(mid 0.275042 -0.275042)
							(end 0.2032 -0.3048)
						)
						(arc
							(start -0.2032 -0.3048)
							(mid -0.275042 -0.275042)
							(end -0.3048 -0.2032)
						)
						(arc
							(start -0.3048 0.2032)
							(mid -0.275042 0.275042)
							(end -0.2032 0.3048)
						)
						(arc
							(start 0.2032 0.3048)
							(mid 0.275042 0.275042)
							(end 0.3048 0.2032)
						)
					)
					(width 0)
					(fill yes)
				)
			)
		)
		(pad "2" smd custom
			(at 0 0.4445)
			(size 0.1524 0.1524)
			(layers "F.Cu" "F.Mask" "F.Paste")
			(net "GND")
			(options
				(clearance outline)
				(anchor circle)
			)
			(primitives
				(gr_poly
					(pts
						(arc
							(start 0.3048 -0.2032)
							(mid 0.275042 -0.275042)
							(end 0.2032 -0.3048)
						)
						(arc
							(start -0.2032 -0.3048)
							(mid -0.275042 -0.275042)
							(end -0.3048 -0.2032)
						)
						(arc
							(start -0.3048 0.2032)
							(mid -0.275042 0.275042)
							(end -0.2032 0.3048)
						)
						(arc
							(start 0.2032 0.3048)
							(mid 0.275042 0.275042)
							(end 0.3048 0.2032)
						)
					)
					(width 0)
					(fill yes)
				)
			)
		)
	)
	(footprint ""
		(layer "F.Cu")
		(at 332.359 -266.827 180)
		(property "Reference" "C109"
			(at 0 0 180)
			(layer "F.SilkS")
			(hide yes)
			(effects
				(font
					(size 1.27 1.27)
				)
			)
		)
		(property "Value" "SC10U16V6KX-2GP"
			(at -0.0762 -5.1308 180)
			(unlocked yes)
			(layer "F.Fab")
			(hide yes)
			(effects
				(font
					(size 1.016 1.016)
					(thickness 0.1524)
				)
			)
		)
		(property "Device Type" "C1206H71"
			(at -0.127 -6.6548 180)
			(unlocked yes)
			(layer "F.Fab")
			(hide yes)
			(effects
				(font
					(size 1.016 1.016)
					(thickness 0.1524)
				)
			)
		)
		(duplicate_pad_numbers_are_jumpers no)
		(fp_line
			(start 1.016 2.2352)
			(end -1.016 2.2352)
			(stroke
				(width 0.1524)
				(type default)
			)
			(layer "F.SilkS")
		)
		(fp_line
			(start 1.016 0.8382)
			(end 1.016 2.2352)
			(stroke
				(width 0.1524)
				(type default)
			)
			(layer "F.SilkS")
		)
		(fp_line
			(start 1.016 -2.2352)
			(end 1.016 -0.8382)
			(stroke
				(width 0.1524)
				(type default)
			)
			(layer "F.SilkS")
		)
		(fp_line
			(start -1.016 2.2352)
			(end -1.016 0.8382)
			(stroke
				(width 0.1524)
				(type default)
			)
			(layer "F.SilkS")
		)
		(fp_line
			(start -1.016 -0.8382)
			(end -1.016 -2.2352)
			(stroke
				(width 0.1524)
				(type default)
			)
			(layer "F.SilkS")
		)
		(fp_line
			(start -1.016 -2.2352)
			(end 1.016 -2.2352)
			(stroke
				(width 0.1524)
				(type default)
			)
			(layer "F.SilkS")
		)
		(fp_rect
			(start -1.0922 2.3114)
			(end 1.0922 -2.3114)
			(stroke
				(width 0)
				(type default)
			)
			(fill no)
			(layer "F.CrtYd")
		)
		(fp_poly
			(pts
				(xy 1.0922 -2.3114) (xy 1.0922 2.3114) (xy -1.0922 2.3114) (xy -1.0922 -2.3114)
			)
			(stroke
				(width 0)
				(type default)
			)
			(fill no)
			(layer "F.Fab")
		)
		(pad "1" smd rect
			(at 0 -1.397 180)
			(size 1.651 1.27)
			(layers "F.Cu" "F.Mask" "F.Paste")
			(net "P5V_HDD6")
		)
		(pad "2" smd rect
			(at 0 1.397 180)
			(size 1.651 1.27)
			(layers "F.Cu" "F.Mask" "F.Paste")
			(net "GND")
		)
	)
	(footprint ""
		(layer "F.Cu")
		(at 46.482 -255.524 90)
		(property "Reference" "C52"
			(at 0 0 90)
			(layer "F.SilkS")
			(hide yes)
			(effects
				(font
					(size 1.27 1.27)
				)
			)
		)
		(property "Value" "SCD033U25V2KX-GP"
			(at 1.1811 -2.7051 90)
			(unlocked yes)
			(layer "F.Fab")
			(hide yes)
			(effects
				(font
					(size 1.016 1.016)
					(thickness 0.1524)
				)
			)
		)
		(property "Device Type" "C402H22"
			(at 1.1811 -4.2291 90)
			(unlocked yes)
			(layer "F.Fab")
			(hide yes)
			(effects
				(font
					(size 1.016 1.016)
					(thickness 0.1524)
				)
			)
		)
		(duplicate_pad_numbers_are_jumpers no)
		(fp_rect
			(start -0.4318 0.9525)
			(end 0.4318 -0.9525)
			(stroke
				(width 0)
				(type default)
			)
			(fill no)
			(layer "F.CrtYd")
		)
		(fp_rect
			(start -0.4318 0.9525)
			(end 0.4318 -0.9525)
			(stroke
				(width 0)
				(type default)
			)
			(fill no)
			(layer "F.Fab")
		)
		(pad "1" smd custom
			(at 0 -0.4445 90)
			(size 0.1524 0.1524)
			(layers "F.Cu" "F.Mask" "F.Paste")
			(net "P12V_B")
			(options
				(clearance outline)
				(anchor circle)
			)
			(primitives
				(gr_poly
					(pts
						(arc
							(start 0.3048 -0.2032)
							(mid 0.275042 -0.275042)
							(end 0.2032 -0.3048)
						)
						(arc
							(start -0.2032 -0.3048)
							(mid -0.275042 -0.275042)
							(end -0.3048 -0.2032)
						)
						(arc
							(start -0.3048 0.2032)
							(mid -0.275042 0.275042)
							(end -0.2032 0.3048)
						)
						(arc
							(start 0.2032 0.3048)
							(mid 0.275042 0.275042)
							(end 0.3048 0.2032)
						)
					)
					(width 0)
					(fill yes)
				)
			)
		)
		(pad "2" smd custom
			(at 0 0.4445 90)
			(size 0.1524 0.1524)
			(layers "F.Cu" "F.Mask" "F.Paste")
			(net "SW_HDD_N1")
			(options
				(clearance outline)
				(anchor circle)
			)
			(primitives
				(gr_poly
					(pts
						(arc
							(start 0.3048 -0.2032)
							(mid 0.275042 -0.275042)
							(end 0.2032 -0.3048)
						)
						(arc
							(start -0.2032 -0.3048)
							(mid -0.275042 -0.275042)
							(end -0.3048 -0.2032)
						)
						(arc
							(start -0.3048 0.2032)
							(mid -0.275042 0.275042)
							(end -0.2032 0.3048)
						)
						(arc
							(start 0.2032 0.3048)
							(mid 0.275042 0.275042)
							(end 0.3048 0.2032)
						)
					)
					(width 0)
					(fill yes)
				)
			)
		)
	)
	(footprint ""
		(layer "F.Cu")
		(at 216.140538 -104.671368)
		(property "Reference" "R14"
			(at 0 0 0)
			(layer "F.SilkS")
			(hide yes)
			(effects
				(font
					(size 1.27 1.27)
				)
			)
		)
		(property "Value" "1KR2F-3-GP"
			(at 0.064008 -3.993896 0)
			(unlocked yes)
			(layer "F.Fab")
			(hide yes)
			(effects
				(font
					(size 1.016 1.016)
					(thickness 0.1524)
				)
			)
		)
		(property "Device Type" "R402H16"
			(at 0.064008 -5.517896 0)
			(unlocked yes)
			(layer "F.Fab")
			(hide yes)
			(effects
				(font
					(size 1.016 1.016)
					(thickness 0.1524)
				)
			)
		)
		(duplicate_pad_numbers_are_jumpers no)
		(fp_line
			(start -0.508 -0.9398)
			(end -0.508 0.9398)
			(stroke
				(width 0.1524)
				(type default)
			)
			(layer "F.SilkS")
		)
		(fp_line
			(start 0.508 -0.9398)
			(end -0.508 -0.9398)
			(stroke
				(width 0.1524)
				(type default)
			)
			(layer "F.SilkS")
		)
		(fp_rect
			(start -0.508 0.9398)
			(end 0.508 -0.9398)
			(stroke
				(width 0)
				(type default)
			)
			(fill no)
			(layer "F.CrtYd")
		)
		(fp_rect
			(start -0.508 0.9398)
			(end 0.508 -0.9398)
			(stroke
				(width 0)
				(type default)
			)
			(fill no)
			(layer "F.Fab")
		)
		(pad "1" smd custom
			(at 0 -0.4445)
			(size 0.1397 0.1397)
			(layers "F.Cu" "F.Mask" "F.Paste")
			(net "P3V3_STBY_B")
			(options
				(clearance outline)
				(anchor circle)
			)
			(primitives
				(gr_poly
					(pts
						(arc
							(start -0.1778 -0.2794)
							(mid -0.249642 -0.249642)
							(end -0.2794 -0.1778)
						)
						(arc
							(start -0.2794 0.1778)
							(mid -0.249642 0.249642)
							(end -0.1778 0.2794)
						)
						(arc
							(start 0.1778 0.2794)
							(mid 0.249642 0.249642)
							(end 0.2794 0.1778)
						)
						(arc
							(start 0.2794 -0.1778)
							(mid 0.249642 -0.249642)
							(end 0.1778 -0.2794)
						)
					)
					(width 0)
					(fill yes)
				)
			)
		)
		(pad "2" smd custom
			(at 0 0.4445)
			(size 0.1397 0.1397)
			(layers "F.Cu" "F.Mask" "F.Paste")
			(net "I2C_BMC_A_EXP_B_SCL")
			(options
				(clearance outline)
				(anchor circle)
			)
			(primitives
				(gr_poly
					(pts
						(arc
							(start -0.1778 -0.2794)
							(mid -0.249642 -0.249642)
							(end -0.2794 -0.1778)
						)
						(arc
							(start -0.2794 0.1778)
							(mid -0.249642 0.249642)
							(end -0.1778 0.2794)
						)
						(arc
							(start 0.1778 0.2794)
							(mid 0.249642 0.249642)
							(end 0.2794 0.1778)
						)
						(arc
							(start 0.2794 -0.1778)
							(mid 0.249642 -0.249642)
							(end 0.1778 -0.2794)
						)
					)
					(width 0)
					(fill yes)
				)
			)
		)
	)
	(footprint ""
		(layer "F.Cu")
		(at 334.7212 -13.2842 180)
		(property "Reference" "R774"
			(at 0 0 180)
			(layer "F.SilkS")
			(hide yes)
			(effects
				(font
					(size 1.27 1.27)
				)
			)
		)
		(property "Value" "4K7R2J-2-GP"
			(at 0.064008 -3.993896 180)
			(unlocked yes)
			(layer "F.Fab")
			(hide yes)
			(effects
				(font
					(size 1.016 1.016)
					(thickness 0.1524)
				)
			)
		)
		(property "Device Type" "R402H16"
			(at 0.064008 -5.517896 180)
			(unlocked yes)
			(layer "F.Fab")
			(hide yes)
			(effects
				(font
					(size 1.016 1.016)
					(thickness 0.1524)
				)
			)
		)
		(duplicate_pad_numbers_are_jumpers no)
		(fp_line
			(start 0.508 -0.9398)
			(end -0.508 -0.9398)
			(stroke
				(width 0.1524)
				(type default)
			)
			(layer "F.SilkS")
		)
		(fp_line
			(start -0.508 -0.9398)
			(end -0.508 0.9398)
			(stroke
				(width 0.1524)
				(type default)
			)
			(layer "F.SilkS")
		)
		(fp_rect
			(start -0.508 0.9398)
			(end 0.508 -0.9398)
			(stroke
				(width 0)
				(type default)
			)
			(fill no)
			(layer "F.CrtYd")
		)
		(fp_rect
			(start -0.508 0.9398)
			(end 0.508 -0.9398)
			(stroke
				(width 0)
				(type default)
			)
			(fill no)
			(layer "F.Fab")
		)
		(pad "1" smd custom
			(at 0 -0.4445 180)
			(size 0.1397 0.1397)
			(layers "F.Cu" "F.Mask" "F.Paste")
			(net "P12V_B")
			(options
				(clearance outline)
				(anchor circle)
			)
			(primitives
				(gr_poly
					(pts
						(arc
							(start -0.1778 -0.2794)
							(mid -0.249642 -0.249642)
							(end -0.2794 -0.1778)
						)
						(arc
							(start -0.2794 0.1778)
							(mid -0.249642 0.249642)
							(end -0.1778 0.2794)
						)
						(arc
							(start 0.1778 0.2794)
							(mid 0.249642 0.249642)
							(end 0.2794 0.1778)
						)
						(arc
							(start 0.2794 -0.1778)
							(mid 0.249642 -0.249642)
							(end 0.1778 -0.2794)
						)
					)
					(width 0)
					(fill yes)
				)
			)
		)
		(pad "2" smd custom
			(at 0 0.4445 180)
			(size 0.1397 0.1397)
			(layers "F.Cu" "F.Mask" "F.Paste")
			(net "SW_HDD_R30")
			(options
				(clearance outline)
				(anchor circle)
			)
			(primitives
				(gr_poly
					(pts
						(arc
							(start -0.1778 -0.2794)
							(mid -0.249642 -0.249642)
							(end -0.2794 -0.1778)
						)
						(arc
							(start -0.2794 0.1778)
							(mid -0.249642 0.249642)
							(end -0.1778 0.2794)
						)
						(arc
							(start 0.1778 0.2794)
							(mid 0.249642 0.249642)
							(end 0.2794 0.1778)
						)
						(arc
							(start 0.2794 -0.1778)
							(mid 0.249642 -0.249642)
							(end 0.1778 -0.2794)
						)
					)
					(width 0)
					(fill yes)
				)
			)
		)
	)
	(footprint ""
		(layer "F.Cu")
		(at 86.0806 -248.4628 -90)
		(property "Reference" "R196"
			(at 0 0 270)
			(layer "F.SilkS")
			(hide yes)
			(effects
				(font
					(size 1.27 1.27)
				)
			)
		)
		(property "Value" "1KR2F-3-GP"
			(at 0.064008 -3.993896 270)
			(unlocked yes)
			(layer "F.Fab")
			(hide yes)
			(effects
				(font
					(size 1.016 1.016)
					(thickness 0.1524)
				)
			)
		)
		(property "Device Type" "R402H16"
			(at 0.064008 -5.517896 270)
			(unlocked yes)
			(layer "F.Fab")
			(hide yes)
			(effects
				(font
					(size 1.016 1.016)
					(thickness 0.1524)
				)
			)
		)
		(duplicate_pad_numbers_are_jumpers no)
		(fp_line
			(start -0.508 -0.9398)
			(end -0.508 0.9398)
			(stroke
				(width 0.1524)
				(type default)
			)
			(layer "F.SilkS")
		)
		(fp_line
			(start 0.508 -0.9398)
			(end -0.508 -0.9398)
			(stroke
				(width 0.1524)
				(type default)
			)
			(layer "F.SilkS")
		)
		(fp_rect
			(start -0.508 0.9398)
			(end 0.508 -0.9398)
			(stroke
				(width 0)
				(type default)
			)
			(fill no)
			(layer "F.CrtYd")
		)
		(fp_rect
			(start -0.508 0.9398)
			(end 0.508 -0.9398)
			(stroke
				(width 0)
				(type default)
			)
			(fill no)
			(layer "F.Fab")
		)
		(pad "1" smd custom
			(at 0 -0.4445 270)
			(size 0.1397 0.1397)
			(layers "F.Cu" "F.Mask" "F.Paste")
			(net "P3V3_STBY_B")
			(options
				(clearance outline)
				(anchor circle)
			)
			(primitives
				(gr_poly
					(pts
						(arc
							(start -0.1778 -0.2794)
							(mid -0.249642 -0.249642)
							(end -0.2794 -0.1778)
						)
						(arc
							(start -0.2794 0.1778)
							(mid -0.249642 0.249642)
							(end -0.1778 0.2794)
						)
						(arc
							(start 0.1778 0.2794)
							(mid 0.249642 0.249642)
							(end 0.2794 0.1778)
						)
						(arc
							(start 0.2794 -0.1778)
							(mid 0.249642 -0.249642)
							(end 0.1778 -0.2794)
						)
					)
					(width 0)
					(fill yes)
				)
			)
		)
		(pad "2" smd custom
			(at 0 0.4445 270)
			(size 0.1397 0.1397)
			(layers "F.Cu" "F.Mask" "F.Paste")
			(net "SW_PWR_R_HDD2")
			(options
				(clearance outline)
				(anchor circle)
			)
			(primitives
				(gr_poly
					(pts
						(arc
							(start -0.1778 -0.2794)
							(mid -0.249642 -0.249642)
							(end -0.2794 -0.1778)
						)
						(arc
							(start -0.2794 0.1778)
							(mid -0.249642 0.249642)
							(end -0.1778 0.2794)
						)
						(arc
							(start 0.1778 0.2794)
							(mid 0.249642 0.249642)
							(end 0.2794 0.1778)
						)
						(arc
							(start 0.2794 -0.1778)
							(mid 0.249642 -0.249642)
							(end 0.1778 -0.2794)
						)
					)
					(width 0)
					(fill yes)
				)
			)
		)
	)
	(footprint ""
		(layer "F.Cu")
		(at 83.185 -32.004 -90)
		(property "Reference" "C369"
			(at 0 0 270)
			(layer "F.SilkS")
			(hide yes)
			(effects
				(font
					(size 1.27 1.27)
				)
			)
		)
		(property "Value" "SC10U16V6KX-2GP"
			(at -0.0762 -5.1308 270)
			(unlocked yes)
			(layer "F.Fab")
			(hide yes)
			(effects
				(font
					(size 1.016 1.016)
					(thickness 0.1524)
				)
			)
		)
		(property "Device Type" "C1206H71"
			(at -0.127 -6.6548 270)
			(unlocked yes)
			(layer "F.Fab")
			(hide yes)
			(effects
				(font
					(size 1.016 1.016)
					(thickness 0.1524)
				)
			)
		)
		(duplicate_pad_numbers_are_jumpers no)
		(fp_line
			(start -1.016 2.2352)
			(end -1.016 0.8382)
			(stroke
				(width 0.1524)
				(type default)
			)
			(layer "F.SilkS")
		)
		(fp_line
			(start 1.016 2.2352)
			(end -1.016 2.2352)
			(stroke
				(width 0.1524)
				(type default)
			)
			(layer "F.SilkS")
		)
		(fp_line
			(start 1.016 0.8382)
			(end 1.016 2.2352)
			(stroke
				(width 0.1524)
				(type default)
			)
			(layer "F.SilkS")
		)
		(fp_line
			(start -1.016 -0.8382)
			(end -1.016 -2.2352)
			(stroke
				(width 0.1524)
				(type default)
			)
			(layer "F.SilkS")
		)
		(fp_line
			(start -1.016 -2.2352)
			(end 1.016 -2.2352)
			(stroke
				(width 0.1524)
				(type default)
			)
			(layer "F.SilkS")
		)
		(fp_line
			(start 1.016 -2.2352)
			(end 1.016 -0.8382)
			(stroke
				(width 0.1524)
				(type default)
			)
			(layer "F.SilkS")
		)
		(fp_rect
			(start -1.0922 2.3114)
			(end 1.0922 -2.3114)
			(stroke
				(width 0)
				(type default)
			)
			(fill no)
			(layer "F.CrtYd")
		)
		(fp_poly
			(pts
				(xy 1.0922 -2.3114) (xy 1.0922 2.3114) (xy -1.0922 2.3114) (xy -1.0922 -2.3114)
			)
			(stroke
				(width 0)
				(type default)
			)
			(fill no)
			(layer "F.Fab")
		)
		(pad "1" smd rect
			(at 0 -1.397 270)
			(size 1.651 1.27)
			(layers "F.Cu" "F.Mask" "F.Paste")
			(net "P5V_HDD26")
		)
		(pad "2" smd rect
			(at 0 1.397 270)
			(size 1.651 1.27)
			(layers "F.Cu" "F.Mask" "F.Paste")
			(net "GND")
		)
	)
	(footprint ""
		(layer "F.Cu")
		(at 44.1706 -6.3754 -90)
		(property "Reference" "R130"
			(at 0 0 270)
			(layer "F.SilkS")
			(hide yes)
			(effects
				(font
					(size 1.27 1.27)
				)
			)
		)
		(property "Value" "4K7R2F-GP"
			(at 0.064008 -3.993896 270)
			(unlocked yes)
			(layer "F.Fab")
			(hide yes)
			(effects
				(font
					(size 1.016 1.016)
					(thickness 0.1524)
				)
			)
		)
		(property "Device Type" "R402H16"
			(at 0.064008 -5.517896 270)
			(unlocked yes)
			(layer "F.Fab")
			(hide yes)
			(effects
				(font
					(size 1.016 1.016)
					(thickness 0.1524)
				)
			)
		)
		(duplicate_pad_numbers_are_jumpers no)
		(fp_line
			(start -0.508 -0.9398)
			(end -0.508 0.9398)
			(stroke
				(width 0.1524)
				(type default)
			)
			(layer "F.SilkS")
		)
		(fp_line
			(start 0.508 -0.9398)
			(end -0.508 -0.9398)
			(stroke
				(width 0.1524)
				(type default)
			)
			(layer "F.SilkS")
		)
		(fp_rect
			(start -0.508 0.9398)
			(end 0.508 -0.9398)
			(stroke
				(width 0)
				(type default)
			)
			(fill no)
			(layer "F.CrtYd")
		)
		(fp_rect
			(start -0.508 0.9398)
			(end 0.508 -0.9398)
			(stroke
				(width 0)
				(type default)
			)
			(fill no)
			(layer "F.Fab")
		)
		(pad "1" smd custom
			(at 0 -0.4445 270)
			(size 0.1397 0.1397)
			(layers "F.Cu" "F.Mask" "F.Paste")
			(net "P3V3_STBY_A")
			(options
				(clearance outline)
				(anchor circle)
			)
			(primitives
				(gr_poly
					(pts
						(arc
							(start -0.1778 -0.2794)
							(mid -0.249642 -0.249642)
							(end -0.2794 -0.1778)
						)
						(arc
							(start -0.2794 0.1778)
							(mid -0.249642 0.249642)
							(end -0.1778 0.2794)
						)
						(arc
							(start 0.1778 0.2794)
							(mid 0.249642 0.249642)
							(end 0.2794 0.1778)
						)
						(arc
							(start 0.2794 -0.1778)
							(mid 0.249642 -0.249642)
							(end 0.1778 -0.2794)
						)
					)
					(width 0)
					(fill yes)
				)
			)
		)
		(pad "2" smd custom
			(at 0 0.4445 270)
			(size 0.1397 0.1397)
			(layers "F.Cu" "F.Mask" "F.Paste")
			(net "TEMP1_A1")
			(options
				(clearance outline)
				(anchor circle)
			)
			(primitives
				(gr_poly
					(pts
						(arc
							(start -0.1778 -0.2794)
							(mid -0.249642 -0.249642)
							(end -0.2794 -0.1778)
						)
						(arc
							(start -0.2794 0.1778)
							(mid -0.249642 0.249642)
							(end -0.1778 0.2794)
						)
						(arc
							(start 0.1778 0.2794)
							(mid 0.249642 0.249642)
							(end 0.2794 0.1778)
						)
						(arc
							(start 0.2794 -0.1778)
							(mid 0.249642 -0.249642)
							(end 0.1778 -0.2794)
						)
					)
					(width 0)
					(fill yes)
				)
			)
		)
	)
	(footprint ""
		(layer "F.Cu")
		(at 260.546596 -238.583724 -90)
		(property "Reference" "R497"
			(at 0 0 270)
			(layer "F.SilkS")
			(hide yes)
			(effects
				(font
					(size 1.27 1.27)
				)
			)
		)
		(property "Value" "10KR2F-2-GP"
			(at 0.064008 -3.993896 270)
			(unlocked yes)
			(layer "F.Fab")
			(hide yes)
			(effects
				(font
					(size 1.016 1.016)
					(thickness 0.1524)
				)
			)
		)
		(property "Device Type" "R402H16"
			(at 0.064008 -5.517896 270)
			(unlocked yes)
			(layer "F.Fab")
			(hide yes)
			(effects
				(font
					(size 1.016 1.016)
					(thickness 0.1524)
				)
			)
		)
		(duplicate_pad_numbers_are_jumpers no)
		(fp_line
			(start -0.508 -0.9398)
			(end -0.508 0.9398)
			(stroke
				(width 0.1524)
				(type default)
			)
			(layer "F.SilkS")
		)
		(fp_line
			(start 0.508 -0.9398)
			(end -0.508 -0.9398)
			(stroke
				(width 0.1524)
				(type default)
			)
			(layer "F.SilkS")
		)
		(fp_rect
			(start -0.508 0.9398)
			(end 0.508 -0.9398)
			(stroke
				(width 0)
				(type default)
			)
			(fill no)
			(layer "F.CrtYd")
		)
		(fp_rect
			(start -0.508 0.9398)
			(end 0.508 -0.9398)
			(stroke
				(width 0)
				(type default)
			)
			(fill no)
			(layer "F.Fab")
		)
		(pad "1" smd custom
			(at 0 -0.4445 270)
			(size 0.1397 0.1397)
			(layers "F.Cu" "F.Mask" "F.Paste")
			(net "P12V_B")
			(options
				(clearance outline)
				(anchor circle)
			)
			(primitives
				(gr_poly
					(pts
						(arc
							(start -0.1778 -0.2794)
							(mid -0.249642 -0.249642)
							(end -0.2794 -0.1778)
						)
						(arc
							(start -0.2794 0.1778)
							(mid -0.249642 0.249642)
							(end -0.1778 0.2794)
						)
						(arc
							(start 0.1778 0.2794)
							(mid 0.249642 0.249642)
							(end 0.2794 0.1778)
						)
						(arc
							(start 0.2794 -0.1778)
							(mid 0.249642 -0.249642)
							(end 0.1778 -0.2794)
						)
					)
					(width 0)
					(fill yes)
				)
			)
		)
		(pad "2" smd custom
			(at 0 0.4445 270)
			(size 0.1397 0.1397)
			(layers "F.Cu" "F.Mask" "F.Paste")
			(net "SCC_B_FULL_PWR_EN_12V")
			(options
				(clearance outline)
				(anchor circle)
			)
			(primitives
				(gr_poly
					(pts
						(arc
							(start -0.1778 -0.2794)
							(mid -0.249642 -0.249642)
							(end -0.2794 -0.1778)
						)
						(arc
							(start -0.2794 0.1778)
							(mid -0.249642 0.249642)
							(end -0.1778 0.2794)
						)
						(arc
							(start 0.1778 0.2794)
							(mid 0.249642 0.249642)
							(end 0.2794 0.1778)
						)
						(arc
							(start 0.2794 -0.1778)
							(mid 0.249642 -0.249642)
							(end 0.1778 -0.2794)
						)
					)
					(width 0)
					(fill yes)
				)
			)
		)
	)
	(footprint ""
		(layer "F.Cu")
		(at 303.249076 -340.812882)
		(property "Reference" "R94"
			(at 0 0 0)
			(layer "F.SilkS")
			(hide yes)
			(effects
				(font
					(size 1.27 1.27)
				)
			)
		)
		(property "Value" "4K7R2F-GP"
			(at 0.064008 -3.993896 0)
			(unlocked yes)
			(layer "F.Fab")
			(hide yes)
			(effects
				(font
					(size 1.016 1.016)
					(thickness 0.1524)
				)
			)
		)
		(property "Device Type" "R402H16"
			(at 0.064008 -5.517896 0)
			(unlocked yes)
			(layer "F.Fab")
			(hide yes)
			(effects
				(font
					(size 1.016 1.016)
					(thickness 0.1524)
				)
			)
		)
		(duplicate_pad_numbers_are_jumpers no)
		(fp_line
			(start -0.508 -0.9398)
			(end -0.508 0.9398)
			(stroke
				(width 0.1524)
				(type default)
			)
			(layer "F.SilkS")
		)
		(fp_line
			(start 0.508 -0.9398)
			(end -0.508 -0.9398)
			(stroke
				(width 0.1524)
				(type default)
			)
			(layer "F.SilkS")
		)
		(fp_rect
			(start -0.508 0.9398)
			(end 0.508 -0.9398)
			(stroke
				(width 0)
				(type default)
			)
			(fill no)
			(layer "F.CrtYd")
		)
		(fp_rect
			(start -0.508 0.9398)
			(end 0.508 -0.9398)
			(stroke
				(width 0)
				(type default)
			)
			(fill no)
			(layer "F.Fab")
		)
		(pad "1" smd custom
			(at 0 -0.4445)
			(size 0.1397 0.1397)
			(layers "F.Cu" "F.Mask" "F.Paste")
			(net "P3V3_IN")
			(options
				(clearance outline)
				(anchor circle)
			)
			(primitives
				(gr_poly
					(pts
						(arc
							(start -0.1778 -0.2794)
							(mid -0.249642 -0.249642)
							(end -0.2794 -0.1778)
						)
						(arc
							(start -0.2794 0.1778)
							(mid -0.249642 0.249642)
							(end -0.1778 0.2794)
						)
						(arc
							(start 0.1778 0.2794)
							(mid 0.249642 0.249642)
							(end 0.2794 0.1778)
						)
						(arc
							(start 0.2794 -0.1778)
							(mid 0.249642 -0.249642)
							(end 0.1778 -0.2794)
						)
					)
					(width 0)
					(fill yes)
				)
			)
		)
		(pad "2" smd custom
			(at 0 0.4445)
			(size 0.1397 0.1397)
			(layers "F.Cu" "F.Mask" "F.Paste")
			(net "THERMHOT#_C")
			(options
				(clearance outline)
				(anchor circle)
			)
			(primitives
				(gr_poly
					(pts
						(arc
							(start -0.1778 -0.2794)
							(mid -0.249642 -0.249642)
							(end -0.2794 -0.1778)
						)
						(arc
							(start -0.2794 0.1778)
							(mid -0.249642 0.249642)
							(end -0.1778 0.2794)
						)
						(arc
							(start 0.1778 0.2794)
							(mid 0.249642 0.249642)
							(end 0.2794 0.1778)
						)
						(arc
							(start 0.2794 -0.1778)
							(mid 0.249642 -0.249642)
							(end 0.1778 -0.2794)
						)
					)
					(width 0)
					(fill yes)
				)
			)
		)
	)
	(footprint ""
		(layer "F.Cu")
		(at 463.1944 -8.128 -90)
		(property "Reference" "R141"
			(at 0 0 270)
			(layer "F.SilkS")
			(hide yes)
			(effects
				(font
					(size 1.27 1.27)
				)
			)
		)
		(property "Value" "4K7R2F-GP"
			(at 0.064008 -3.993896 270)
			(unlocked yes)
			(layer "F.Fab")
			(hide yes)
			(effects
				(font
					(size 1.016 1.016)
					(thickness 0.1524)
				)
			)
		)
		(property "Device Type" "R402H16"
			(at 0.064008 -5.517896 270)
			(unlocked yes)
			(layer "F.Fab")
			(hide yes)
			(effects
				(font
					(size 1.016 1.016)
					(thickness 0.1524)
				)
			)
		)
		(duplicate_pad_numbers_are_jumpers no)
		(fp_line
			(start -0.508 -0.9398)
			(end -0.508 0.9398)
			(stroke
				(width 0.1524)
				(type default)
			)
			(layer "F.SilkS")
		)
		(fp_line
			(start 0.508 -0.9398)
			(end -0.508 -0.9398)
			(stroke
				(width 0.1524)
				(type default)
			)
			(layer "F.SilkS")
		)
		(fp_rect
			(start -0.508 0.9398)
			(end 0.508 -0.9398)
			(stroke
				(width 0)
				(type default)
			)
			(fill no)
			(layer "F.CrtYd")
		)
		(fp_rect
			(start -0.508 0.9398)
			(end 0.508 -0.9398)
			(stroke
				(width 0)
				(type default)
			)
			(fill no)
			(layer "F.Fab")
		)
		(pad "1" smd custom
			(at 0 -0.4445 270)
			(size 0.1397 0.1397)
			(layers "F.Cu" "F.Mask" "F.Paste")
			(net "TEMP2_A0")
			(options
				(clearance outline)
				(anchor circle)
			)
			(primitives
				(gr_poly
					(pts
						(arc
							(start -0.1778 -0.2794)
							(mid -0.249642 -0.249642)
							(end -0.2794 -0.1778)
						)
						(arc
							(start -0.2794 0.1778)
							(mid -0.249642 0.249642)
							(end -0.1778 0.2794)
						)
						(arc
							(start 0.1778 0.2794)
							(mid 0.249642 0.249642)
							(end 0.2794 0.1778)
						)
						(arc
							(start 0.2794 -0.1778)
							(mid 0.249642 -0.249642)
							(end 0.1778 -0.2794)
						)
					)
					(width 0)
					(fill yes)
				)
			)
		)
		(pad "2" smd custom
			(at 0 0.4445 270)
			(size 0.1397 0.1397)
			(layers "F.Cu" "F.Mask" "F.Paste")
			(net "GND")
			(options
				(clearance outline)
				(anchor circle)
			)
			(primitives
				(gr_poly
					(pts
						(arc
							(start -0.1778 -0.2794)
							(mid -0.249642 -0.249642)
							(end -0.2794 -0.1778)
						)
						(arc
							(start -0.2794 0.1778)
							(mid -0.249642 0.249642)
							(end -0.1778 0.2794)
						)
						(arc
							(start 0.1778 0.2794)
							(mid 0.249642 0.249642)
							(end 0.2794 0.1778)
						)
						(arc
							(start 0.2794 -0.1778)
							(mid 0.249642 -0.249642)
							(end 0.1778 -0.2794)
						)
					)
					(width 0)
					(fill yes)
				)
			)
		)
	)
	(footprint ""
		(layer "F.Cu")
		(at 41.275 -5.3594 -90)
		(property "Reference" "R129"
			(at 0 0 270)
			(layer "F.SilkS")
			(hide yes)
			(effects
				(font
					(size 1.27 1.27)
				)
			)
		)
		(property "Value" "4K7R2F-GP"
			(at 0.064008 -3.993896 270)
			(unlocked yes)
			(layer "F.Fab")
			(hide yes)
			(effects
				(font
					(size 1.016 1.016)
					(thickness 0.1524)
				)
			)
		)
		(property "Device Type" "R402H16"
			(at 0.064008 -5.517896 270)
			(unlocked yes)
			(layer "F.Fab")
			(hide yes)
			(effects
				(font
					(size 1.016 1.016)
					(thickness 0.1524)
				)
			)
		)
		(duplicate_pad_numbers_are_jumpers no)
		(fp_line
			(start -0.508 -0.9398)
			(end -0.508 0.9398)
			(stroke
				(width 0.1524)
				(type default)
			)
			(layer "F.SilkS")
		)
		(fp_line
			(start 0.508 -0.9398)
			(end -0.508 -0.9398)
			(stroke
				(width 0.1524)
				(type default)
			)
			(layer "F.SilkS")
		)
		(fp_rect
			(start -0.508 0.9398)
			(end 0.508 -0.9398)
			(stroke
				(width 0)
				(type default)
			)
			(fill no)
			(layer "F.CrtYd")
		)
		(fp_rect
			(start -0.508 0.9398)
			(end 0.508 -0.9398)
			(stroke
				(width 0)
				(type default)
			)
			(fill no)
			(layer "F.Fab")
		)
		(pad "1" smd custom
			(at 0 -0.4445 270)
			(size 0.1397 0.1397)
			(layers "F.Cu" "F.Mask" "F.Paste")
			(net "TEMP1_A2")
			(options
				(clearance outline)
				(anchor circle)
			)
			(primitives
				(gr_poly
					(pts
						(arc
							(start -0.1778 -0.2794)
							(mid -0.249642 -0.249642)
							(end -0.2794 -0.1778)
						)
						(arc
							(start -0.2794 0.1778)
							(mid -0.249642 0.249642)
							(end -0.1778 0.2794)
						)
						(arc
							(start 0.1778 0.2794)
							(mid 0.249642 0.249642)
							(end 0.2794 0.1778)
						)
						(arc
							(start 0.2794 -0.1778)
							(mid 0.249642 -0.249642)
							(end 0.1778 -0.2794)
						)
					)
					(width 0)
					(fill yes)
				)
			)
		)
		(pad "2" smd custom
			(at 0 0.4445 270)
			(size 0.1397 0.1397)
			(layers "F.Cu" "F.Mask" "F.Paste")
			(net "GND")
			(options
				(clearance outline)
				(anchor circle)
			)
			(primitives
				(gr_poly
					(pts
						(arc
							(start -0.1778 -0.2794)
							(mid -0.249642 -0.249642)
							(end -0.2794 -0.1778)
						)
						(arc
							(start -0.2794 0.1778)
							(mid -0.249642 0.249642)
							(end -0.1778 0.2794)
						)
						(arc
							(start 0.1778 0.2794)
							(mid 0.249642 0.249642)
							(end 0.2794 0.1778)
						)
						(arc
							(start 0.2794 -0.1778)
							(mid 0.249642 -0.249642)
							(end 0.1778 -0.2794)
						)
					)
					(width 0)
					(fill yes)
				)
			)
		)
	)
	(footprint ""
		(layer "F.Cu")
		(at 394.462 -10.16)
		(property "Reference" "R818"
			(at 0 0 0)
			(layer "F.SilkS")
			(hide yes)
			(effects
				(font
					(size 1.27 1.27)
				)
			)
		)
		(property "Value" "4K7R2F-GP"
			(at 0.064008 -3.993896 0)
			(unlocked yes)
			(layer "F.Fab")
			(hide yes)
			(effects
				(font
					(size 1.016 1.016)
					(thickness 0.1524)
				)
			)
		)
		(property "Device Type" "R402H16"
			(at 0.064008 -5.517896 0)
			(unlocked yes)
			(layer "F.Fab")
			(hide yes)
			(effects
				(font
					(size 1.016 1.016)
					(thickness 0.1524)
				)
			)
		)
		(duplicate_pad_numbers_are_jumpers no)
		(fp_line
			(start -0.508 -0.9398)
			(end -0.508 0.9398)
			(stroke
				(width 0.1524)
				(type default)
			)
			(layer "F.SilkS")
		)
		(fp_line
			(start 0.508 -0.9398)
			(end -0.508 -0.9398)
			(stroke
				(width 0.1524)
				(type default)
			)
			(layer "F.SilkS")
		)
		(fp_rect
			(start -0.508 0.9398)
			(end 0.508 -0.9398)
			(stroke
				(width 0)
				(type default)
			)
			(fill no)
			(layer "F.CrtYd")
		)
		(fp_rect
			(start -0.508 0.9398)
			(end 0.508 -0.9398)
			(stroke
				(width 0)
				(type default)
			)
			(fill no)
			(layer "F.Fab")
		)
		(pad "1" smd custom
			(at 0 -0.4445)
			(size 0.1397 0.1397)
			(layers "F.Cu" "F.Mask" "F.Paste")
			(net "SW_PWR_R_HDD32")
			(options
				(clearance outline)
				(anchor circle)
			)
			(primitives
				(gr_poly
					(pts
						(arc
							(start -0.1778 -0.2794)
							(mid -0.249642 -0.249642)
							(end -0.2794 -0.1778)
						)
						(arc
							(start -0.2794 0.1778)
							(mid -0.249642 0.249642)
							(end -0.1778 0.2794)
						)
						(arc
							(start 0.1778 0.2794)
							(mid 0.249642 0.249642)
							(end 0.2794 0.1778)
						)
						(arc
							(start 0.2794 -0.1778)
							(mid 0.249642 -0.249642)
							(end 0.1778 -0.2794)
						)
					)
					(width 0)
					(fill yes)
				)
			)
		)
		(pad "2" smd custom
			(at 0 0.4445)
			(size 0.1397 0.1397)
			(layers "F.Cu" "F.Mask" "F.Paste")
			(net "GND")
			(options
				(clearance outline)
				(anchor circle)
			)
			(primitives
				(gr_poly
					(pts
						(arc
							(start -0.1778 -0.2794)
							(mid -0.249642 -0.249642)
							(end -0.2794 -0.1778)
						)
						(arc
							(start -0.2794 0.1778)
							(mid -0.249642 0.249642)
							(end -0.1778 0.2794)
						)
						(arc
							(start 0.1778 0.2794)
							(mid 0.249642 0.249642)
							(end 0.2794 0.1778)
						)
						(arc
							(start 0.2794 -0.1778)
							(mid 0.249642 -0.249642)
							(end 0.1778 -0.2794)
						)
					)
					(width 0)
					(fill yes)
				)
			)
		)
	)
	(footprint ""
		(layer "F.Cu")
		(at 54.61 -248.4374 -90)
		(property "Reference" "R180"
			(at 0 0 270)
			(layer "F.SilkS")
			(hide yes)
			(effects
				(font
					(size 1.27 1.27)
				)
			)
		)
		(property "Value" "1KR2F-3-GP"
			(at 0.064008 -3.993896 270)
			(unlocked yes)
			(layer "F.Fab")
			(hide yes)
			(effects
				(font
					(size 1.016 1.016)
					(thickness 0.1524)
				)
			)
		)
		(property "Device Type" "R402H16"
			(at 0.064008 -5.517896 270)
			(unlocked yes)
			(layer "F.Fab")
			(hide yes)
			(effects
				(font
					(size 1.016 1.016)
					(thickness 0.1524)
				)
			)
		)
		(duplicate_pad_numbers_are_jumpers no)
		(fp_line
			(start -0.508 -0.9398)
			(end -0.508 0.9398)
			(stroke
				(width 0.1524)
				(type default)
			)
			(layer "F.SilkS")
		)
		(fp_line
			(start 0.508 -0.9398)
			(end -0.508 -0.9398)
			(stroke
				(width 0.1524)
				(type default)
			)
			(layer "F.SilkS")
		)
		(fp_rect
			(start -0.508 0.9398)
			(end 0.508 -0.9398)
			(stroke
				(width 0)
				(type default)
			)
			(fill no)
			(layer "F.CrtYd")
		)
		(fp_rect
			(start -0.508 0.9398)
			(end 0.508 -0.9398)
			(stroke
				(width 0)
				(type default)
			)
			(fill no)
			(layer "F.Fab")
		)
		(pad "1" smd custom
			(at 0 -0.4445 270)
			(size 0.1397 0.1397)
			(layers "F.Cu" "F.Mask" "F.Paste")
			(net "P3V3_STBY_B")
			(options
				(clearance outline)
				(anchor circle)
			)
			(primitives
				(gr_poly
					(pts
						(arc
							(start -0.1778 -0.2794)
							(mid -0.249642 -0.249642)
							(end -0.2794 -0.1778)
						)
						(arc
							(start -0.2794 0.1778)
							(mid -0.249642 0.249642)
							(end -0.1778 0.2794)
						)
						(arc
							(start 0.1778 0.2794)
							(mid 0.249642 0.249642)
							(end 0.2794 0.1778)
						)
						(arc
							(start 0.2794 -0.1778)
							(mid 0.249642 -0.249642)
							(end 0.1778 -0.2794)
						)
					)
					(width 0)
					(fill yes)
				)
			)
		)
		(pad "2" smd custom
			(at 0 0.4445 270)
			(size 0.1397 0.1397)
			(layers "F.Cu" "F.Mask" "F.Paste")
			(net "SW_PWR_R_HDD1")
			(options
				(clearance outline)
				(anchor circle)
			)
			(primitives
				(gr_poly
					(pts
						(arc
							(start -0.1778 -0.2794)
							(mid -0.249642 -0.249642)
							(end -0.2794 -0.1778)
						)
						(arc
							(start -0.2794 0.1778)
							(mid -0.249642 0.249642)
							(end -0.1778 0.2794)
						)
						(arc
							(start 0.1778 0.2794)
							(mid 0.249642 0.249642)
							(end 0.2794 0.1778)
						)
						(arc
							(start 0.2794 -0.1778)
							(mid 0.249642 -0.249642)
							(end 0.1778 -0.2794)
						)
					)
					(width 0)
					(fill yes)
				)
			)
		)
	)
	(footprint ""
		(layer "F.Cu")
		(at 302.393096 -327.858882)
		(property "Reference" "R96"
			(at 0 0 0)
			(layer "F.SilkS")
			(hide yes)
			(effects
				(font
					(size 1.27 1.27)
				)
			)
		)
		(property "Value" "100KR2F-L1-GP"
			(at 0.064008 -3.993896 0)
			(unlocked yes)
			(layer "F.Fab")
			(hide yes)
			(effects
				(font
					(size 1.016 1.016)
					(thickness 0.1524)
				)
			)
		)
		(property "Device Type" "R402H16"
			(at 0.064008 -5.517896 0)
			(unlocked yes)
			(layer "F.Fab")
			(hide yes)
			(effects
				(font
					(size 1.016 1.016)
					(thickness 0.1524)
				)
			)
		)
		(duplicate_pad_numbers_are_jumpers no)
		(fp_line
			(start -0.508 -0.9398)
			(end -0.508 0.9398)
			(stroke
				(width 0.1524)
				(type default)
			)
			(layer "F.SilkS")
		)
		(fp_line
			(start 0.508 -0.9398)
			(end -0.508 -0.9398)
			(stroke
				(width 0.1524)
				(type default)
			)
			(layer "F.SilkS")
		)
		(fp_rect
			(start -0.508 0.9398)
			(end 0.508 -0.9398)
			(stroke
				(width 0)
				(type default)
			)
			(fill no)
			(layer "F.CrtYd")
		)
		(fp_rect
			(start -0.508 0.9398)
			(end 0.508 -0.9398)
			(stroke
				(width 0)
				(type default)
			)
			(fill no)
			(layer "F.Fab")
		)
		(pad "1" smd custom
			(at 0 -0.4445)
			(size 0.1397 0.1397)
			(layers "F.Cu" "F.Mask" "F.Paste")
			(net "PWM_SCC_A_ZONE_C")
			(options
				(clearance outline)
				(anchor circle)
			)
			(primitives
				(gr_poly
					(pts
						(arc
							(start -0.1778 -0.2794)
							(mid -0.249642 -0.249642)
							(end -0.2794 -0.1778)
						)
						(arc
							(start -0.2794 0.1778)
							(mid -0.249642 0.249642)
							(end -0.1778 0.2794)
						)
						(arc
							(start 0.1778 0.2794)
							(mid 0.249642 0.249642)
							(end 0.2794 0.1778)
						)
						(arc
							(start 0.2794 -0.1778)
							(mid 0.249642 -0.249642)
							(end 0.1778 -0.2794)
						)
					)
					(width 0)
					(fill yes)
				)
			)
		)
		(pad "2" smd custom
			(at 0 0.4445)
			(size 0.1397 0.1397)
			(layers "F.Cu" "F.Mask" "F.Paste")
			(net "GND")
			(options
				(clearance outline)
				(anchor circle)
			)
			(primitives
				(gr_poly
					(pts
						(arc
							(start -0.1778 -0.2794)
							(mid -0.249642 -0.249642)
							(end -0.2794 -0.1778)
						)
						(arc
							(start -0.2794 0.1778)
							(mid -0.249642 0.249642)
							(end -0.1778 0.2794)
						)
						(arc
							(start 0.1778 0.2794)
							(mid 0.249642 0.249642)
							(end 0.2794 0.1778)
						)
						(arc
							(start 0.2794 -0.1778)
							(mid 0.249642 -0.249642)
							(end 0.1778 -0.2794)
						)
					)
					(width 0)
					(fill yes)
				)
			)
		)
	)
	(footprint ""
		(layer "F.Cu")
		(at 423.958004 -365.379 -90)
		(property "Reference" "R960"
			(at 0 0 270)
			(layer "F.SilkS")
			(hide yes)
			(effects
				(font
					(size 1.27 1.27)
				)
			)
		)
		(property "Value" "27KR3F-GP"
			(at -0.0254 -2.5146 270)
			(unlocked yes)
			(layer "F.Fab")
			(hide yes)
			(effects
				(font
					(size 1.016 1.016)
					(thickness 0.1524)
				)
			)
		)
		(property "Device Type" "R603H22"
			(at -0.0254 -4.0386 270)
			(unlocked yes)
			(layer "F.Fab")
			(hide yes)
			(effects
				(font
					(size 1.016 1.016)
					(thickness 0.1524)
				)
			)
		)
		(duplicate_pad_numbers_are_jumpers no)
		(fp_line
			(start -0.4826 0)
			(end -0.2032 0)
			(stroke
				(width 0.2032)
				(type default)
			)
			(layer "F.SilkS")
		)
		(fp_line
			(start 0.2032 0)
			(end 0.4826 0)
			(stroke
				(width 0.2032)
				(type default)
			)
			(layer "F.SilkS")
		)
		(fp_rect
			(start -0.5842 1.3335)
			(end 0.5842 -1.3335)
			(stroke
				(width 0)
				(type default)
			)
			(fill no)
			(layer "F.CrtYd")
		)
		(fp_rect
			(start -0.5842 1.3335)
			(end 0.5842 -1.3335)
			(stroke
				(width 0)
				(type default)
			)
			(fill no)
			(layer "F.Fab")
		)
		(pad "1" smd custom
			(at 0 -0.762 270)
			(size 0.2159 0.2159)
			(layers "F.Cu" "F.Mask" "F.Paste")
			(net "FAN_3_TACH1")
			(options
				(clearance outline)
				(anchor circle)
			)
			(primitives
				(gr_poly
					(pts
						(arc
							(start -0.3302 -0.4318)
							(mid -0.402042 -0.402042)
							(end -0.4318 -0.3302)
						)
						(arc
							(start -0.4318 0.3302)
							(mid -0.402042 0.402042)
							(end -0.3302 0.4318)
						)
						(arc
							(start 0.3302 0.4318)
							(mid 0.402042 0.402042)
							(end 0.4318 0.3302)
						)
						(arc
							(start 0.4318 -0.3302)
							(mid 0.402042 -0.402042)
							(end 0.3302 -0.4318)
						)
					)
					(width 0)
					(fill yes)
				)
			)
		)
		(pad "2" smd custom
			(at 0 0.762 270)
			(size 0.2159 0.2159)
			(layers "F.Cu" "F.Mask" "F.Paste")
			(net "FANTACH_F3")
			(options
				(clearance outline)
				(anchor circle)
			)
			(primitives
				(gr_poly
					(pts
						(arc
							(start -0.3302 -0.4318)
							(mid -0.402042 -0.402042)
							(end -0.4318 -0.3302)
						)
						(arc
							(start -0.4318 0.3302)
							(mid -0.402042 0.402042)
							(end -0.3302 0.4318)
						)
						(arc
							(start 0.3302 0.4318)
							(mid 0.402042 0.402042)
							(end 0.4318 0.3302)
						)
						(arc
							(start 0.4318 -0.3302)
							(mid 0.402042 -0.402042)
							(end 0.3302 -0.4318)
						)
					)
					(width 0)
					(fill yes)
				)
			)
		)
	)
	(footprint ""
		(layer "F.Cu")
		(at 182.372 -370.459 90)
		(property "Reference" "R988"
			(at 0 0 90)
			(layer "F.SilkS")
			(hide yes)
			(effects
				(font
					(size 1.27 1.27)
				)
			)
		)
		(property "Value" "0R2J-2-GP"
			(at 0.064008 -3.993896 90)
			(unlocked yes)
			(layer "F.Fab")
			(hide yes)
			(effects
				(font
					(size 1.016 1.016)
					(thickness 0.1524)
				)
			)
		)
		(property "Device Type" "R402H16"
			(at 0.064008 -5.517896 90)
			(unlocked yes)
			(layer "F.Fab")
			(hide yes)
			(effects
				(font
					(size 1.016 1.016)
					(thickness 0.1524)
				)
			)
		)
		(duplicate_pad_numbers_are_jumpers no)
		(fp_line
			(start 0.508 -0.9398)
			(end -0.508 -0.9398)
			(stroke
				(width 0.1524)
				(type default)
			)
			(layer "F.SilkS")
		)
		(fp_line
			(start -0.508 -0.9398)
			(end -0.508 0.9398)
			(stroke
				(width 0.1524)
				(type default)
			)
			(layer "F.SilkS")
		)
		(fp_rect
			(start -0.508 0.9398)
			(end 0.508 -0.9398)
			(stroke
				(width 0)
				(type default)
			)
			(fill no)
			(layer "F.CrtYd")
		)
		(fp_rect
			(start -0.508 0.9398)
			(end 0.508 -0.9398)
			(stroke
				(width 0)
				(type default)
			)
			(fill no)
			(layer "F.Fab")
		)
		(pad "1" smd custom
			(at 0 -0.4445 90)
			(size 0.1397 0.1397)
			(layers "F.Cu" "F.Mask" "F.Paste")
			(net "MB0_SDA_R")
			(options
				(clearance outline)
				(anchor circle)
			)
			(primitives
				(gr_poly
					(pts
						(arc
							(start -0.1778 -0.2794)
							(mid -0.249642 -0.249642)
							(end -0.2794 -0.1778)
						)
						(arc
							(start -0.2794 0.1778)
							(mid -0.249642 0.249642)
							(end -0.1778 0.2794)
						)
						(arc
							(start 0.1778 0.2794)
							(mid 0.249642 0.249642)
							(end 0.2794 0.1778)
						)
						(arc
							(start 0.2794 -0.1778)
							(mid 0.249642 -0.249642)
							(end 0.1778 -0.2794)
						)
					)
					(width 0)
					(fill yes)
				)
			)
		)
		(pad "2" smd custom
			(at 0 0.4445 90)
			(size 0.1397 0.1397)
			(layers "F.Cu" "F.Mask" "F.Paste")
			(net "I2C_CLIP_B_SDA")
			(options
				(clearance outline)
				(anchor circle)
			)
			(primitives
				(gr_poly
					(pts
						(arc
							(start -0.1778 -0.2794)
							(mid -0.249642 -0.249642)
							(end -0.2794 -0.1778)
						)
						(arc
							(start -0.2794 0.1778)
							(mid -0.249642 0.249642)
							(end -0.1778 0.2794)
						)
						(arc
							(start 0.1778 0.2794)
							(mid 0.249642 0.249642)
							(end 0.2794 0.1778)
						)
						(arc
							(start 0.2794 -0.1778)
							(mid 0.249642 -0.249642)
							(end 0.1778 -0.2794)
						)
					)
					(width 0)
					(fill yes)
				)
			)
		)
	)
	(footprint ""
		(layer "F.Cu")
		(at 461.01 -138.938 -90)
		(property "Reference" "Q106"
			(at 0 0 270)
			(layer "F.SilkS")
			(hide yes)
			(effects
				(font
					(size 1.27 1.27)
				)
			)
		)
		(property "Value" "AO4406AL-GP"
			(at -3.707384 -1.5367 270)
			(unlocked yes)
			(layer "F.Fab")
			(hide yes)
			(effects
				(font
					(size 1.016 1.016)
					(thickness 0.1524)
				)
			)
		)
		(property "Device Type" "SOIC8H69"
			(at -3.707384 -3.0607 270)
			(unlocked yes)
			(layer "F.Fab")
			(hide yes)
			(effects
				(font
					(size 1.016 1.016)
					(thickness 0.1524)
				)
			)
		)
		(duplicate_pad_numbers_are_jumpers no)
		(fp_line
			(start -2.6289 3.4417)
			(end -2.6289 1.4732)
			(stroke
				(width 0.381)
				(type default)
			)
			(layer "F.SilkS")
		)
		(fp_line
			(start -2.7432 1.4224)
			(end -2.6416 1.4224)
			(stroke
				(width 0.1524)
				(type default)
			)
			(layer "F.SilkS")
		)
		(fp_line
			(start -2.7432 1.4224)
			(end 2.1336 1.4224)
			(stroke
				(width 0.1524)
				(type default)
			)
			(layer "F.SilkS")
		)
		(fp_line
			(start 2.1336 1.4224)
			(end 2.1336 -1.4224)
			(stroke
				(width 0.1524)
				(type default)
			)
			(layer "F.SilkS")
		)
		(fp_line
			(start -2.1844 -0.0508)
			(end -2.7178 0.508)
			(stroke
				(width 0.1524)
				(type default)
			)
			(layer "F.SilkS")
		)
		(fp_line
			(start -2.7178 -0.508)
			(end -2.1844 -0.0508)
			(stroke
				(width 0.1524)
				(type default)
			)
			(layer "F.SilkS")
		)
		(fp_line
			(start -2.7432 -1.4224)
			(end -2.7432 1.4224)
			(stroke
				(width 0.1524)
				(type default)
			)
			(layer "F.SilkS")
		)
		(fp_line
			(start 2.1336 -1.4224)
			(end -2.7432 -1.4224)
			(stroke
				(width 0.1524)
				(type default)
			)
			(layer "F.SilkS")
		)
		(fp_poly
			(pts
				(xy -2.2098 -1.4224) (xy -2.2098 1.4224) (xy 2.2098 1.4224) (xy 2.2098 -1.4224)
			)
			(stroke
				(width 0)
				(type default)
			)
			(fill yes)
			(layer "F.SilkS")
		)
		(fp_rect
			(start -2.450084 2.999994)
			(end 2.450084 -2.999994)
			(stroke
				(width 0)
				(type default)
			)
			(fill no)
			(layer "F.CrtYd")
		)
		(fp_poly
			(pts
				(xy -2.8194 3.6322) (xy -2.8194 -3.6322) (xy 2.8194 -3.6322) (xy 2.8194 1.18364) (xy 2.450084 1.18364)
				(xy 2.450084 -2.999994) (xy -2.450084 -2.999994) (xy -2.450084 2.999994) (xy 2.450084 2.999994)
				(xy 2.450084 1.18618) (xy 2.8194 1.18618) (xy 2.8194 3.6322)
			)
			(stroke
				(width 0)
				(type default)
			)
			(fill no)
			(layer "F.CrtYd")
		)
		(fp_rect
			(start -2.8194 3.6322)
			(end 2.8194 -3.6322)
			(stroke
				(width 0)
				(type default)
			)
			(fill no)
			(layer "F.Fab")
		)
		(pad "1" smd rect
			(at -1.905 2.54 270)
			(size 0.635 1.651)
			(layers "F.Cu" "F.Mask" "F.Paste")
			(net "P5V_HDD22")
		)
		(pad "2" smd rect
			(at -0.635 2.54 270)
			(size 0.635 1.651)
			(layers "F.Cu" "F.Mask" "F.Paste")
			(net "P5V_HDD22")
		)
		(pad "3" smd rect
			(at 0.635 2.54 270)
			(size 0.635 1.651)
			(layers "F.Cu" "F.Mask" "F.Paste")
			(net "P5V_HDD22")
		)
		(pad "4" smd rect
			(at 1.905 2.54 270)
			(size 0.635 1.651)
			(layers "F.Cu" "F.Mask" "F.Paste")
			(net "SW_HDD_P22")
		)
		(pad "5" smd rect
			(at 1.905 -2.54 270)
			(size 0.635 1.651)
			(layers "F.Cu" "F.Mask" "F.Paste")
			(net "P5V_B_4")
		)
		(pad "6" smd rect
			(at 0.635 -2.54 270)
			(size 0.635 1.651)
			(layers "F.Cu" "F.Mask" "F.Paste")
			(net "P5V_B_4")
		)
		(pad "7" smd rect
			(at -0.635 -2.54 270)
			(size 0.635 1.651)
			(layers "F.Cu" "F.Mask" "F.Paste")
			(net "P5V_B_4")
		)
		(pad "8" smd rect
			(at -1.905 -2.54 270)
			(size 0.635 1.651)
			(layers "F.Cu" "F.Mask" "F.Paste")
			(net "P5V_B_4")
		)
	)
	(footprint ""
		(layer "F.Cu")
		(at 478.9932 -157.226)
		(property "Reference" "C334"
			(at 0 0 0)
			(layer "F.SilkS")
			(hide yes)
			(effects
				(font
					(size 1.27 1.27)
				)
			)
		)
		(property "Value" "SC4D7U25V5KX-1-GP"
			(at -0.0762 -6.1214 0)
			(unlocked yes)
			(layer "F.Fab")
			(hide yes)
			(effects
				(font
					(size 1.016 1.016)
					(thickness 0.1524)
				)
			)
		)
		(property "Device Type" "C805H58"
			(at -0.0762 -8.1534 0)
			(unlocked yes)
			(layer "F.Fab")
			(hide yes)
			(effects
				(font
					(size 1.016 1.016)
					(thickness 0.1524)
				)
			)
		)
		(duplicate_pad_numbers_are_jumpers no)
		(fp_line
			(start 0.635 0)
			(end -0.635 0)
			(stroke
				(width 0.508)
				(type default)
			)
			(layer "F.SilkS")
		)
		(fp_rect
			(start -0.9652 1.778)
			(end 0.9652 -1.778)
			(stroke
				(width 0)
				(type default)
			)
			(fill no)
			(layer "F.CrtYd")
		)
		(fp_poly
			(pts
				(xy -0.9652 -1.778) (xy 0.9652 -1.778) (xy 0.9652 1.778) (xy -0.9652 1.778)
			)
			(stroke
				(width 0)
				(type default)
			)
			(fill no)
			(layer "F.Fab")
		)
		(pad "1" smd rect
			(at 0 -0.9652)
			(size 1.397 1.143)
			(layers "F.Cu" "F.Mask" "F.Paste")
			(net "P12V_HDD23")
		)
		(pad "2" smd rect
			(at 0 0.9652)
			(size 1.397 1.143)
			(layers "F.Cu" "F.Mask" "F.Paste")
			(net "GND")
		)
	)
	(footprint ""
		(layer "F.Cu")
		(at 455.93 -160.401 180)
		(property "Reference" "C323"
			(at 0 0 180)
			(layer "F.SilkS")
			(hide yes)
			(effects
				(font
					(size 1.27 1.27)
				)
			)
		)
		(property "Value" "SC1U25V3KX-GP"
			(at 0 -2.8194 180)
			(unlocked yes)
			(layer "F.Fab")
			(hide yes)
			(effects
				(font
					(size 1.016 1.016)
					(thickness 0.1524)
				)
			)
		)
		(property "Device Type" "C603H36"
			(at 0 -4.3434 180)
			(unlocked yes)
			(layer "F.Fab")
			(hide yes)
			(effects
				(font
					(size 1.016 1.016)
					(thickness 0.1524)
				)
			)
		)
		(duplicate_pad_numbers_are_jumpers no)
		(fp_line
			(start 0.508 0)
			(end -0.508 0)
			(stroke
				(width 0.2032)
				(type default)
			)
			(layer "F.SilkS")
		)
		(fp_rect
			(start -0.5842 1.3335)
			(end 0.5842 -1.3335)
			(stroke
				(width 0)
				(type default)
			)
			(fill no)
			(layer "F.CrtYd")
		)
		(fp_rect
			(start -0.5842 1.3335)
			(end 0.5842 -1.3335)
			(stroke
				(width 0)
				(type default)
			)
			(fill no)
			(layer "F.Fab")
		)
		(pad "1" smd custom
			(at 0 -0.762 180)
			(size 0.2159 0.2159)
			(layers "F.Cu" "F.Mask" "F.Paste")
			(net "P12V_HDD22")
			(options
				(clearance outline)
				(anchor circle)
			)
			(primitives
				(gr_poly
					(pts
						(arc
							(start -0.3302 -0.4318)
							(mid -0.402042 -0.402042)
							(end -0.4318 -0.3302)
						)
						(arc
							(start -0.4318 0.3302)
							(mid -0.402042 0.402042)
							(end -0.3302 0.4318)
						)
						(arc
							(start 0.3302 0.4318)
							(mid 0.402042 0.402042)
							(end 0.4318 0.3302)
						)
						(arc
							(start 0.4318 -0.3302)
							(mid 0.402042 -0.402042)
							(end 0.3302 -0.4318)
						)
					)
					(width 0)
					(fill yes)
				)
			)
		)
		(pad "2" smd custom
			(at 0 0.762 180)
			(size 0.2159 0.2159)
			(layers "F.Cu" "F.Mask" "F.Paste")
			(net "GND")
			(options
				(clearance outline)
				(anchor circle)
			)
			(primitives
				(gr_poly
					(pts
						(arc
							(start -0.3302 -0.4318)
							(mid -0.402042 -0.402042)
							(end -0.4318 -0.3302)
						)
						(arc
							(start -0.4318 0.3302)
							(mid -0.402042 0.402042)
							(end -0.3302 0.4318)
						)
						(arc
							(start 0.3302 0.4318)
							(mid 0.402042 0.402042)
							(end 0.4318 0.3302)
						)
						(arc
							(start 0.4318 -0.3302)
							(mid 0.402042 -0.402042)
							(end 0.3302 -0.4318)
						)
					)
					(width 0)
					(fill yes)
				)
			)
		)
	)
	(footprint ""
		(layer "F.Cu")
		(at 28.200096 -258.910074 -90)
		(property "Reference" "HDDSAS0"
			(at 0 0 270)
			(layer "F.SilkS")
			(hide yes)
			(effects
				(font
					(size 1.27 1.27)
				)
			)
		)
		(property "Value" "SKT-SAS15P-14P-45-GP"
			(at -20.7645 -8.9789 270)
			(unlocked yes)
			(layer "F.Fab")
			(hide yes)
			(effects
				(font
					(size 1.016 1.016)
					(thickness 0.1524)
				)
			)
		)
		(property "Device Type" "10120818-001C-TRLF"
			(at -20.7645 -10.5029 270)
			(unlocked yes)
			(layer "F.Fab")
			(hide yes)
			(effects
				(font
					(size 1.016 1.016)
					(thickness 0.1524)
				)
			)
		)
		(duplicate_pad_numbers_are_jumpers no)
		(fp_line
			(start 1.651 4.2926)
			(end 1.651 3.0099)
			(stroke
				(width 0.1524)
				(type default)
			)
			(layer "F.SilkS")
		)
		(fp_line
			(start 8.509 4.2926)
			(end 1.651 4.2926)
			(stroke
				(width 0.1524)
				(type default)
			)
			(layer "F.SilkS")
		)
		(fp_line
			(start -23.4188 3.0099)
			(end -23.4188 -3.2512)
			(stroke
				(width 0.1524)
				(type default)
			)
			(layer "F.SilkS")
		)
		(fp_line
			(start 1.651 3.0099)
			(end -23.4188 3.0099)
			(stroke
				(width 0.1524)
				(type default)
			)
			(layer "F.SilkS")
		)
		(fp_line
			(start 8.509 3.0099)
			(end 8.509 4.2926)
			(stroke
				(width 0.1524)
				(type default)
			)
			(layer "F.SilkS")
		)
		(fp_line
			(start 23.4188 3.0099)
			(end 8.509 3.0099)
			(stroke
				(width 0.1524)
				(type default)
			)
			(layer "F.SilkS")
		)
		(fp_line
			(start -23.4188 -3.2512)
			(end 23.4188 -3.2512)
			(stroke
				(width 0.1524)
				(type default)
			)
			(layer "F.SilkS")
		)
		(fp_line
			(start 23.4188 -3.2512)
			(end 23.4188 3.0099)
			(stroke
				(width 0.1524)
				(type default)
			)
			(layer "F.SilkS")
		)
		(fp_line
			(start 15.5067 -3.3401)
			(end 16.2687 -3.3401)
			(stroke
				(width 0.3302)
				(type default)
			)
			(layer "F.SilkS")
		)
		(fp_poly
			(pts
				(xy 15.868904 -3.230372) (xy 16.503904 -3.865372) (xy 15.233904 -3.865372)
			)
			(stroke
				(width 0)
				(type default)
			)
			(fill yes)
			(layer "F.SilkS")
		)
		(fp_poly
			(pts
				(xy -22.8727 -2.7559) (xy 22.8727 -2.7559) (xy 22.8727 2.7559) (xy 8.255 2.7559) (xy 8.255 3.5179)
				(xy 1.905 3.5179) (xy 1.905 2.7559) (xy -22.8727 2.7559)
			)
			(stroke
				(width 0)
				(type default)
			)
			(fill no)
			(layer "F.CrtYd")
		)
		(fp_poly
			(pts
				(xy 1.397 4.5466) (xy 1.397 3.2639) (xy -23.6728 3.2639) (xy -23.6728 -3.5052) (xy 23.6728 -3.5052)
				(xy 23.6728 -0.00635) (xy 22.8727 -0.00635) (xy 22.8727 -2.7559) (xy -22.8727 -2.7559) (xy -22.8727 2.7559)
				(xy 1.905 2.7559) (xy 1.905 3.5179) (xy 8.255 3.5179) (xy 8.255 2.7559) (xy 22.8727 2.7559) (xy 22.8727 0.00635)
				(xy 23.6728 0.00635) (xy 23.6728 3.2639) (xy 8.763 3.2639) (xy 8.763 4.5466)
			)
			(stroke
				(width 0)
				(type default)
			)
			(fill no)
			(layer "F.CrtYd")
		)
		(fp_poly
			(pts
				(xy 1.397 4.5466) (xy 1.397 3.2639) (xy -23.6728 3.2639) (xy -23.6728 -3.5052) (xy 23.6728 -3.5052)
				(xy 23.6728 3.2639) (xy 8.763 3.2639) (xy 8.763 4.5466)
			)
			(stroke
				(width 0)
				(type default)
			)
			(fill no)
			(layer "F.Fab")
		)
		(pad "" np_thru_hole circle
			(at -18.874994 0 270)
			(size 0.254 0.254)
			(drill 1.3462)
			(layers "*.Cu" "*.Mask")
			(clearance 0.9017)
			(thermal_gap 0.9017)
		)
		(pad "" np_thru_hole circle
			(at 18.874994 0 270)
			(size 0.254 0.254)
			(drill 0.9398)
			(layers "*.Cu" "*.Mask")
			(clearance 0.6985)
			(thermal_gap 0.6985)
		)
		(pad "G1" smd rect
			(at 21.874988 0 270)
			(size 2.5908 2.5908)
			(layers "F.Cu" "F.Mask" "F.Paste")
			(net "GND")
		)
		(pad "G2" smd rect
			(at -21.874988 0 270)
			(size 2.5908 2.5908)
			(layers "F.Cu" "F.Mask" "F.Paste")
			(net "GND")
		)
		(pad "P1" smd rect
			(at 1.905 -1.82499 270)
			(size 0.6096 2.3622)
			(layers "F.Cu" "F.Mask" "F.Paste")
			(net "Net_1764")
		)
		(pad "P2" smd rect
			(at 0.635 -1.82499 270)
			(size 0.6096 2.3622)
			(layers "F.Cu" "F.Mask" "F.Paste")
			(net "Net_1765")
		)
		(pad "P3" smd rect
			(at -0.635 -1.82499 270)
			(size 0.6096 2.3622)
			(layers "F.Cu" "F.Mask" "F.Paste")
			(net "Net_1766")
		)
		(pad "P4" smd rect
			(at -1.905 -1.82499 270)
			(size 0.6096 2.3622)
			(layers "F.Cu" "F.Mask" "F.Paste")
			(net "GND")
		)
		(pad "P5" smd rect
			(at -3.175 -1.82499 270)
			(size 0.6096 2.3622)
			(layers "F.Cu" "F.Mask" "F.Paste")
			(net "HDD_PRSNT_0")
		)
		(pad "P6" smd rect
			(at -4.445 -1.82499 270)
			(size 0.6096 2.3622)
			(layers "F.Cu" "F.Mask" "F.Paste")
			(net "GND")
		)
		(pad "P7" smd rect
			(at -5.715 -1.82499 270)
			(size 0.6096 2.3622)
			(layers "F.Cu" "F.Mask" "F.Paste")
			(net "5V_PRE_0")
		)
		(pad "P8" smd rect
			(at -6.985 -1.82499 270)
			(size 0.6096 2.3622)
			(layers "F.Cu" "F.Mask" "F.Paste")
			(net "P5V_HDD0")
		)
		(pad "P9" smd rect
			(at -8.255 -1.82499 270)
			(size 0.6096 2.3622)
			(layers "F.Cu" "F.Mask" "F.Paste")
			(net "P5V_HDD0")
		)
		(pad "P10" smd rect
			(at -9.525 -1.82499 270)
			(size 0.6096 2.3622)
			(layers "F.Cu" "F.Mask" "F.Paste")
			(net "GND")
		)
		(pad "P11" smd rect
			(at -10.795 -1.82499 270)
			(size 0.6096 2.3622)
			(layers "F.Cu" "F.Mask" "F.Paste")
			(net "ACT_HDD_0")
		)
		(pad "P12" smd rect
			(at -12.065 -1.82499 270)
			(size 0.6096 2.3622)
			(layers "F.Cu" "F.Mask" "F.Paste")
			(net "GND")
		)
		(pad "P13" smd rect
			(at -13.335 -1.82499 270)
			(size 0.6096 2.3622)
			(layers "F.Cu" "F.Mask" "F.Paste")
			(net "12V_PRE_0")
		)
		(pad "P14" smd rect
			(at -14.605 -1.82499 270)
			(size 0.6096 2.3622)
			(layers "F.Cu" "F.Mask" "F.Paste")
			(net "P12V_HDD0")
		)
		(pad "P15" smd rect
			(at -15.875 -1.82499 270)
			(size 0.6096 2.3622)
			(layers "F.Cu" "F.Mask" "F.Paste")
			(net "P12V_HDD0")
		)
		(pad "S1" smd rect
			(at 15.875 -1.82499 270)
			(size 0.6096 2.3622)
			(layers "F.Cu" "F.Mask" "F.Paste")
			(net "GND")
		)
		(pad "S2" smd rect
			(at 14.605 -1.82499 270)
			(size 0.6096 2.3622)
			(layers "F.Cu" "F.Mask" "F.Paste")
			(net "SAS_HDD_RX_P0")
		)
		(pad "S3" smd rect
			(at 13.335 -1.82499 270)
			(size 0.6096 2.3622)
			(layers "F.Cu" "F.Mask" "F.Paste")
			(net "SAS_HDD_RX_N0")
		)
		(pad "S4" smd rect
			(at 12.065 -1.82499 270)
			(size 0.6096 2.3622)
			(layers "F.Cu" "F.Mask" "F.Paste")
			(net "GND")
		)
		(pad "S5" smd rect
			(at 10.795 -1.82499 270)
			(size 0.6096 2.3622)
			(layers "F.Cu" "F.Mask" "F.Paste")
			(net "PHY_DRV_B_TO_SCC_B_0_DN")
		)
		(pad "S6" smd rect
			(at 9.525 -1.82499 270)
			(size 0.6096 2.3622)
			(layers "F.Cu" "F.Mask" "F.Paste")
			(net "PHY_DRV_B_TO_SCC_B_0_DP")
		)
		(pad "S7" smd rect
			(at 8.255 -1.82499 270)
			(size 0.6096 2.3622)
			(layers "F.Cu" "F.Mask" "F.Paste")
			(net "GND")
		)
		(pad "S8" smd rect
			(at 7.480046 2.845054 270)
			(size 0.508 2.3622)
			(layers "F.Cu" "F.Mask" "F.Paste")
			(net "GND")
		)
		(pad "S9" smd rect
			(at 6.679946 2.845054 270)
			(size 0.508 2.3622)
			(layers "F.Cu" "F.Mask" "F.Paste")
			(net "Net_431")
		)
		(pad "S10" smd rect
			(at 5.8801 2.845054 270)
			(size 0.508 2.3622)
			(layers "F.Cu" "F.Mask" "F.Paste")
			(net "Net_323")
		)
		(pad "S11" smd rect
			(at 5.08 2.845054 270)
			(size 0.508 2.3622)
			(layers "F.Cu" "F.Mask" "F.Paste")
			(net "GND")
		)
		(pad "S12" smd rect
			(at 4.2799 2.845054 270)
			(size 0.508 2.3622)
			(layers "F.Cu" "F.Mask" "F.Paste")
			(net "Net_359")
		)
		(pad "S13" smd rect
			(at 3.480054 2.845054 270)
			(size 0.508 2.3622)
			(layers "F.Cu" "F.Mask" "F.Paste")
			(net "Net_395")
		)
		(pad "S14" smd rect
			(at 2.679954 2.845054 270)
			(size 0.508 2.3622)
			(layers "F.Cu" "F.Mask" "F.Paste")
			(net "GND")
		)
		(zone
			(layer "F.Cu")
			(hatch none 0.5)
			(connect_pads
				(clearance 0)
			)
			(min_thickness 0.25)
			(keepout
				(tracks not_allowed)
				(vias allowed)
				(pads allowed)
				(copperpour not_allowed)
				(footprints allowed)
			)
			(placement
				(enabled no)
				(sheetname "")
			)
			(fill
				(thermal_gap 0.5)
				(thermal_bridge_width 0.5)
				(island_removal_mode 0)
			)
			(polygon
				(pts
					(xy 31.857696 -275.648674) (xy 24.783796 -275.648674) (xy 24.783796 -282.582874) (xy 25.888696 -282.582874)
					(xy 25.888696 -278.468074) (xy 30.511496 -278.468074) (xy 30.511496 -282.582874) (xy 31.857696 -282.582874)
				)
			)
		)
		(zone
			(layer "F.Cu")
			(hatch none 0.5)
			(connect_pads
				(clearance 0)
			)
			(min_thickness 0.25)
			(keepout
				(tracks allowed)
				(vias not_allowed)
				(pads allowed)
				(copperpour not_allowed)
				(footprints allowed)
			)
			(placement
				(enabled no)
				(sheetname "")
			)
			(fill
				(thermal_gap 0.5)
				(thermal_bridge_width 0.5)
				(island_removal_mode 0)
			)
			(polygon
				(pts
					(xy 31.857696 -275.648674) (xy 24.783796 -275.648674) (xy 24.783796 -282.582874) (xy 25.888696 -282.582874)
					(xy 25.888696 -278.468074) (xy 30.511496 -278.468074) (xy 30.511496 -282.582874) (xy 31.857696 -282.582874)
				)
			)
		)
		(zone
			(layer "F.Cu")
			(hatch none 0.5)
			(connect_pads
				(clearance 0)
			)
			(min_thickness 0.25)
			(keepout
				(tracks allowed)
				(vias not_allowed)
				(pads allowed)
				(copperpour not_allowed)
				(footprints allowed)
			)
			(placement
				(enabled no)
				(sheetname "")
			)
			(fill
				(thermal_gap 0.5)
				(thermal_bridge_width 0.5)
				(island_removal_mode 0)
			)
			(polygon
				(pts
					(xy 31.857696 -242.171474) (xy 24.783796 -242.171474) (xy 24.783796 -235.237274) (xy 25.888696 -235.237274)
					(xy 25.888696 -239.352074) (xy 30.511496 -239.352074) (xy 30.511496 -235.237274) (xy 31.857696 -235.237274)
				)
			)
		)
		(zone
			(layer "F.Cu")
			(hatch none 0.5)
			(connect_pads
				(clearance 0)
			)
			(min_thickness 0.25)
			(keepout
				(tracks not_allowed)
				(vias allowed)
				(pads allowed)
				(copperpour not_allowed)
				(footprints allowed)
			)
			(placement
				(enabled no)
				(sheetname "")
			)
			(fill
				(thermal_gap 0.5)
				(thermal_bridge_width 0.5)
				(island_removal_mode 0)
			)
			(polygon
				(pts
					(xy 31.857696 -242.171474) (xy 24.783796 -242.171474) (xy 24.783796 -235.237274) (xy 25.888696 -235.237274)
					(xy 25.888696 -239.352074) (xy 30.511496 -239.352074) (xy 30.511496 -235.237274) (xy 31.857696 -235.237274)
				)
			)
		)
		(zone
			(layers "F.Cu" "B.Cu" "In1.Cu" "In2.Cu" "In3.Cu" "In4.Cu" "In5.Cu" "In6.Cu")
			(hatch none 0.5)
			(connect_pads
				(clearance 0)
			)
			(min_thickness 0.25)
			(keepout
				(tracks not_allowed)
				(vias allowed)
				(pads allowed)
				(copperpour not_allowed)
				(footprints allowed)
			)
			(placement
				(enabled no)
				(sheetname "")
			)
			(fill
				(thermal_gap 0.5)
				(thermal_bridge_width 0.5)
				(island_removal_mode 0)
			)
			(polygon
				(pts
					(arc
						(start 28.974796 -240.03508)
						(mid 27.425396 -240.03508)
						(end 28.974796 -240.03508)
					)
				)
			)
		)
		(zone
			(layers "F.Cu" "B.Cu" "In1.Cu" "In2.Cu" "In3.Cu" "In4.Cu" "In5.Cu" "In6.Cu")
			(hatch none 0.5)
			(connect_pads
				(clearance 0)
			)
			(min_thickness 0.25)
			(keepout
				(tracks not_allowed)
				(vias allowed)
				(pads allowed)
				(copperpour not_allowed)
				(footprints allowed)
			)
			(placement
				(enabled no)
				(sheetname "")
			)
			(fill
				(thermal_gap 0.5)
				(thermal_bridge_width 0.5)
				(island_removal_mode 0)
			)
			(polygon
				(pts
					(arc
						(start 29.177996 -277.785068)
						(mid 27.222196 -277.785068)
						(end 29.177996 -277.785068)
					)
				)
			)
		)
	)
	(footprint ""
		(layer "F.Cu")
		(at 146.939 -256.286 180)
		(property "Reference" "Q14"
			(at 0 0 180)
			(layer "F.SilkS")
			(hide yes)
			(effects
				(font
					(size 1.27 1.27)
				)
			)
		)
		(property "Value" "AO4406AL-GP"
			(at -3.707384 -1.5367 180)
			(unlocked yes)
			(layer "F.Fab")
			(hide yes)
			(effects
				(font
					(size 1.016 1.016)
					(thickness 0.1524)
				)
			)
		)
		(property "Device Type" "SOIC8H69"
			(at -3.707384 -3.0607 180)
			(unlocked yes)
			(layer "F.Fab")
			(hide yes)
			(effects
				(font
					(size 1.016 1.016)
					(thickness 0.1524)
				)
			)
		)
		(duplicate_pad_numbers_are_jumpers no)
		(fp_line
			(start 2.1336 1.4224)
			(end 2.1336 -1.4224)
			(stroke
				(width 0.1524)
				(type default)
			)
			(layer "F.SilkS")
		)
		(fp_line
			(start 2.1336 -1.4224)
			(end -2.7432 -1.4224)
			(stroke
				(width 0.1524)
				(type default)
			)
			(layer "F.SilkS")
		)
		(fp_line
			(start -2.1844 -0.0508)
			(end -2.7178 0.508)
			(stroke
				(width 0.1524)
				(type default)
			)
			(layer "F.SilkS")
		)
		(fp_line
			(start -2.6289 3.4417)
			(end -2.6289 1.4732)
			(stroke
				(width 0.381)
				(type default)
			)
			(layer "F.SilkS")
		)
		(fp_line
			(start -2.7178 -0.508)
			(end -2.1844 -0.0508)
			(stroke
				(width 0.1524)
				(type default)
			)
			(layer "F.SilkS")
		)
		(fp_line
			(start -2.7432 1.4224)
			(end 2.1336 1.4224)
			(stroke
				(width 0.1524)
				(type default)
			)
			(layer "F.SilkS")
		)
		(fp_line
			(start -2.7432 1.4224)
			(end -2.6416 1.4224)
			(stroke
				(width 0.1524)
				(type default)
			)
			(layer "F.SilkS")
		)
		(fp_line
			(start -2.7432 -1.4224)
			(end -2.7432 1.4224)
			(stroke
				(width 0.1524)
				(type default)
			)
			(layer "F.SilkS")
		)
		(fp_poly
			(pts
				(xy -2.2098 -1.4224) (xy -2.2098 1.4224) (xy 2.2098 1.4224) (xy 2.2098 -1.4224)
			)
			(stroke
				(width 0)
				(type default)
			)
			(fill yes)
			(layer "F.SilkS")
		)
		(fp_rect
			(start -2.450084 2.999994)
			(end 2.450084 -2.999994)
			(stroke
				(width 0)
				(type default)
			)
			(fill no)
			(layer "F.CrtYd")
		)
		(fp_poly
			(pts
				(xy -2.8194 3.6322) (xy -2.8194 -3.6322) (xy 2.8194 -3.6322) (xy 2.8194 1.18364) (xy 2.450084 1.18364)
				(xy 2.450084 -2.999994) (xy -2.450084 -2.999994) (xy -2.450084 2.999994) (xy 2.450084 2.999994)
				(xy 2.450084 1.18618) (xy 2.8194 1.18618) (xy 2.8194 3.6322)
			)
			(stroke
				(width 0)
				(type default)
			)
			(fill no)
			(layer "F.CrtYd")
		)
		(fp_rect
			(start -2.8194 3.6322)
			(end 2.8194 -3.6322)
			(stroke
				(width 0)
				(type default)
			)
			(fill no)
			(layer "F.Fab")
		)
		(pad "1" smd rect
			(at -1.905 2.54 180)
			(size 0.635 1.651)
			(layers "F.Cu" "F.Mask" "F.Paste")
			(net "P5V_HDD4")
		)
		(pad "2" smd rect
			(at -0.635 2.54 180)
			(size 0.635 1.651)
			(layers "F.Cu" "F.Mask" "F.Paste")
			(net "P5V_HDD4")
		)
		(pad "3" smd rect
			(at 0.635 2.54 180)
			(size 0.635 1.651)
			(layers "F.Cu" "F.Mask" "F.Paste")
			(net "P5V_HDD4")
		)
		(pad "4" smd rect
			(at 1.905 2.54 180)
			(size 0.635 1.651)
			(layers "F.Cu" "F.Mask" "F.Paste")
			(net "SW_HDD_P4")
		)
		(pad "5" smd rect
			(at 1.905 -2.54 180)
			(size 0.635 1.651)
			(layers "F.Cu" "F.Mask" "F.Paste")
			(net "P5V_B_1")
		)
		(pad "6" smd rect
			(at 0.635 -2.54 180)
			(size 0.635 1.651)
			(layers "F.Cu" "F.Mask" "F.Paste")
			(net "P5V_B_1")
		)
		(pad "7" smd rect
			(at -0.635 -2.54 180)
			(size 0.635 1.651)
			(layers "F.Cu" "F.Mask" "F.Paste")
			(net "P5V_B_1")
		)
		(pad "8" smd rect
			(at -1.905 -2.54 180)
			(size 0.635 1.651)
			(layers "F.Cu" "F.Mask" "F.Paste")
			(net "P5V_B_1")
		)
	)
	(footprint ""
		(layer "F.Cu")
		(at 320.34353 -97.350326 -90)
		(property "Reference" "R467"
			(at 0 0 270)
			(layer "F.SilkS")
			(hide yes)
			(effects
				(font
					(size 1.27 1.27)
				)
			)
		)
		(property "Value" "4K7R2F-GP"
			(at 0.064008 -3.993896 270)
			(unlocked yes)
			(layer "F.Fab")
			(hide yes)
			(effects
				(font
					(size 1.016 1.016)
					(thickness 0.1524)
				)
			)
		)
		(property "Device Type" "R402H16"
			(at 0.064008 -5.517896 270)
			(unlocked yes)
			(layer "F.Fab")
			(hide yes)
			(effects
				(font
					(size 1.016 1.016)
					(thickness 0.1524)
				)
			)
		)
		(duplicate_pad_numbers_are_jumpers no)
		(fp_line
			(start -0.508 -0.9398)
			(end -0.508 0.9398)
			(stroke
				(width 0.1524)
				(type default)
			)
			(layer "F.SilkS")
		)
		(fp_line
			(start 0.508 -0.9398)
			(end -0.508 -0.9398)
			(stroke
				(width 0.1524)
				(type default)
			)
			(layer "F.SilkS")
		)
		(fp_rect
			(start -0.508 0.9398)
			(end 0.508 -0.9398)
			(stroke
				(width 0)
				(type default)
			)
			(fill no)
			(layer "F.CrtYd")
		)
		(fp_rect
			(start -0.508 0.9398)
			(end 0.508 -0.9398)
			(stroke
				(width 0)
				(type default)
			)
			(fill no)
			(layer "F.Fab")
		)
		(pad "1" smd custom
			(at 0 -0.4445 270)
			(size 0.1397 0.1397)
			(layers "F.Cu" "F.Mask" "F.Paste")
			(net "DRIVE_B_18_ACT")
			(options
				(clearance outline)
				(anchor circle)
			)
			(primitives
				(gr_poly
					(pts
						(arc
							(start -0.1778 -0.2794)
							(mid -0.249642 -0.249642)
							(end -0.2794 -0.1778)
						)
						(arc
							(start -0.2794 0.1778)
							(mid -0.249642 0.249642)
							(end -0.1778 0.2794)
						)
						(arc
							(start 0.1778 0.2794)
							(mid 0.249642 0.249642)
							(end 0.2794 0.1778)
						)
						(arc
							(start 0.2794 -0.1778)
							(mid 0.249642 -0.249642)
							(end 0.1778 -0.2794)
						)
					)
					(width 0)
					(fill yes)
				)
			)
		)
		(pad "2" smd custom
			(at 0 0.4445 270)
			(size 0.1397 0.1397)
			(layers "F.Cu" "F.Mask" "F.Paste")
			(net "GND")
			(options
				(clearance outline)
				(anchor circle)
			)
			(primitives
				(gr_poly
					(pts
						(arc
							(start -0.1778 -0.2794)
							(mid -0.249642 -0.249642)
							(end -0.2794 -0.1778)
						)
						(arc
							(start -0.2794 0.1778)
							(mid -0.249642 0.249642)
							(end -0.1778 0.2794)
						)
						(arc
							(start 0.1778 0.2794)
							(mid 0.249642 0.249642)
							(end 0.2794 0.1778)
						)
						(arc
							(start 0.2794 -0.1778)
							(mid 0.249642 -0.249642)
							(end 0.1778 -0.2794)
						)
					)
					(width 0)
					(fill yes)
				)
			)
		)
	)
	(footprint ""
		(layer "F.Cu")
		(at 461.899 -131.826 180)
		(property "Reference" "R593"
			(at 0 0 180)
			(layer "F.SilkS")
			(hide yes)
			(effects
				(font
					(size 1.27 1.27)
				)
			)
		)
		(property "Value" "0R2J-2-GP"
			(at 0.064008 -3.993896 180)
			(unlocked yes)
			(layer "F.Fab")
			(hide yes)
			(effects
				(font
					(size 1.016 1.016)
					(thickness 0.1524)
				)
			)
		)
		(property "Device Type" "R402H16"
			(at 0.064008 -5.517896 180)
			(unlocked yes)
			(layer "F.Fab")
			(hide yes)
			(effects
				(font
					(size 1.016 1.016)
					(thickness 0.1524)
				)
			)
		)
		(duplicate_pad_numbers_are_jumpers no)
		(fp_line
			(start 0.508 -0.9398)
			(end -0.508 -0.9398)
			(stroke
				(width 0.1524)
				(type default)
			)
			(layer "F.SilkS")
		)
		(fp_line
			(start -0.508 -0.9398)
			(end -0.508 0.9398)
			(stroke
				(width 0.1524)
				(type default)
			)
			(layer "F.SilkS")
		)
		(fp_rect
			(start -0.508 0.9398)
			(end 0.508 -0.9398)
			(stroke
				(width 0)
				(type default)
			)
			(fill no)
			(layer "F.CrtYd")
		)
		(fp_rect
			(start -0.508 0.9398)
			(end 0.508 -0.9398)
			(stroke
				(width 0)
				(type default)
			)
			(fill no)
			(layer "F.Fab")
		)
		(pad "1" smd custom
			(at 0 -0.4445 180)
			(size 0.1397 0.1397)
			(layers "F.Cu" "F.Mask" "F.Paste")
			(net "SW_HDD_G22")
			(options
				(clearance outline)
				(anchor circle)
			)
			(primitives
				(gr_poly
					(pts
						(arc
							(start -0.1778 -0.2794)
							(mid -0.249642 -0.249642)
							(end -0.2794 -0.1778)
						)
						(arc
							(start -0.2794 0.1778)
							(mid -0.249642 0.249642)
							(end -0.1778 0.2794)
						)
						(arc
							(start 0.1778 0.2794)
							(mid 0.249642 0.249642)
							(end 0.2794 0.1778)
						)
						(arc
							(start 0.2794 -0.1778)
							(mid 0.249642 -0.249642)
							(end 0.1778 -0.2794)
						)
					)
					(width 0)
					(fill yes)
				)
			)
		)
		(pad "2" smd custom
			(at 0 0.4445 180)
			(size 0.1397 0.1397)
			(layers "F.Cu" "F.Mask" "F.Paste")
			(net "SW_HDD_R22")
			(options
				(clearance outline)
				(anchor circle)
			)
			(primitives
				(gr_poly
					(pts
						(arc
							(start -0.1778 -0.2794)
							(mid -0.249642 -0.249642)
							(end -0.2794 -0.1778)
						)
						(arc
							(start -0.2794 0.1778)
							(mid -0.249642 0.249642)
							(end -0.1778 0.2794)
						)
						(arc
							(start 0.1778 0.2794)
							(mid 0.249642 0.249642)
							(end 0.2794 0.1778)
						)
						(arc
							(start 0.2794 -0.1778)
							(mid 0.249642 -0.249642)
							(end 0.1778 -0.2794)
						)
					)
					(width 0)
					(fill yes)
				)
			)
		)
	)
	(footprint ""
		(layer "F.Cu")
		(at 127.9906 -31.623 180)
		(property "Reference" "R691"
			(at 0 0 180)
			(layer "F.SilkS")
			(hide yes)
			(effects
				(font
					(size 1.27 1.27)
				)
			)
		)
		(property "Value" "10KR2F-2-GP"
			(at 0.064008 -3.993896 180)
			(unlocked yes)
			(layer "F.Fab")
			(hide yes)
			(effects
				(font
					(size 1.016 1.016)
					(thickness 0.1524)
				)
			)
		)
		(property "Device Type" "R402H16"
			(at 0.064008 -5.517896 180)
			(unlocked yes)
			(layer "F.Fab")
			(hide yes)
			(effects
				(font
					(size 1.016 1.016)
					(thickness 0.1524)
				)
			)
		)
		(duplicate_pad_numbers_are_jumpers no)
		(fp_line
			(start 0.508 -0.9398)
			(end -0.508 -0.9398)
			(stroke
				(width 0.1524)
				(type default)
			)
			(layer "F.SilkS")
		)
		(fp_line
			(start -0.508 -0.9398)
			(end -0.508 0.9398)
			(stroke
				(width 0.1524)
				(type default)
			)
			(layer "F.SilkS")
		)
		(fp_rect
			(start -0.508 0.9398)
			(end 0.508 -0.9398)
			(stroke
				(width 0)
				(type default)
			)
			(fill no)
			(layer "F.CrtYd")
		)
		(fp_rect
			(start -0.508 0.9398)
			(end 0.508 -0.9398)
			(stroke
				(width 0)
				(type default)
			)
			(fill no)
			(layer "F.Fab")
		)
		(pad "1" smd custom
			(at 0 -0.4445 180)
			(size 0.1397 0.1397)
			(layers "F.Cu" "F.Mask" "F.Paste")
			(net "P3V3_STBY_B")
			(options
				(clearance outline)
				(anchor circle)
			)
			(primitives
				(gr_poly
					(pts
						(arc
							(start -0.1778 -0.2794)
							(mid -0.249642 -0.249642)
							(end -0.2794 -0.1778)
						)
						(arc
							(start -0.2794 0.1778)
							(mid -0.249642 0.249642)
							(end -0.1778 0.2794)
						)
						(arc
							(start 0.1778 0.2794)
							(mid 0.249642 0.249642)
							(end 0.2794 0.1778)
						)
						(arc
							(start 0.2794 -0.1778)
							(mid 0.249642 -0.249642)
							(end 0.1778 -0.2794)
						)
					)
					(width 0)
					(fill yes)
				)
			)
		)
		(pad "2" smd custom
			(at 0 0.4445 180)
			(size 0.1397 0.1397)
			(layers "F.Cu" "F.Mask" "F.Paste")
			(net "HDD_PRSNT_27")
			(options
				(clearance outline)
				(anchor circle)
			)
			(primitives
				(gr_poly
					(pts
						(arc
							(start -0.1778 -0.2794)
							(mid -0.249642 -0.249642)
							(end -0.2794 -0.1778)
						)
						(arc
							(start -0.2794 0.1778)
							(mid -0.249642 0.249642)
							(end -0.1778 0.2794)
						)
						(arc
							(start 0.1778 0.2794)
							(mid 0.249642 0.249642)
							(end 0.2794 0.1778)
						)
						(arc
							(start 0.2794 -0.1778)
							(mid 0.249642 -0.249642)
							(end 0.1778 -0.2794)
						)
					)
					(width 0)
					(fill yes)
				)
			)
		)
	)
	(footprint ""
		(layer "F.Cu")
		(at 51.562 -32.004 -90)
		(property "Reference" "C356"
			(at 0 0 270)
			(layer "F.SilkS")
			(hide yes)
			(effects
				(font
					(size 1.27 1.27)
				)
			)
		)
		(property "Value" "SC10U16V6KX-2GP"
			(at -0.0762 -5.1308 270)
			(unlocked yes)
			(layer "F.Fab")
			(hide yes)
			(effects
				(font
					(size 1.016 1.016)
					(thickness 0.1524)
				)
			)
		)
		(property "Device Type" "C1206H71"
			(at -0.127 -6.6548 270)
			(unlocked yes)
			(layer "F.Fab")
			(hide yes)
			(effects
				(font
					(size 1.016 1.016)
					(thickness 0.1524)
				)
			)
		)
		(duplicate_pad_numbers_are_jumpers no)
		(fp_line
			(start -1.016 2.2352)
			(end -1.016 0.8382)
			(stroke
				(width 0.1524)
				(type default)
			)
			(layer "F.SilkS")
		)
		(fp_line
			(start 1.016 2.2352)
			(end -1.016 2.2352)
			(stroke
				(width 0.1524)
				(type default)
			)
			(layer "F.SilkS")
		)
		(fp_line
			(start 1.016 0.8382)
			(end 1.016 2.2352)
			(stroke
				(width 0.1524)
				(type default)
			)
			(layer "F.SilkS")
		)
		(fp_line
			(start -1.016 -0.8382)
			(end -1.016 -2.2352)
			(stroke
				(width 0.1524)
				(type default)
			)
			(layer "F.SilkS")
		)
		(fp_line
			(start -1.016 -2.2352)
			(end 1.016 -2.2352)
			(stroke
				(width 0.1524)
				(type default)
			)
			(layer "F.SilkS")
		)
		(fp_line
			(start 1.016 -2.2352)
			(end 1.016 -0.8382)
			(stroke
				(width 0.1524)
				(type default)
			)
			(layer "F.SilkS")
		)
		(fp_rect
			(start -1.0922 2.3114)
			(end 1.0922 -2.3114)
			(stroke
				(width 0)
				(type default)
			)
			(fill no)
			(layer "F.CrtYd")
		)
		(fp_poly
			(pts
				(xy 1.0922 -2.3114) (xy 1.0922 2.3114) (xy -1.0922 2.3114) (xy -1.0922 -2.3114)
			)
			(stroke
				(width 0)
				(type default)
			)
			(fill no)
			(layer "F.Fab")
		)
		(pad "1" smd rect
			(at 0 -1.397 270)
			(size 1.651 1.27)
			(layers "F.Cu" "F.Mask" "F.Paste")
			(net "P5V_HDD25")
		)
		(pad "2" smd rect
			(at 0 1.397 270)
			(size 1.651 1.27)
			(layers "F.Cu" "F.Mask" "F.Paste")
			(net "GND")
		)
	)
	(footprint ""
		(layer "F.Cu")
		(at 366.395 -253.873 -90)
		(property "Reference" "Q26"
			(at 0 0 270)
			(layer "F.SilkS")
			(hide yes)
			(effects
				(font
					(size 1.27 1.27)
				)
			)
		)
		(property "Value" "AO4406AL-GP"
			(at -3.707384 -1.5367 270)
			(unlocked yes)
			(layer "F.Fab")
			(hide yes)
			(effects
				(font
					(size 1.016 1.016)
					(thickness 0.1524)
				)
			)
		)
		(property "Device Type" "SOIC8H69"
			(at -3.707384 -3.0607 270)
			(unlocked yes)
			(layer "F.Fab")
			(hide yes)
			(effects
				(font
					(size 1.016 1.016)
					(thickness 0.1524)
				)
			)
		)
		(duplicate_pad_numbers_are_jumpers no)
		(fp_line
			(start -2.6289 3.4417)
			(end -2.6289 1.4732)
			(stroke
				(width 0.381)
				(type default)
			)
			(layer "F.SilkS")
		)
		(fp_line
			(start -2.7432 1.4224)
			(end -2.6416 1.4224)
			(stroke
				(width 0.1524)
				(type default)
			)
			(layer "F.SilkS")
		)
		(fp_line
			(start -2.7432 1.4224)
			(end 2.1336 1.4224)
			(stroke
				(width 0.1524)
				(type default)
			)
			(layer "F.SilkS")
		)
		(fp_line
			(start 2.1336 1.4224)
			(end 2.1336 -1.4224)
			(stroke
				(width 0.1524)
				(type default)
			)
			(layer "F.SilkS")
		)
		(fp_line
			(start -2.1844 -0.0508)
			(end -2.7178 0.508)
			(stroke
				(width 0.1524)
				(type default)
			)
			(layer "F.SilkS")
		)
		(fp_line
			(start -2.7178 -0.508)
			(end -2.1844 -0.0508)
			(stroke
				(width 0.1524)
				(type default)
			)
			(layer "F.SilkS")
		)
		(fp_line
			(start -2.7432 -1.4224)
			(end -2.7432 1.4224)
			(stroke
				(width 0.1524)
				(type default)
			)
			(layer "F.SilkS")
		)
		(fp_line
			(start 2.1336 -1.4224)
			(end -2.7432 -1.4224)
			(stroke
				(width 0.1524)
				(type default)
			)
			(layer "F.SilkS")
		)
		(fp_poly
			(pts
				(xy -2.2098 -1.4224) (xy -2.2098 1.4224) (xy 2.2098 1.4224) (xy 2.2098 -1.4224)
			)
			(stroke
				(width 0)
				(type default)
			)
			(fill yes)
			(layer "F.SilkS")
		)
		(fp_rect
			(start -2.450084 2.999994)
			(end 2.450084 -2.999994)
			(stroke
				(width 0)
				(type default)
			)
			(fill no)
			(layer "F.CrtYd")
		)
		(fp_poly
			(pts
				(xy -2.8194 3.6322) (xy -2.8194 -3.6322) (xy 2.8194 -3.6322) (xy 2.8194 1.18364) (xy 2.450084 1.18364)
				(xy 2.450084 -2.999994) (xy -2.450084 -2.999994) (xy -2.450084 2.999994) (xy 2.450084 2.999994)
				(xy 2.450084 1.18618) (xy 2.8194 1.18618) (xy 2.8194 3.6322)
			)
			(stroke
				(width 0)
				(type default)
			)
			(fill no)
			(layer "F.CrtYd")
		)
		(fp_rect
			(start -2.8194 3.6322)
			(end 2.8194 -3.6322)
			(stroke
				(width 0)
				(type default)
			)
			(fill no)
			(layer "F.Fab")
		)
		(pad "1" smd rect
			(at -1.905 2.54 270)
			(size 0.635 1.651)
			(layers "F.Cu" "F.Mask" "F.Paste")
			(net "P5V_HDD7")
		)
		(pad "2" smd rect
			(at -0.635 2.54 270)
			(size 0.635 1.651)
			(layers "F.Cu" "F.Mask" "F.Paste")
			(net "P5V_HDD7")
		)
		(pad "3" smd rect
			(at 0.635 2.54 270)
			(size 0.635 1.651)
			(layers "F.Cu" "F.Mask" "F.Paste")
			(net "P5V_HDD7")
		)
		(pad "4" smd rect
			(at 1.905 2.54 270)
			(size 0.635 1.651)
			(layers "F.Cu" "F.Mask" "F.Paste")
			(net "SW_HDD_P7")
		)
		(pad "5" smd rect
			(at 1.905 -2.54 270)
			(size 0.635 1.651)
			(layers "F.Cu" "F.Mask" "F.Paste")
			(net "P5V_B_3")
		)
		(pad "6" smd rect
			(at 0.635 -2.54 270)
			(size 0.635 1.651)
			(layers "F.Cu" "F.Mask" "F.Paste")
			(net "P5V_B_3")
		)
		(pad "7" smd rect
			(at -0.635 -2.54 270)
			(size 0.635 1.651)
			(layers "F.Cu" "F.Mask" "F.Paste")
			(net "P5V_B_3")
		)
		(pad "8" smd rect
			(at -1.905 -2.54 270)
			(size 0.635 1.651)
			(layers "F.Cu" "F.Mask" "F.Paste")
			(net "P5V_B_3")
		)
	)
	(footprint ""
		(layer "F.Cu")
		(at 424.434 -275.336 180)
		(property "Reference" "C153"
			(at 0 0 180)
			(layer "F.SilkS")
			(hide yes)
			(effects
				(font
					(size 1.27 1.27)
				)
			)
		)
		(property "Value" "SC1U25V3KX-GP"
			(at 0 -2.8194 180)
			(unlocked yes)
			(layer "F.Fab")
			(hide yes)
			(effects
				(font
					(size 1.016 1.016)
					(thickness 0.1524)
				)
			)
		)
		(property "Device Type" "C603H36"
			(at 0 -4.3434 180)
			(unlocked yes)
			(layer "F.Fab")
			(hide yes)
			(effects
				(font
					(size 1.016 1.016)
					(thickness 0.1524)
				)
			)
		)
		(duplicate_pad_numbers_are_jumpers no)
		(fp_line
			(start 0.508 0)
			(end -0.508 0)
			(stroke
				(width 0.2032)
				(type default)
			)
			(layer "F.SilkS")
		)
		(fp_rect
			(start -0.5842 1.3335)
			(end 0.5842 -1.3335)
			(stroke
				(width 0)
				(type default)
			)
			(fill no)
			(layer "F.CrtYd")
		)
		(fp_rect
			(start -0.5842 1.3335)
			(end 0.5842 -1.3335)
			(stroke
				(width 0)
				(type default)
			)
			(fill no)
			(layer "F.Fab")
		)
		(pad "1" smd custom
			(at 0 -0.762 180)
			(size 0.2159 0.2159)
			(layers "F.Cu" "F.Mask" "F.Paste")
			(net "P12V_HDD9")
			(options
				(clearance outline)
				(anchor circle)
			)
			(primitives
				(gr_poly
					(pts
						(arc
							(start -0.3302 -0.4318)
							(mid -0.402042 -0.402042)
							(end -0.4318 -0.3302)
						)
						(arc
							(start -0.4318 0.3302)
							(mid -0.402042 0.402042)
							(end -0.3302 0.4318)
						)
						(arc
							(start 0.3302 0.4318)
							(mid 0.402042 0.402042)
							(end 0.4318 0.3302)
						)
						(arc
							(start 0.4318 -0.3302)
							(mid 0.402042 -0.402042)
							(end 0.3302 -0.4318)
						)
					)
					(width 0)
					(fill yes)
				)
			)
		)
		(pad "2" smd custom
			(at 0 0.762 180)
			(size 0.2159 0.2159)
			(layers "F.Cu" "F.Mask" "F.Paste")
			(net "GND")
			(options
				(clearance outline)
				(anchor circle)
			)
			(primitives
				(gr_poly
					(pts
						(arc
							(start -0.3302 -0.4318)
							(mid -0.402042 -0.402042)
							(end -0.4318 -0.3302)
						)
						(arc
							(start -0.4318 0.3302)
							(mid -0.402042 0.402042)
							(end -0.3302 0.4318)
						)
						(arc
							(start 0.3302 0.4318)
							(mid 0.402042 0.402042)
							(end 0.4318 0.3302)
						)
						(arc
							(start 0.4318 -0.3302)
							(mid 0.402042 -0.402042)
							(end 0.3302 -0.4318)
						)
					)
					(width 0)
					(fill yes)
				)
			)
		)
	)
	(footprint ""
		(layer "F.Cu")
		(at 141.097 -16.637 90)
		(property "Reference" "R728"
			(at 0 0 90)
			(layer "F.SilkS")
			(hide yes)
			(effects
				(font
					(size 1.27 1.27)
				)
			)
		)
		(property "Value" "4K7R2J-2-GP"
			(at 0.064008 -3.993896 90)
			(unlocked yes)
			(layer "F.Fab")
			(hide yes)
			(effects
				(font
					(size 1.016 1.016)
					(thickness 0.1524)
				)
			)
		)
		(property "Device Type" "R402H16"
			(at 0.064008 -5.517896 90)
			(unlocked yes)
			(layer "F.Fab")
			(hide yes)
			(effects
				(font
					(size 1.016 1.016)
					(thickness 0.1524)
				)
			)
		)
		(duplicate_pad_numbers_are_jumpers no)
		(fp_line
			(start 0.508 -0.9398)
			(end -0.508 -0.9398)
			(stroke
				(width 0.1524)
				(type default)
			)
			(layer "F.SilkS")
		)
		(fp_line
			(start -0.508 -0.9398)
			(end -0.508 0.9398)
			(stroke
				(width 0.1524)
				(type default)
			)
			(layer "F.SilkS")
		)
		(fp_rect
			(start -0.508 0.9398)
			(end 0.508 -0.9398)
			(stroke
				(width 0)
				(type default)
			)
			(fill no)
			(layer "F.CrtYd")
		)
		(fp_rect
			(start -0.508 0.9398)
			(end 0.508 -0.9398)
			(stroke
				(width 0)
				(type default)
			)
			(fill no)
			(layer "F.Fab")
		)
		(pad "1" smd custom
			(at 0 -0.4445 90)
			(size 0.1397 0.1397)
			(layers "F.Cu" "F.Mask" "F.Paste")
			(net "P12V_B")
			(options
				(clearance outline)
				(anchor circle)
			)
			(primitives
				(gr_poly
					(pts
						(arc
							(start -0.1778 -0.2794)
							(mid -0.249642 -0.249642)
							(end -0.2794 -0.1778)
						)
						(arc
							(start -0.2794 0.1778)
							(mid -0.249642 0.249642)
							(end -0.1778 0.2794)
						)
						(arc
							(start 0.1778 0.2794)
							(mid 0.249642 0.249642)
							(end 0.2794 0.1778)
						)
						(arc
							(start 0.2794 -0.1778)
							(mid 0.249642 -0.249642)
							(end 0.1778 -0.2794)
						)
					)
					(width 0)
					(fill yes)
				)
			)
		)
		(pad "2" smd custom
			(at 0 0.4445 90)
			(size 0.1397 0.1397)
			(layers "F.Cu" "F.Mask" "F.Paste")
			(net "SW_HDD_R28")
			(options
				(clearance outline)
				(anchor circle)
			)
			(primitives
				(gr_poly
					(pts
						(arc
							(start -0.1778 -0.2794)
							(mid -0.249642 -0.249642)
							(end -0.2794 -0.1778)
						)
						(arc
							(start -0.2794 0.1778)
							(mid -0.249642 0.249642)
							(end -0.1778 0.2794)
						)
						(arc
							(start 0.1778 0.2794)
							(mid 0.249642 0.249642)
							(end 0.2794 0.1778)
						)
						(arc
							(start 0.2794 -0.1778)
							(mid 0.249642 -0.249642)
							(end 0.1778 -0.2794)
						)
					)
					(width 0)
					(fill yes)
				)
			)
		)
	)
	(footprint ""
		(layer "F.Cu")
		(at 77.851 -35.687 -90)
		(property "Reference" "C372"
			(at 0 0 270)
			(layer "F.SilkS")
			(hide yes)
			(effects
				(font
					(size 1.27 1.27)
				)
			)
		)
		(property "Value" "SC4D7U25V5KX-1-GP"
			(at -0.0762 -6.1214 270)
			(unlocked yes)
			(layer "F.Fab")
			(hide yes)
			(effects
				(font
					(size 1.016 1.016)
					(thickness 0.1524)
				)
			)
		)
		(property "Device Type" "C805H58"
			(at -0.0762 -8.1534 270)
			(unlocked yes)
			(layer "F.Fab")
			(hide yes)
			(effects
				(font
					(size 1.016 1.016)
					(thickness 0.1524)
				)
			)
		)
		(duplicate_pad_numbers_are_jumpers no)
		(fp_line
			(start 0.635 0)
			(end -0.635 0)
			(stroke
				(width 0.508)
				(type default)
			)
			(layer "F.SilkS")
		)
		(fp_rect
			(start -0.9652 1.778)
			(end 0.9652 -1.778)
			(stroke
				(width 0)
				(type default)
			)
			(fill no)
			(layer "F.CrtYd")
		)
		(fp_poly
			(pts
				(xy -0.9652 -1.778) (xy 0.9652 -1.778) (xy 0.9652 1.778) (xy -0.9652 1.778)
			)
			(stroke
				(width 0)
				(type default)
			)
			(fill no)
			(layer "F.Fab")
		)
		(pad "1" smd rect
			(at 0 -0.9652 270)
			(size 1.397 1.143)
			(layers "F.Cu" "F.Mask" "F.Paste")
			(net "P12V_HDD26")
		)
		(pad "2" smd rect
			(at 0 0.9652 270)
			(size 1.397 1.143)
			(layers "F.Cu" "F.Mask" "F.Paste")
			(net "GND")
		)
	)
	(footprint ""
		(layer "F.Cu")
		(at 378.968 -214.249)
		(property "Reference" "R333"
			(at 0 0 0)
			(layer "F.SilkS")
			(hide yes)
			(effects
				(font
					(size 1.27 1.27)
				)
			)
		)
		(property "Value" "91R3F-1-GP"
			(at -0.0254 -2.5146 0)
			(unlocked yes)
			(layer "F.Fab")
			(hide yes)
			(effects
				(font
					(size 1.016 1.016)
					(thickness 0.1524)
				)
			)
		)
		(property "Device Type" "R603H22"
			(at -0.0254 -4.0386 0)
			(unlocked yes)
			(layer "F.Fab")
			(hide yes)
			(effects
				(font
					(size 1.016 1.016)
					(thickness 0.1524)
				)
			)
		)
		(duplicate_pad_numbers_are_jumpers no)
		(fp_line
			(start -0.4826 0)
			(end -0.2032 0)
			(stroke
				(width 0.2032)
				(type default)
			)
			(layer "F.SilkS")
		)
		(fp_line
			(start 0.2032 0)
			(end 0.4826 0)
			(stroke
				(width 0.2032)
				(type default)
			)
			(layer "F.SilkS")
		)
		(fp_rect
			(start -0.5842 1.3335)
			(end 0.5842 -1.3335)
			(stroke
				(width 0)
				(type default)
			)
			(fill no)
			(layer "F.CrtYd")
		)
		(fp_rect
			(start -0.5842 1.3335)
			(end 0.5842 -1.3335)
			(stroke
				(width 0)
				(type default)
			)
			(fill no)
			(layer "F.Fab")
		)
		(pad "1" smd custom
			(at 0 -0.762)
			(size 0.2159 0.2159)
			(layers "F.Cu" "F.Mask" "F.Paste")
			(net "P5V_B_3")
			(options
				(clearance outline)
				(anchor circle)
			)
			(primitives
				(gr_poly
					(pts
						(arc
							(start -0.3302 -0.4318)
							(mid -0.402042 -0.402042)
							(end -0.4318 -0.3302)
						)
						(arc
							(start -0.4318 0.3302)
							(mid -0.402042 0.402042)
							(end -0.3302 0.4318)
						)
						(arc
							(start 0.3302 0.4318)
							(mid 0.402042 0.402042)
							(end 0.4318 0.3302)
						)
						(arc
							(start 0.4318 -0.3302)
							(mid 0.402042 -0.402042)
							(end 0.3302 -0.4318)
						)
					)
					(width 0)
					(fill yes)
				)
			)
		)
		(pad "2" smd custom
			(at 0 0.762)
			(size 0.2159 0.2159)
			(layers "F.Cu" "F.Mask" "F.Paste")
			(net "DRV_ACT_8")
			(options
				(clearance outline)
				(anchor circle)
			)
			(primitives
				(gr_poly
					(pts
						(arc
							(start -0.3302 -0.4318)
							(mid -0.402042 -0.402042)
							(end -0.4318 -0.3302)
						)
						(arc
							(start -0.4318 0.3302)
							(mid -0.402042 0.402042)
							(end -0.3302 0.4318)
						)
						(arc
							(start 0.3302 0.4318)
							(mid 0.402042 0.402042)
							(end 0.4318 0.3302)
						)
						(arc
							(start 0.4318 -0.3302)
							(mid 0.402042 -0.402042)
							(end 0.3302 -0.4318)
						)
					)
					(width 0)
					(fill yes)
				)
			)
		)
	)
	(footprint ""
		(layer "F.Cu")
		(at 339.743796 -214.860378 90)
		(property "Reference" "Q250"
			(at 0 0 90)
			(layer "F.SilkS")
			(hide yes)
			(effects
				(font
					(size 1.27 1.27)
				)
			)
		)
		(property "Value" "SSM3K324R-GP"
			(at 0.127 -8.9662 90)
			(unlocked yes)
			(layer "F.Fab")
			(hide yes)
			(effects
				(font
					(size 1.016 1.016)
					(thickness 0.1524)
				)
			)
		)
		(property "Device Type" "SOT23DGS2D4H35"
			(at 0.127 -10.4902 90)
			(unlocked yes)
			(layer "F.Fab")
			(hide yes)
			(effects
				(font
					(size 1.016 1.016)
					(thickness 0.1524)
				)
			)
		)
		(duplicate_pad_numbers_are_jumpers no)
		(fp_line
			(start 1.651 -1.778)
			(end -1.651 -1.778)
			(stroke
				(width 0.1524)
				(type default)
			)
			(layer "F.SilkS")
		)
		(fp_line
			(start -1.651 -1.778)
			(end -1.651 1.778)
			(stroke
				(width 0.1524)
				(type default)
			)
			(layer "F.SilkS")
		)
		(fp_line
			(start 1.651 1.778)
			(end 1.651 -1.778)
			(stroke
				(width 0.1524)
				(type default)
			)
			(layer "F.SilkS")
		)
		(fp_line
			(start -1.651 1.778)
			(end 1.651 1.778)
			(stroke
				(width 0.1524)
				(type default)
			)
			(layer "F.SilkS")
		)
		(fp_poly
			(pts
				(xy -1.778 1.8796) (xy -1.778 -1.8796) (xy 1.778 -1.8796) (xy 1.778 1.8796)
			)
			(stroke
				(width 0)
				(type default)
			)
			(fill no)
			(layer "F.CrtYd")
		)
		(fp_poly
			(pts
				(xy -1.778 1.8796) (xy -1.778 -1.8796) (xy 1.778 -1.8796) (xy 1.778 1.8796)
			)
			(stroke
				(width 0)
				(type default)
			)
			(fill no)
			(layer "F.Fab")
		)
		(pad "D" smd custom
			(at 0 -0.9525 90)
			(size 0.1905 0.1905)
			(layers "F.Cu" "F.Mask" "F.Paste")
			(net "DRV_ACT_7_N")
			(options
				(clearance outline)
				(anchor circle)
			)
			(primitives
				(gr_poly
					(pts
						(arc
							(start -0.1778 0.5715)
							(mid -0.321484 0.511984)
							(end -0.381 0.3683)
						)
						(arc
							(start -0.381 -0.3683)
							(mid -0.321484 -0.511984)
							(end -0.1778 -0.5715)
						)
						(arc
							(start 0.1778 -0.5715)
							(mid 0.321484 -0.511984)
							(end 0.381 -0.3683)
						)
						(arc
							(start 0.381 0.3683)
							(mid 0.321484 0.511984)
							(end 0.1778 0.5715)
						)
					)
					(width 0)
					(fill yes)
				)
			)
		)
		(pad "G" smd custom
			(at -0.98425 0.9525 90)
			(size 0.1905 0.1905)
			(layers "F.Cu" "F.Mask" "F.Paste")
			(net "DRIVE_B_7_ACT")
			(options
				(clearance outline)
				(anchor circle)
			)
			(primitives
				(gr_poly
					(pts
						(arc
							(start -0.1778 0.5715)
							(mid -0.321484 0.511984)
							(end -0.381 0.3683)
						)
						(arc
							(start -0.381 -0.3683)
							(mid -0.321484 -0.511984)
							(end -0.1778 -0.5715)
						)
						(arc
							(start 0.1778 -0.5715)
							(mid 0.321484 -0.511984)
							(end 0.381 -0.3683)
						)
						(arc
							(start 0.381 0.3683)
							(mid 0.321484 0.511984)
							(end 0.1778 0.5715)
						)
					)
					(width 0)
					(fill yes)
				)
			)
		)
		(pad "S" smd custom
			(at 0.98425 0.9525 90)
			(size 0.1905 0.1905)
			(layers "F.Cu" "F.Mask" "F.Paste")
			(net "GND")
			(options
				(clearance outline)
				(anchor circle)
			)
			(primitives
				(gr_poly
					(pts
						(arc
							(start -0.1778 0.5715)
							(mid -0.321484 0.511984)
							(end -0.381 0.3683)
						)
						(arc
							(start -0.381 -0.3683)
							(mid -0.321484 -0.511984)
							(end -0.1778 -0.5715)
						)
						(arc
							(start 0.1778 -0.5715)
							(mid 0.321484 -0.511984)
							(end 0.381 -0.3683)
						)
						(arc
							(start 0.381 0.3683)
							(mid 0.321484 0.511984)
							(end 0.1778 0.5715)
						)
					)
					(width 0)
					(fill yes)
				)
			)
		)
	)
	(footprint ""
		(layer "F.Cu")
		(at 175.550068 -180.399944)
		(property "Reference" "LED6"
			(at 0 0 0)
			(layer "F.SilkS")
			(hide yes)
			(effects
				(font
					(size 1.27 1.27)
				)
			)
		)
		(property "Value" "LED-BY-19-GP"
			(at -2.132076 1.414018 0)
			(unlocked yes)
			(layer "F.Fab")
			(hide yes)
			(effects
				(font
					(size 1.016 1.016)
					(thickness 0.1524)
				)
			)
		)
		(property "Device Type" "LED-1615-4PH26"
			(at -2.132076 -0.109982 0)
			(unlocked yes)
			(layer "F.Fab")
			(hide yes)
			(effects
				(font
					(size 1.016 1.016)
					(thickness 0.1524)
				)
			)
		)
		(duplicate_pad_numbers_are_jumpers no)
		(fp_line
			(start -1.2954 0.254)
			(end -1.2954 1.6002)
			(stroke
				(width 0.508)
				(type default)
			)
			(layer "F.SilkS")
		)
		(fp_line
			(start -1.2954 1.6002)
			(end 1.2954 1.6002)
			(stroke
				(width 0.508)
				(type default)
			)
			(layer "F.SilkS")
		)
		(fp_line
			(start -1.1176 -1.4224)
			(end 1.1176 -1.4224)
			(stroke
				(width 0.1524)
				(type default)
			)
			(layer "F.SilkS")
		)
		(fp_line
			(start -1.1176 1.4224)
			(end -1.1176 -1.4224)
			(stroke
				(width 0.1524)
				(type default)
			)
			(layer "F.SilkS")
		)
		(fp_line
			(start 1.1176 -1.4224)
			(end 1.1176 1.4224)
			(stroke
				(width 0.1524)
				(type default)
			)
			(layer "F.SilkS")
		)
		(fp_line
			(start 1.1176 1.4224)
			(end -1.1176 1.4224)
			(stroke
				(width 0.1524)
				(type default)
			)
			(layer "F.SilkS")
		)
		(fp_line
			(start 1.2954 1.6002)
			(end 1.2954 0.254)
			(stroke
				(width 0.508)
				(type default)
			)
			(layer "F.SilkS")
		)
		(fp_rect
			(start -0.7493 0.8001)
			(end 0.7493 -0.8001)
			(stroke
				(width 0)
				(type default)
			)
			(fill no)
			(layer "F.CrtYd")
		)
		(fp_poly
			(pts
				(xy -1.3716 1.6764) (xy -1.3716 -1.6764) (xy 1.3716 -1.6764) (xy 1.3716 0.0635) (xy 0.7493 0.0635)
				(xy 0.7493 -0.8001) (xy -0.7493 -0.8001) (xy -0.7493 0.8001) (xy 0.7493 0.8001) (xy 0.7493 0.0762)
				(xy 1.3716 0.0762) (xy 1.3716 1.6764)
			)
			(stroke
				(width 0)
				(type default)
			)
			(fill no)
			(layer "F.CrtYd")
		)
		(fp_rect
			(start -1.3716 1.6764)
			(end 1.3716 -1.6764)
			(stroke
				(width 0)
				(type default)
			)
			(fill no)
			(layer "F.Fab")
		)
		(pad "1" smd rect
			(at 0.50038 -0.73025)
			(size 0.7112 0.8636)
			(layers "F.Cu" "F.Mask" "F.Paste")
			(net "DRV_ACT_5")
		)
		(pad "2" smd rect
			(at -0.50038 -0.73025)
			(size 0.7112 0.8636)
			(layers "F.Cu" "F.Mask" "F.Paste")
			(net "FLT_HDD5")
		)
		(pad "3" smd rect
			(at 0.50038 0.73025)
			(size 0.7112 0.8636)
			(layers "F.Cu" "F.Mask" "F.Paste")
			(net "DRV_ACT_5_N")
		)
		(pad "4" smd rect
			(at -0.50038 0.73025)
			(size 0.7112 0.8636)
			(layers "F.Cu" "F.Mask" "F.Paste")
			(net "FLT_HDD5_N")
		)
	)
	(footprint ""
		(layer "F.Cu")
		(at 161.544 -147.066 90)
		(property "Reference" "C245"
			(at 0 0 90)
			(layer "F.SilkS")
			(hide yes)
			(effects
				(font
					(size 1.27 1.27)
				)
			)
		)
		(property "Value" "SCD01U50V2KX-1GP"
			(at 1.1811 -2.7051 90)
			(unlocked yes)
			(layer "F.Fab")
			(hide yes)
			(effects
				(font
					(size 1.016 1.016)
					(thickness 0.1524)
				)
			)
		)
		(property "Device Type" "C402H22"
			(at 1.1811 -4.2291 90)
			(unlocked yes)
			(layer "F.Fab")
			(hide yes)
			(effects
				(font
					(size 1.016 1.016)
					(thickness 0.1524)
				)
			)
		)
		(duplicate_pad_numbers_are_jumpers no)
		(fp_rect
			(start -0.4318 0.9525)
			(end 0.4318 -0.9525)
			(stroke
				(width 0)
				(type default)
			)
			(fill no)
			(layer "F.CrtYd")
		)
		(fp_rect
			(start -0.4318 0.9525)
			(end 0.4318 -0.9525)
			(stroke
				(width 0)
				(type default)
			)
			(fill no)
			(layer "F.Fab")
		)
		(pad "1" smd custom
			(at 0 -0.4445 90)
			(size 0.1524 0.1524)
			(layers "F.Cu" "F.Mask" "F.Paste")
			(net "HDD_PRSNT_16")
			(options
				(clearance outline)
				(anchor circle)
			)
			(primitives
				(gr_poly
					(pts
						(arc
							(start 0.3048 -0.2032)
							(mid 0.275042 -0.275042)
							(end 0.2032 -0.3048)
						)
						(arc
							(start -0.2032 -0.3048)
							(mid -0.275042 -0.275042)
							(end -0.3048 -0.2032)
						)
						(arc
							(start -0.3048 0.2032)
							(mid -0.275042 0.275042)
							(end -0.2032 0.3048)
						)
						(arc
							(start 0.2032 0.3048)
							(mid 0.275042 0.275042)
							(end 0.3048 0.2032)
						)
					)
					(width 0)
					(fill yes)
				)
			)
		)
		(pad "2" smd custom
			(at 0 0.4445 90)
			(size 0.1524 0.1524)
			(layers "F.Cu" "F.Mask" "F.Paste")
			(net "GND")
			(options
				(clearance outline)
				(anchor circle)
			)
			(primitives
				(gr_poly
					(pts
						(arc
							(start 0.3048 -0.2032)
							(mid 0.275042 -0.275042)
							(end 0.2032 -0.3048)
						)
						(arc
							(start -0.2032 -0.3048)
							(mid -0.275042 -0.275042)
							(end -0.3048 -0.2032)
						)
						(arc
							(start -0.3048 0.2032)
							(mid -0.275042 0.275042)
							(end -0.2032 0.3048)
						)
						(arc
							(start 0.2032 0.3048)
							(mid 0.275042 0.275042)
							(end 0.3048 0.2032)
						)
					)
					(width 0)
					(fill yes)
				)
			)
		)
	)
	(footprint ""
		(layer "F.Cu")
		(at 97.863914 -154.70505)
		(property "Reference" "TP91"
			(at 0 0 0)
			(layer "F.SilkS")
			(hide yes)
			(effects
				(font
					(size 1.27 1.27)
				)
			)
		)
		(property "Value" "*"
			(at -0.0508 -1.6764 0)
			(unlocked yes)
			(layer "F.Fab")
			(hide yes)
			(effects
				(font
					(size 1.016 1.016)
					(thickness 0.1524)
				)
			)
		)
		(property "Device Type" "TPAD32"
			(at -0.0508 -3.2004 0)
			(unlocked yes)
			(layer "F.Fab")
			(hide yes)
			(effects
				(font
					(size 1.016 1.016)
					(thickness 0.1524)
				)
			)
		)
		(duplicate_pad_numbers_are_jumpers no)
		(fp_poly
			(pts
				(arc
					(start 0.4064 0)
					(mid -0.4064 0)
					(end 0.4064 0)
				)
			)
			(stroke
				(width 0)
				(type default)
			)
			(fill no)
			(layer "F.CrtYd")
		)
		(fp_poly
			(pts
				(arc
					(start 0.7112 0)
					(mid -0.7112 0)
					(end 0.7112 0)
				)
			)
			(stroke
				(width 0)
				(type default)
			)
			(fill no)
			(layer "F.Fab")
		)
		(pad "1" smd circle
			(at 0 0)
			(size 0.8128 0.8128)
			(layers "F.Cu" "F.Mask" "F.Paste")
			(net "ACT_HDD_14")
		)
	)
	(footprint ""
		(layer "F.Cu")
		(at 353.184714 -14.660626 -90)
		(property "Reference" "C432"
			(at 0 0 270)
			(layer "F.SilkS")
			(hide yes)
			(effects
				(font
					(size 1.27 1.27)
				)
			)
		)
		(property "Value" "SCD01U16V1KX-GP"
			(at -2.8321 -1.7399 270)
			(unlocked yes)
			(layer "F.Fab")
			(hide yes)
			(effects
				(font
					(size 1.016 1.016)
					(thickness 0.1524)
				)
			)
		)
		(property "Device Type" "C0201H13"
			(at -2.8321 -3.2639 270)
			(unlocked yes)
			(layer "F.Fab")
			(hide yes)
			(effects
				(font
					(size 1.016 1.016)
					(thickness 0.1524)
				)
			)
		)
		(duplicate_pad_numbers_are_jumpers no)
		(fp_rect
			(start -0.2794 0.6477)
			(end 0.2794 -0.6477)
			(stroke
				(width 0)
				(type default)
			)
			(fill no)
			(layer "F.CrtYd")
		)
		(fp_rect
			(start -0.2794 0.6477)
			(end 0.2794 -0.6477)
			(stroke
				(width 0)
				(type default)
			)
			(fill no)
			(layer "F.Fab")
		)
		(pad "1" smd custom
			(at 0 -0.2794 270)
			(size 0.0762 0.0762)
			(layers "F.Cu" "F.Mask" "F.Paste")
			(net "SAS_HDD_RX_P31")
			(options
				(clearance outline)
				(anchor circle)
			)
			(primitives
				(gr_poly
					(pts
						(arc
							(start 0.1524 -0.127)
							(mid 0.137521 -0.162921)
							(end 0.1016 -0.1778)
						)
						(arc
							(start -0.1016 -0.1778)
							(mid -0.137521 -0.162921)
							(end -0.1524 -0.127)
						)
						(arc
							(start -0.1524 0.127)
							(mid -0.137521 0.162921)
							(end -0.1016 0.1778)
						)
						(arc
							(start 0.1016 0.1778)
							(mid 0.137521 0.162921)
							(end 0.1524 0.127)
						)
					)
					(width 0)
					(fill yes)
				)
			)
		)
		(pad "2" smd custom
			(at 0 0.2794 270)
			(size 0.0762 0.0762)
			(layers "F.Cu" "F.Mask" "F.Paste")
			(net "PHY_SCC_B_TO_DRV_B_31_DP")
			(options
				(clearance outline)
				(anchor circle)
			)
			(primitives
				(gr_poly
					(pts
						(arc
							(start 0.1524 -0.127)
							(mid 0.137521 -0.162921)
							(end 0.1016 -0.1778)
						)
						(arc
							(start -0.1016 -0.1778)
							(mid -0.137521 -0.162921)
							(end -0.1524 -0.127)
						)
						(arc
							(start -0.1524 0.127)
							(mid -0.137521 0.162921)
							(end -0.1016 0.1778)
						)
						(arc
							(start 0.1016 0.1778)
							(mid 0.137521 0.162921)
							(end 0.1524 0.127)
						)
					)
					(width 0)
					(fill yes)
				)
			)
		)
	)
	(footprint ""
		(layer "F.Cu")
		(at 479.384614 -244.660674 -90)
		(property "Reference" "C172"
			(at 0 0 270)
			(layer "F.SilkS")
			(hide yes)
			(effects
				(font
					(size 1.27 1.27)
				)
			)
		)
		(property "Value" "SCD01U16V1KX-GP"
			(at -2.8321 -1.7399 270)
			(unlocked yes)
			(layer "F.Fab")
			(hide yes)
			(effects
				(font
					(size 1.016 1.016)
					(thickness 0.1524)
				)
			)
		)
		(property "Device Type" "C0201H13"
			(at -2.8321 -3.2639 270)
			(unlocked yes)
			(layer "F.Fab")
			(hide yes)
			(effects
				(font
					(size 1.016 1.016)
					(thickness 0.1524)
				)
			)
		)
		(duplicate_pad_numbers_are_jumpers no)
		(fp_rect
			(start -0.2794 0.6477)
			(end 0.2794 -0.6477)
			(stroke
				(width 0)
				(type default)
			)
			(fill no)
			(layer "F.CrtYd")
		)
		(fp_rect
			(start -0.2794 0.6477)
			(end 0.2794 -0.6477)
			(stroke
				(width 0)
				(type default)
			)
			(fill no)
			(layer "F.Fab")
		)
		(pad "1" smd custom
			(at 0 -0.2794 270)
			(size 0.0762 0.0762)
			(layers "F.Cu" "F.Mask" "F.Paste")
			(net "SAS_HDD_RX_P11")
			(options
				(clearance outline)
				(anchor circle)
			)
			(primitives
				(gr_poly
					(pts
						(arc
							(start 0.1524 -0.127)
							(mid 0.137521 -0.162921)
							(end 0.1016 -0.1778)
						)
						(arc
							(start -0.1016 -0.1778)
							(mid -0.137521 -0.162921)
							(end -0.1524 -0.127)
						)
						(arc
							(start -0.1524 0.127)
							(mid -0.137521 0.162921)
							(end -0.1016 0.1778)
						)
						(arc
							(start 0.1016 0.1778)
							(mid 0.137521 0.162921)
							(end 0.1524 0.127)
						)
					)
					(width 0)
					(fill yes)
				)
			)
		)
		(pad "2" smd custom
			(at 0 0.2794 270)
			(size 0.0762 0.0762)
			(layers "F.Cu" "F.Mask" "F.Paste")
			(net "PHY_SCC_B_TO_DRV_B_11_DP")
			(options
				(clearance outline)
				(anchor circle)
			)
			(primitives
				(gr_poly
					(pts
						(arc
							(start 0.1524 -0.127)
							(mid 0.137521 -0.162921)
							(end 0.1016 -0.1778)
						)
						(arc
							(start -0.1016 -0.1778)
							(mid -0.137521 -0.162921)
							(end -0.1524 -0.127)
						)
						(arc
							(start -0.1524 0.127)
							(mid -0.137521 0.162921)
							(end -0.1016 0.1778)
						)
						(arc
							(start 0.1016 0.1778)
							(mid 0.137521 0.162921)
							(end 0.1524 0.127)
						)
					)
					(width 0)
					(fill yes)
				)
			)
		)
	)
	(footprint ""
		(layer "F.Cu")
		(at 283.365448 -356.304342 -90)
		(property "Reference" "C615"
			(at 0 0 270)
			(layer "F.SilkS")
			(hide yes)
			(effects
				(font
					(size 1.27 1.27)
				)
			)
		)
		(property "Value" "SCD1U16V2KX-3GP"
			(at 1.1811 -2.7051 270)
			(unlocked yes)
			(layer "F.Fab")
			(hide yes)
			(effects
				(font
					(size 1.016 1.016)
					(thickness 0.1524)
				)
			)
		)
		(property "Device Type" "C402H22"
			(at 1.1811 -4.2291 270)
			(unlocked yes)
			(layer "F.Fab")
			(hide yes)
			(effects
				(font
					(size 1.016 1.016)
					(thickness 0.1524)
				)
			)
		)
		(duplicate_pad_numbers_are_jumpers no)
		(fp_rect
			(start -0.4318 0.9525)
			(end 0.4318 -0.9525)
			(stroke
				(width 0)
				(type default)
			)
			(fill no)
			(layer "F.CrtYd")
		)
		(fp_rect
			(start -0.4318 0.9525)
			(end 0.4318 -0.9525)
			(stroke
				(width 0)
				(type default)
			)
			(fill no)
			(layer "F.Fab")
		)
		(pad "1" smd custom
			(at 0 -0.4445 270)
			(size 0.1524 0.1524)
			(layers "F.Cu" "F.Mask" "F.Paste")
			(net "P3V3_STBY_B")
			(options
				(clearance outline)
				(anchor circle)
			)
			(primitives
				(gr_poly
					(pts
						(arc
							(start 0.3048 -0.2032)
							(mid 0.275042 -0.275042)
							(end 0.2032 -0.3048)
						)
						(arc
							(start -0.2032 -0.3048)
							(mid -0.275042 -0.275042)
							(end -0.3048 -0.2032)
						)
						(arc
							(start -0.3048 0.2032)
							(mid -0.275042 0.275042)
							(end -0.2032 0.3048)
						)
						(arc
							(start 0.2032 0.3048)
							(mid 0.275042 0.275042)
							(end 0.3048 0.2032)
						)
					)
					(width 0)
					(fill yes)
				)
			)
		)
		(pad "2" smd custom
			(at 0 0.4445 270)
			(size 0.1524 0.1524)
			(layers "F.Cu" "F.Mask" "F.Paste")
			(net "GND")
			(options
				(clearance outline)
				(anchor circle)
			)
			(primitives
				(gr_poly
					(pts
						(arc
							(start 0.3048 -0.2032)
							(mid 0.275042 -0.275042)
							(end 0.2032 -0.3048)
						)
						(arc
							(start -0.2032 -0.3048)
							(mid -0.275042 -0.275042)
							(end -0.3048 -0.2032)
						)
						(arc
							(start -0.3048 0.2032)
							(mid -0.275042 0.275042)
							(end -0.2032 0.3048)
						)
						(arc
							(start 0.2032 0.3048)
							(mid 0.275042 0.275042)
							(end 0.3048 0.2032)
						)
					)
					(width 0)
					(fill yes)
				)
			)
		)
	)
	(footprint ""
		(layer "F.Cu")
		(at 340.5124 -360.8578)
		(property "Reference" "Q130"
			(at 0 0 0)
			(layer "F.SilkS")
			(hide yes)
			(effects
				(font
					(size 1.27 1.27)
				)
			)
		)
		(property "Value" "AO4407AL-GP"
			(at -3.707384 -1.5367 0)
			(unlocked yes)
			(layer "F.Fab")
			(hide yes)
			(effects
				(font
					(size 1.016 1.016)
					(thickness 0.1524)
				)
			)
		)
		(property "Device Type" "SOIC8H69"
			(at -3.707384 -3.0607 0)
			(unlocked yes)
			(layer "F.Fab")
			(hide yes)
			(effects
				(font
					(size 1.016 1.016)
					(thickness 0.1524)
				)
			)
		)
		(duplicate_pad_numbers_are_jumpers no)
		(fp_line
			(start -2.7432 -1.4224)
			(end -2.7432 1.4224)
			(stroke
				(width 0.1524)
				(type default)
			)
			(layer "F.SilkS")
		)
		(fp_line
			(start -2.7432 1.4224)
			(end -2.6416 1.4224)
			(stroke
				(width 0.1524)
				(type default)
			)
			(layer "F.SilkS")
		)
		(fp_line
			(start -2.7432 1.4224)
			(end 2.1336 1.4224)
			(stroke
				(width 0.1524)
				(type default)
			)
			(layer "F.SilkS")
		)
		(fp_line
			(start -2.7178 -0.508)
			(end -2.1844 -0.0508)
			(stroke
				(width 0.1524)
				(type default)
			)
			(layer "F.SilkS")
		)
		(fp_line
			(start -2.6289 3.4417)
			(end -2.6289 1.4732)
			(stroke
				(width 0.381)
				(type default)
			)
			(layer "F.SilkS")
		)
		(fp_line
			(start -2.1844 -0.0508)
			(end -2.7178 0.508)
			(stroke
				(width 0.1524)
				(type default)
			)
			(layer "F.SilkS")
		)
		(fp_line
			(start 2.1336 -1.4224)
			(end -2.7432 -1.4224)
			(stroke
				(width 0.1524)
				(type default)
			)
			(layer "F.SilkS")
		)
		(fp_line
			(start 2.1336 1.4224)
			(end 2.1336 -1.4224)
			(stroke
				(width 0.1524)
				(type default)
			)
			(layer "F.SilkS")
		)
		(fp_poly
			(pts
				(xy -2.2098 -1.4224) (xy -2.2098 1.4224) (xy 2.2098 1.4224) (xy 2.2098 -1.4224)
			)
			(stroke
				(width 0)
				(type default)
			)
			(fill yes)
			(layer "F.SilkS")
		)
		(fp_rect
			(start -2.450084 2.999994)
			(end 2.450084 -2.999994)
			(stroke
				(width 0)
				(type default)
			)
			(fill no)
			(layer "F.CrtYd")
		)
		(fp_poly
			(pts
				(xy -2.8194 3.6322) (xy -2.8194 -3.6322) (xy 2.8194 -3.6322) (xy 2.8194 1.18364) (xy 2.450084 1.18364)
				(xy 2.450084 -2.999994) (xy -2.450084 -2.999994) (xy -2.450084 2.999994) (xy 2.450084 2.999994)
				(xy 2.450084 1.18618) (xy 2.8194 1.18618) (xy 2.8194 3.6322)
			)
			(stroke
				(width 0)
				(type default)
			)
			(fill no)
			(layer "F.CrtYd")
		)
		(fp_rect
			(start -2.8194 3.6322)
			(end 2.8194 -3.6322)
			(stroke
				(width 0)
				(type default)
			)
			(fill no)
			(layer "F.Fab")
		)
		(pad "1" smd rect
			(at -1.905 2.54)
			(size 0.635 1.651)
			(layers "F.Cu" "F.Mask" "F.Paste")
			(net "P12V_IN")
		)
		(pad "2" smd rect
			(at -0.635 2.54)
			(size 0.635 1.651)
			(layers "F.Cu" "F.Mask" "F.Paste")
			(net "P12V_IN")
		)
		(pad "3" smd rect
			(at 0.635 2.54)
			(size 0.635 1.651)
			(layers "F.Cu" "F.Mask" "F.Paste")
			(net "P12V_IN")
		)
		(pad "4" smd rect
			(at 1.905 2.54)
			(size 0.635 1.651)
			(layers "F.Cu" "F.Mask" "F.Paste")
			(net "GATE_FAN2_R")
		)
		(pad "5" smd rect
			(at 1.905 -2.54)
			(size 0.635 1.651)
			(layers "F.Cu" "F.Mask" "F.Paste")
			(net "P12V_FAN2")
		)
		(pad "6" smd rect
			(at 0.635 -2.54)
			(size 0.635 1.651)
			(layers "F.Cu" "F.Mask" "F.Paste")
			(net "P12V_FAN2")
		)
		(pad "7" smd rect
			(at -0.635 -2.54)
			(size 0.635 1.651)
			(layers "F.Cu" "F.Mask" "F.Paste")
			(net "P12V_FAN2")
		)
		(pad "8" smd rect
			(at -1.905 -2.54)
			(size 0.635 1.651)
			(layers "F.Cu" "F.Mask" "F.Paste")
			(net "P12V_FAN2")
		)
	)
	(footprint ""
		(layer "F.Cu")
		(at 258.064 -232.283 180)
		(property "Reference" "Q21"
			(at 0 0 180)
			(layer "F.SilkS")
			(hide yes)
			(effects
				(font
					(size 1.27 1.27)
				)
			)
		)
		(property "Value" "2N7002K-1-GP"
			(at 0.127 -8.9662 180)
			(unlocked yes)
			(layer "F.Fab")
			(hide yes)
			(effects
				(font
					(size 1.016 1.016)
					(thickness 0.1524)
				)
			)
		)
		(property "Device Type" "SOT23DGS2D4H44"
			(at 0.127 -10.4902 180)
			(unlocked yes)
			(layer "F.Fab")
			(hide yes)
			(effects
				(font
					(size 1.016 1.016)
					(thickness 0.1524)
				)
			)
		)
		(duplicate_pad_numbers_are_jumpers no)
		(fp_line
			(start 1.651 1.778)
			(end 1.651 -1.778)
			(stroke
				(width 0.1524)
				(type default)
			)
			(layer "F.SilkS")
		)
		(fp_line
			(start 1.651 -1.778)
			(end -1.651 -1.778)
			(stroke
				(width 0.1524)
				(type default)
			)
			(layer "F.SilkS")
		)
		(fp_line
			(start -1.651 1.778)
			(end 1.651 1.778)
			(stroke
				(width 0.1524)
				(type default)
			)
			(layer "F.SilkS")
		)
		(fp_line
			(start -1.651 -1.778)
			(end -1.651 1.778)
			(stroke
				(width 0.1524)
				(type default)
			)
			(layer "F.SilkS")
		)
		(fp_poly
			(pts
				(xy -1.778 1.8796) (xy -1.778 -1.8796) (xy 1.778 -1.8796) (xy 1.778 1.8796)
			)
			(stroke
				(width 0)
				(type default)
			)
			(fill no)
			(layer "F.CrtYd")
		)
		(fp_poly
			(pts
				(xy -1.778 1.8796) (xy -1.778 -1.8796) (xy 1.778 -1.8796) (xy 1.778 1.8796)
			)
			(stroke
				(width 0)
				(type default)
			)
			(fill no)
			(layer "F.Fab")
		)
		(pad "D" smd custom
			(at 0 -0.9525 180)
			(size 0.1905 0.1905)
			(layers "F.Cu" "F.Mask" "F.Paste")
			(net "SCC_FULL_PWR_EN_5V_R")
			(options
				(clearance outline)
				(anchor circle)
			)
			(primitives
				(gr_poly
					(pts
						(arc
							(start -0.1778 0.5715)
							(mid -0.321484 0.511984)
							(end -0.381 0.3683)
						)
						(arc
							(start -0.381 -0.3683)
							(mid -0.321484 -0.511984)
							(end -0.1778 -0.5715)
						)
						(arc
							(start 0.1778 -0.5715)
							(mid 0.321484 -0.511984)
							(end 0.381 -0.3683)
						)
						(arc
							(start 0.381 0.3683)
							(mid 0.321484 0.511984)
							(end 0.1778 0.5715)
						)
					)
					(width 0)
					(fill yes)
				)
			)
		)
		(pad "G" smd custom
			(at -0.98425 0.9525 180)
			(size 0.1905 0.1905)
			(layers "F.Cu" "F.Mask" "F.Paste")
			(net "SCC_B_FULL_PWR_EN_12V")
			(options
				(clearance outline)
				(anchor circle)
			)
			(primitives
				(gr_poly
					(pts
						(arc
							(start -0.1778 0.5715)
							(mid -0.321484 0.511984)
							(end -0.381 0.3683)
						)
						(arc
							(start -0.381 -0.3683)
							(mid -0.321484 -0.511984)
							(end -0.1778 -0.5715)
						)
						(arc
							(start 0.1778 -0.5715)
							(mid 0.321484 -0.511984)
							(end 0.381 -0.3683)
						)
						(arc
							(start 0.381 0.3683)
							(mid 0.321484 0.511984)
							(end 0.1778 0.5715)
						)
					)
					(width 0)
					(fill yes)
				)
			)
		)
		(pad "S" smd custom
			(at 0.98425 0.9525 180)
			(size 0.1905 0.1905)
			(layers "F.Cu" "F.Mask" "F.Paste")
			(net "GND")
			(options
				(clearance outline)
				(anchor circle)
			)
			(primitives
				(gr_poly
					(pts
						(arc
							(start -0.1778 0.5715)
							(mid -0.321484 0.511984)
							(end -0.381 0.3683)
						)
						(arc
							(start -0.381 -0.3683)
							(mid -0.321484 -0.511984)
							(end -0.1778 -0.5715)
						)
						(arc
							(start 0.1778 -0.5715)
							(mid 0.321484 -0.511984)
							(end 0.381 -0.3683)
						)
						(arc
							(start 0.381 0.3683)
							(mid 0.321484 0.511984)
							(end 0.1778 0.5715)
						)
					)
					(width 0)
					(fill yes)
				)
			)
		)
	)
	(footprint ""
		(layer "F.Cu")
		(at 427.863 -128.651 180)
		(property "Reference" "R561"
			(at 0 0 180)
			(layer "F.SilkS")
			(hide yes)
			(effects
				(font
					(size 1.27 1.27)
				)
			)
		)
		(property "Value" "1KR2F-3-GP"
			(at 0.064008 -3.993896 180)
			(unlocked yes)
			(layer "F.Fab")
			(hide yes)
			(effects
				(font
					(size 1.016 1.016)
					(thickness 0.1524)
				)
			)
		)
		(property "Device Type" "R402H16"
			(at 0.064008 -5.517896 180)
			(unlocked yes)
			(layer "F.Fab")
			(hide yes)
			(effects
				(font
					(size 1.016 1.016)
					(thickness 0.1524)
				)
			)
		)
		(duplicate_pad_numbers_are_jumpers no)
		(fp_line
			(start 0.508 -0.9398)
			(end -0.508 -0.9398)
			(stroke
				(width 0.1524)
				(type default)
			)
			(layer "F.SilkS")
		)
		(fp_line
			(start -0.508 -0.9398)
			(end -0.508 0.9398)
			(stroke
				(width 0.1524)
				(type default)
			)
			(layer "F.SilkS")
		)
		(fp_rect
			(start -0.508 0.9398)
			(end 0.508 -0.9398)
			(stroke
				(width 0)
				(type default)
			)
			(fill no)
			(layer "F.CrtYd")
		)
		(fp_rect
			(start -0.508 0.9398)
			(end 0.508 -0.9398)
			(stroke
				(width 0)
				(type default)
			)
			(fill no)
			(layer "F.Fab")
		)
		(pad "1" smd custom
			(at 0 -0.4445 180)
			(size 0.1397 0.1397)
			(layers "F.Cu" "F.Mask" "F.Paste")
			(net "P3V3_STBY_B")
			(options
				(clearance outline)
				(anchor circle)
			)
			(primitives
				(gr_poly
					(pts
						(arc
							(start -0.1778 -0.2794)
							(mid -0.249642 -0.249642)
							(end -0.2794 -0.1778)
						)
						(arc
							(start -0.2794 0.1778)
							(mid -0.249642 0.249642)
							(end -0.1778 0.2794)
						)
						(arc
							(start 0.1778 0.2794)
							(mid 0.249642 0.249642)
							(end 0.2794 0.1778)
						)
						(arc
							(start 0.2794 -0.1778)
							(mid 0.249642 -0.249642)
							(end 0.1778 -0.2794)
						)
					)
					(width 0)
					(fill yes)
				)
			)
		)
		(pad "2" smd custom
			(at 0 0.4445 180)
			(size 0.1397 0.1397)
			(layers "F.Cu" "F.Mask" "F.Paste")
			(net "SW_PWR_R_HDD21")
			(options
				(clearance outline)
				(anchor circle)
			)
			(primitives
				(gr_poly
					(pts
						(arc
							(start -0.1778 -0.2794)
							(mid -0.249642 -0.249642)
							(end -0.2794 -0.1778)
						)
						(arc
							(start -0.2794 0.1778)
							(mid -0.249642 0.249642)
							(end -0.1778 0.2794)
						)
						(arc
							(start 0.1778 0.2794)
							(mid 0.249642 0.249642)
							(end 0.2794 0.1778)
						)
						(arc
							(start 0.2794 -0.1778)
							(mid 0.249642 -0.249642)
							(end 0.1778 -0.2794)
						)
					)
					(width 0)
					(fill yes)
				)
			)
		)
	)
	(footprint ""
		(layer "F.Cu")
		(at 425.863004 -369.697 180)
		(property "Reference" "R953"
			(at 0 0 180)
			(layer "F.SilkS")
			(hide yes)
			(effects
				(font
					(size 1.27 1.27)
				)
			)
		)
		(property "Value" "4K7R2F-GP"
			(at 0.064008 -3.993896 180)
			(unlocked yes)
			(layer "F.Fab")
			(hide yes)
			(effects
				(font
					(size 1.016 1.016)
					(thickness 0.1524)
				)
			)
		)
		(property "Device Type" "R402H16"
			(at 0.064008 -5.517896 180)
			(unlocked yes)
			(layer "F.Fab")
			(hide yes)
			(effects
				(font
					(size 1.016 1.016)
					(thickness 0.1524)
				)
			)
		)
		(duplicate_pad_numbers_are_jumpers no)
		(fp_line
			(start 0.508 -0.9398)
			(end -0.508 -0.9398)
			(stroke
				(width 0.1524)
				(type default)
			)
			(layer "F.SilkS")
		)
		(fp_line
			(start -0.508 -0.9398)
			(end -0.508 0.9398)
			(stroke
				(width 0.1524)
				(type default)
			)
			(layer "F.SilkS")
		)
		(fp_rect
			(start -0.508 0.9398)
			(end 0.508 -0.9398)
			(stroke
				(width 0)
				(type default)
			)
			(fill no)
			(layer "F.CrtYd")
		)
		(fp_rect
			(start -0.508 0.9398)
			(end 0.508 -0.9398)
			(stroke
				(width 0)
				(type default)
			)
			(fill no)
			(layer "F.Fab")
		)
		(pad "1" smd custom
			(at 0 -0.4445 180)
			(size 0.1397 0.1397)
			(layers "F.Cu" "F.Mask" "F.Paste")
			(net "P12V_IN")
			(options
				(clearance outline)
				(anchor circle)
			)
			(primitives
				(gr_poly
					(pts
						(arc
							(start -0.1778 -0.2794)
							(mid -0.249642 -0.249642)
							(end -0.2794 -0.1778)
						)
						(arc
							(start -0.2794 0.1778)
							(mid -0.249642 0.249642)
							(end -0.1778 0.2794)
						)
						(arc
							(start 0.1778 0.2794)
							(mid 0.249642 0.249642)
							(end 0.2794 0.1778)
						)
						(arc
							(start 0.2794 -0.1778)
							(mid 0.249642 -0.249642)
							(end 0.1778 -0.2794)
						)
					)
					(width 0)
					(fill yes)
				)
			)
		)
		(pad "2" smd custom
			(at 0 0.4445 180)
			(size 0.1397 0.1397)
			(layers "F.Cu" "F.Mask" "F.Paste")
			(net "FAN_3_TACH0")
			(options
				(clearance outline)
				(anchor circle)
			)
			(primitives
				(gr_poly
					(pts
						(arc
							(start -0.1778 -0.2794)
							(mid -0.249642 -0.249642)
							(end -0.2794 -0.1778)
						)
						(arc
							(start -0.2794 0.1778)
							(mid -0.249642 0.249642)
							(end -0.1778 0.2794)
						)
						(arc
							(start 0.1778 0.2794)
							(mid 0.249642 0.249642)
							(end 0.2794 0.1778)
						)
						(arc
							(start 0.2794 -0.1778)
							(mid 0.249642 -0.249642)
							(end 0.1778 -0.2794)
						)
					)
					(width 0)
					(fill yes)
				)
			)
		)
	)
	(footprint ""
		(layer "F.Cu")
		(at 364.998 -160.02 180)
		(property "Reference" "C283"
			(at 0 0 180)
			(layer "F.SilkS")
			(hide yes)
			(effects
				(font
					(size 1.27 1.27)
				)
			)
		)
		(property "Value" "SC4D7U25V5KX-1-GP"
			(at -0.0762 -6.1214 180)
			(unlocked yes)
			(layer "F.Fab")
			(hide yes)
			(effects
				(font
					(size 1.016 1.016)
					(thickness 0.1524)
				)
			)
		)
		(property "Device Type" "C805H58"
			(at -0.0762 -8.1534 180)
			(unlocked yes)
			(layer "F.Fab")
			(hide yes)
			(effects
				(font
					(size 1.016 1.016)
					(thickness 0.1524)
				)
			)
		)
		(duplicate_pad_numbers_are_jumpers no)
		(fp_line
			(start 0.635 0)
			(end -0.635 0)
			(stroke
				(width 0.508)
				(type default)
			)
			(layer "F.SilkS")
		)
		(fp_rect
			(start -0.9652 1.778)
			(end 0.9652 -1.778)
			(stroke
				(width 0)
				(type default)
			)
			(fill no)
			(layer "F.CrtYd")
		)
		(fp_poly
			(pts
				(xy -0.9652 -1.778) (xy 0.9652 -1.778) (xy 0.9652 1.778) (xy -0.9652 1.778)
			)
			(stroke
				(width 0)
				(type default)
			)
			(fill no)
			(layer "F.Fab")
		)
		(pad "1" smd rect
			(at 0 -0.9652 180)
			(size 1.397 1.143)
			(layers "F.Cu" "F.Mask" "F.Paste")
			(net "P12V_HDD19")
		)
		(pad "2" smd rect
			(at 0 0.9652 180)
			(size 1.397 1.143)
			(layers "F.Cu" "F.Mask" "F.Paste")
			(net "GND")
		)
	)
	(footprint ""
		(layer "F.Cu")
		(at 346.700094 -65.39992)
		(property "Reference" "LED20"
			(at 0 0 0)
			(layer "F.SilkS")
			(hide yes)
			(effects
				(font
					(size 1.27 1.27)
				)
			)
		)
		(property "Value" "LED-BY-19-GP"
			(at -2.132076 1.414018 0)
			(unlocked yes)
			(layer "F.Fab")
			(hide yes)
			(effects
				(font
					(size 1.016 1.016)
					(thickness 0.1524)
				)
			)
		)
		(property "Device Type" "LED-1615-4PH26"
			(at -2.132076 -0.109982 0)
			(unlocked yes)
			(layer "F.Fab")
			(hide yes)
			(effects
				(font
					(size 1.016 1.016)
					(thickness 0.1524)
				)
			)
		)
		(duplicate_pad_numbers_are_jumpers no)
		(fp_line
			(start -1.2954 0.254)
			(end -1.2954 1.6002)
			(stroke
				(width 0.508)
				(type default)
			)
			(layer "F.SilkS")
		)
		(fp_line
			(start -1.2954 1.6002)
			(end 1.2954 1.6002)
			(stroke
				(width 0.508)
				(type default)
			)
			(layer "F.SilkS")
		)
		(fp_line
			(start -1.1176 -1.4224)
			(end 1.1176 -1.4224)
			(stroke
				(width 0.1524)
				(type default)
			)
			(layer "F.SilkS")
		)
		(fp_line
			(start -1.1176 1.4224)
			(end -1.1176 -1.4224)
			(stroke
				(width 0.1524)
				(type default)
			)
			(layer "F.SilkS")
		)
		(fp_line
			(start 1.1176 -1.4224)
			(end 1.1176 1.4224)
			(stroke
				(width 0.1524)
				(type default)
			)
			(layer "F.SilkS")
		)
		(fp_line
			(start 1.1176 1.4224)
			(end -1.1176 1.4224)
			(stroke
				(width 0.1524)
				(type default)
			)
			(layer "F.SilkS")
		)
		(fp_line
			(start 1.2954 1.6002)
			(end 1.2954 0.254)
			(stroke
				(width 0.508)
				(type default)
			)
			(layer "F.SilkS")
		)
		(fp_rect
			(start -0.7493 0.8001)
			(end 0.7493 -0.8001)
			(stroke
				(width 0)
				(type default)
			)
			(fill no)
			(layer "F.CrtYd")
		)
		(fp_poly
			(pts
				(xy -1.3716 1.6764) (xy -1.3716 -1.6764) (xy 1.3716 -1.6764) (xy 1.3716 0.0635) (xy 0.7493 0.0635)
				(xy 0.7493 -0.8001) (xy -0.7493 -0.8001) (xy -0.7493 0.8001) (xy 0.7493 0.8001) (xy 0.7493 0.0762)
				(xy 1.3716 0.0762) (xy 1.3716 1.6764)
			)
			(stroke
				(width 0)
				(type default)
			)
			(fill no)
			(layer "F.CrtYd")
		)
		(fp_rect
			(start -1.3716 1.6764)
			(end 1.3716 -1.6764)
			(stroke
				(width 0)
				(type default)
			)
			(fill no)
			(layer "F.Fab")
		)
		(pad "1" smd rect
			(at 0.50038 -0.73025)
			(size 0.7112 0.8636)
			(layers "F.Cu" "F.Mask" "F.Paste")
			(net "DRV_ACT_19")
		)
		(pad "2" smd rect
			(at -0.50038 -0.73025)
			(size 0.7112 0.8636)
			(layers "F.Cu" "F.Mask" "F.Paste")
			(net "FLT_HDD19")
		)
		(pad "3" smd rect
			(at 0.50038 0.73025)
			(size 0.7112 0.8636)
			(layers "F.Cu" "F.Mask" "F.Paste")
			(net "DRV_ACT_19_N")
		)
		(pad "4" smd rect
			(at -0.50038 0.73025)
			(size 0.7112 0.8636)
			(layers "F.Cu" "F.Mask" "F.Paste")
			(net "FLT_HDD19_N")
		)
	)
	(footprint ""
		(layer "F.Cu")
		(at 172.466 -35.687 -90)
		(property "Reference" "C411"
			(at 0 0 270)
			(layer "F.SilkS")
			(hide yes)
			(effects
				(font
					(size 1.27 1.27)
				)
			)
		)
		(property "Value" "SC4D7U25V5KX-1-GP"
			(at -0.0762 -6.1214 270)
			(unlocked yes)
			(layer "F.Fab")
			(hide yes)
			(effects
				(font
					(size 1.016 1.016)
					(thickness 0.1524)
				)
			)
		)
		(property "Device Type" "C805H58"
			(at -0.0762 -8.1534 270)
			(unlocked yes)
			(layer "F.Fab")
			(hide yes)
			(effects
				(font
					(size 1.016 1.016)
					(thickness 0.1524)
				)
			)
		)
		(duplicate_pad_numbers_are_jumpers no)
		(fp_line
			(start 0.635 0)
			(end -0.635 0)
			(stroke
				(width 0.508)
				(type default)
			)
			(layer "F.SilkS")
		)
		(fp_rect
			(start -0.9652 1.778)
			(end 0.9652 -1.778)
			(stroke
				(width 0)
				(type default)
			)
			(fill no)
			(layer "F.CrtYd")
		)
		(fp_poly
			(pts
				(xy -0.9652 -1.778) (xy 0.9652 -1.778) (xy 0.9652 1.778) (xy -0.9652 1.778)
			)
			(stroke
				(width 0)
				(type default)
			)
			(fill no)
			(layer "F.Fab")
		)
		(pad "1" smd rect
			(at 0 -0.9652 270)
			(size 1.397 1.143)
			(layers "F.Cu" "F.Mask" "F.Paste")
			(net "P12V_HDD29")
		)
		(pad "2" smd rect
			(at 0 0.9652 270)
			(size 1.397 1.143)
			(layers "F.Cu" "F.Mask" "F.Paste")
			(net "GND")
		)
	)
	(footprint ""
		(layer "F.Cu")
		(at 414.436052 -13.6271 180)
		(property "Reference" "VIA67"
			(at 0 0 180)
			(layer "F.SilkS")
			(hide yes)
			(effects
				(font
					(size 1.27 1.27)
				)
			)
		)
		(property "Value" "100OHM-8L-2D36MM-L18-GP"
			(at 3.8989 0.5715 180)
			(unlocked yes)
			(layer "F.Fab")
			(hide yes)
			(effects
				(font
					(size 1.016 1.016)
					(thickness 0.1524)
				)
			)
		)
		(property "Device Type" "VIA-PCIE-4P-414097"
			(at 3.8989 -0.9525 180)
			(unlocked yes)
			(layer "F.Fab")
			(hide yes)
			(effects
				(font
					(size 1.016 1.016)
					(thickness 0.1524)
				)
			)
		)
		(duplicate_pad_numbers_are_jumpers no)
		(fp_rect
			(start -2.0701 0.4826)
			(end 2.0701 -0.4826)
			(stroke
				(width 0)
				(type default)
			)
			(fill no)
			(layer "F.CrtYd")
		)
		(fp_rect
			(start -2.0701 0.4826)
			(end 2.0701 -0.4826)
			(stroke
				(width 0)
				(type default)
			)
			(fill no)
			(layer "F.Fab")
		)
		(pad "1" thru_hole circle
			(at -1.5875 0 180)
			(size 0.508 0.508)
			(drill 0.254)
			(layers "*.Cu" "*.Mask")
			(remove_unused_layers no)
			(net "GND")
			(clearance 0.2286)
			(thermal_gap 0.2286)
		)
		(pad "2" thru_hole circle
			(at -0.5715 0 180)
			(size 0.508 0.508)
			(drill 0.254)
			(layers "*.Cu" "*.Mask")
			(remove_unused_layers no)
			(net "PHY_SCC_B_TO_DRV_B_33_DP")
			(clearance 0.2286)
			(thermal_gap 0.2286)
		)
		(pad "3" thru_hole circle
			(at 0.5715 0 180)
			(size 0.508 0.508)
			(drill 0.254)
			(layers "*.Cu" "*.Mask")
			(remove_unused_layers no)
			(net "PHY_SCC_B_TO_DRV_B_33_DN")
			(clearance 0.2286)
			(thermal_gap 0.2286)
		)
		(pad "4" thru_hole circle
			(at 1.5875 0 180)
			(size 0.508 0.508)
			(drill 0.254)
			(layers "*.Cu" "*.Mask")
			(remove_unused_layers no)
			(net "GND")
			(clearance 0.2286)
			(thermal_gap 0.2286)
		)
	)
	(footprint ""
		(layer "F.Cu")
		(at 449.5165 -17.4371)
		(property "Reference" "VIA70"
			(at 0 0 0)
			(layer "F.SilkS")
			(hide yes)
			(effects
				(font
					(size 1.27 1.27)
				)
			)
		)
		(property "Value" "100OHM-8L-2D36MM-L16-GP"
			(at -3.4036 -0.4572 0)
			(unlocked yes)
			(layer "F.Fab")
			(hide yes)
			(effects
				(font
					(size 1.016 1.016)
					(thickness 0.1524)
				)
			)
		)
		(property "Device Type" "VIA-PCIE-4P-427097"
			(at -3.4036 -1.9812 0)
			(unlocked yes)
			(layer "F.Fab")
			(hide yes)
			(effects
				(font
					(size 1.016 1.016)
					(thickness 0.1524)
				)
			)
		)
		(duplicate_pad_numbers_are_jumpers no)
		(fp_rect
			(start -2.1336 0.4826)
			(end 2.1336 -0.4826)
			(stroke
				(width 0)
				(type default)
			)
			(fill no)
			(layer "F.CrtYd")
		)
		(fp_rect
			(start -2.1336 0.4826)
			(end 2.1336 -0.4826)
			(stroke
				(width 0)
				(type default)
			)
			(fill no)
			(layer "F.Fab")
		)
		(pad "1" thru_hole circle
			(at -1.651 0)
			(size 0.508 0.508)
			(drill 0.254)
			(layers "*.Cu" "*.Mask")
			(remove_unused_layers no)
			(net "GND")
			(clearance 0.2286)
			(thermal_gap 0.2286)
		)
		(pad "2" thru_hole circle
			(at -0.635 0)
			(size 0.508 0.508)
			(drill 0.254)
			(layers "*.Cu" "*.Mask")
			(remove_unused_layers no)
			(net "PHY_DRV_B_TO_SCC_B_34_DP")
			(clearance 0.2286)
			(thermal_gap 0.2286)
		)
		(pad "3" thru_hole circle
			(at 0.635 0)
			(size 0.508 0.508)
			(drill 0.254)
			(layers "*.Cu" "*.Mask")
			(remove_unused_layers no)
			(net "PHY_DRV_B_TO_SCC_B_34_DN")
			(clearance 0.2286)
			(thermal_gap 0.2286)
		)
		(pad "4" thru_hole circle
			(at 1.651 0)
			(size 0.508 0.508)
			(drill 0.254)
			(layers "*.Cu" "*.Mask")
			(remove_unused_layers no)
			(net "GND")
			(clearance 0.2286)
			(thermal_gap 0.2286)
		)
	)
	(footprint ""
		(layer "F.Cu")
		(at 165.42893 -365.358426)
		(property "Reference" "C551"
			(at 0 0 0)
			(layer "F.SilkS")
			(hide yes)
			(effects
				(font
					(size 1.27 1.27)
				)
			)
		)
		(property "Value" "SC1U16V3KX-5GP"
			(at 0 -2.8194 0)
			(unlocked yes)
			(layer "F.Fab")
			(hide yes)
			(effects
				(font
					(size 1.016 1.016)
					(thickness 0.1524)
				)
			)
		)
		(property "Device Type" "C603H36"
			(at 0 -4.3434 0)
			(unlocked yes)
			(layer "F.Fab")
			(hide yes)
			(effects
				(font
					(size 1.016 1.016)
					(thickness 0.1524)
				)
			)
		)
		(duplicate_pad_numbers_are_jumpers no)
		(fp_line
			(start 0.508 0)
			(end -0.508 0)
			(stroke
				(width 0.2032)
				(type default)
			)
			(layer "F.SilkS")
		)
		(fp_rect
			(start -0.5842 1.3335)
			(end 0.5842 -1.3335)
			(stroke
				(width 0)
				(type default)
			)
			(fill no)
			(layer "F.CrtYd")
		)
		(fp_rect
			(start -0.5842 1.3335)
			(end 0.5842 -1.3335)
			(stroke
				(width 0)
				(type default)
			)
			(fill no)
			(layer "F.Fab")
		)
		(pad "1" smd custom
			(at 0 -0.762)
			(size 0.2159 0.2159)
			(layers "F.Cu" "F.Mask" "F.Paste")
			(net "MB0_CM_UV_R")
			(options
				(clearance outline)
				(anchor circle)
			)
			(primitives
				(gr_poly
					(pts
						(arc
							(start -0.3302 -0.4318)
							(mid -0.402042 -0.402042)
							(end -0.4318 -0.3302)
						)
						(arc
							(start -0.4318 0.3302)
							(mid -0.402042 0.402042)
							(end -0.3302 0.4318)
						)
						(arc
							(start 0.3302 0.4318)
							(mid 0.402042 0.402042)
							(end 0.4318 0.3302)
						)
						(arc
							(start 0.4318 -0.3302)
							(mid 0.402042 -0.402042)
							(end 0.3302 -0.4318)
						)
					)
					(width 0)
					(fill yes)
				)
			)
		)
		(pad "2" smd custom
			(at 0 0.762)
			(size 0.2159 0.2159)
			(layers "F.Cu" "F.Mask" "F.Paste")
			(net "AGND_CURRENT_MON")
			(options
				(clearance outline)
				(anchor circle)
			)
			(primitives
				(gr_poly
					(pts
						(arc
							(start -0.3302 -0.4318)
							(mid -0.402042 -0.402042)
							(end -0.4318 -0.3302)
						)
						(arc
							(start -0.4318 0.3302)
							(mid -0.402042 0.402042)
							(end -0.3302 0.4318)
						)
						(arc
							(start 0.3302 0.4318)
							(mid 0.402042 0.402042)
							(end 0.4318 0.3302)
						)
						(arc
							(start 0.4318 -0.3302)
							(mid 0.402042 -0.402042)
							(end 0.3302 -0.4318)
						)
					)
					(width 0)
					(fill yes)
				)
			)
		)
	)
	(footprint ""
		(layer "F.Cu")
		(at 43.07586 -115.389406 -90)
		(property "Reference" "R1133"
			(at 0 0 270)
			(layer "F.SilkS")
			(hide yes)
			(effects
				(font
					(size 1.27 1.27)
				)
			)
		)
		(property "Value" "309KR2F-GP"
			(at 0.064008 -3.993896 270)
			(unlocked yes)
			(layer "F.Fab")
			(hide yes)
			(effects
				(font
					(size 1.016 1.016)
					(thickness 0.1524)
				)
			)
		)
		(property "Device Type" "R402H16"
			(at 0.064008 -5.517896 270)
			(unlocked yes)
			(layer "F.Fab")
			(hide yes)
			(effects
				(font
					(size 1.016 1.016)
					(thickness 0.1524)
				)
			)
		)
		(duplicate_pad_numbers_are_jumpers no)
		(fp_line
			(start -0.508 -0.9398)
			(end -0.508 0.9398)
			(stroke
				(width 0.1524)
				(type default)
			)
			(layer "F.SilkS")
		)
		(fp_line
			(start 0.508 -0.9398)
			(end -0.508 -0.9398)
			(stroke
				(width 0.1524)
				(type default)
			)
			(layer "F.SilkS")
		)
		(fp_rect
			(start -0.508 0.9398)
			(end 0.508 -0.9398)
			(stroke
				(width 0)
				(type default)
			)
			(fill no)
			(layer "F.CrtYd")
		)
		(fp_rect
			(start -0.508 0.9398)
			(end 0.508 -0.9398)
			(stroke
				(width 0)
				(type default)
			)
			(fill no)
			(layer "F.Fab")
		)
		(pad "1" smd custom
			(at 0 -0.4445 270)
			(size 0.1397 0.1397)
			(layers "F.Cu" "F.Mask" "F.Paste")
			(net "P5V_B_2_RF")
			(options
				(clearance outline)
				(anchor circle)
			)
			(primitives
				(gr_poly
					(pts
						(arc
							(start -0.1778 -0.2794)
							(mid -0.249642 -0.249642)
							(end -0.2794 -0.1778)
						)
						(arc
							(start -0.2794 0.1778)
							(mid -0.249642 0.249642)
							(end -0.1778 0.2794)
						)
						(arc
							(start 0.1778 0.2794)
							(mid 0.249642 0.249642)
							(end 0.2794 0.1778)
						)
						(arc
							(start 0.2794 -0.1778)
							(mid 0.249642 -0.249642)
							(end 0.1778 -0.2794)
						)
					)
					(width 0)
					(fill yes)
				)
			)
		)
		(pad "2" smd custom
			(at 0 0.4445 270)
			(size 0.1397 0.1397)
			(layers "F.Cu" "F.Mask" "F.Paste")
			(net "P5V_B_2_VREG")
			(options
				(clearance outline)
				(anchor circle)
			)
			(primitives
				(gr_poly
					(pts
						(arc
							(start -0.1778 -0.2794)
							(mid -0.249642 -0.249642)
							(end -0.2794 -0.1778)
						)
						(arc
							(start -0.2794 0.1778)
							(mid -0.249642 0.249642)
							(end -0.1778 0.2794)
						)
						(arc
							(start 0.1778 0.2794)
							(mid 0.249642 0.249642)
							(end 0.2794 0.1778)
						)
						(arc
							(start 0.2794 -0.1778)
							(mid 0.249642 -0.249642)
							(end 0.1778 -0.2794)
						)
					)
					(width 0)
					(fill yes)
				)
			)
		)
	)
	(footprint ""
		(layer "F.Cu")
		(at 263.728962 -367.448846)
		(property "Reference" "R2"
			(at 0 0 0)
			(layer "F.SilkS")
			(hide yes)
			(effects
				(font
					(size 1.27 1.27)
				)
			)
		)
		(property "Value" "3K83R2F-GP"
			(at 0.064008 -3.993896 0)
			(unlocked yes)
			(layer "F.Fab")
			(hide yes)
			(effects
				(font
					(size 1.016 1.016)
					(thickness 0.1524)
				)
			)
		)
		(property "Device Type" "R402H16"
			(at 0.064008 -5.517896 0)
			(unlocked yes)
			(layer "F.Fab")
			(hide yes)
			(effects
				(font
					(size 1.016 1.016)
					(thickness 0.1524)
				)
			)
		)
		(duplicate_pad_numbers_are_jumpers no)
		(fp_line
			(start -0.508 -0.9398)
			(end -0.508 0.9398)
			(stroke
				(width 0.1524)
				(type default)
			)
			(layer "F.SilkS")
		)
		(fp_line
			(start 0.508 -0.9398)
			(end -0.508 -0.9398)
			(stroke
				(width 0.1524)
				(type default)
			)
			(layer "F.SilkS")
		)
		(fp_rect
			(start -0.508 0.9398)
			(end 0.508 -0.9398)
			(stroke
				(width 0)
				(type default)
			)
			(fill no)
			(layer "F.CrtYd")
		)
		(fp_rect
			(start -0.508 0.9398)
			(end 0.508 -0.9398)
			(stroke
				(width 0)
				(type default)
			)
			(fill no)
			(layer "F.Fab")
		)
		(pad "1" smd custom
			(at 0 -0.4445)
			(size 0.1397 0.1397)
			(layers "F.Cu" "F.Mask" "F.Paste")
			(net "DPB_PWR_BTN_BUF_B")
			(options
				(clearance outline)
				(anchor circle)
			)
			(primitives
				(gr_poly
					(pts
						(arc
							(start -0.1778 -0.2794)
							(mid -0.249642 -0.249642)
							(end -0.2794 -0.1778)
						)
						(arc
							(start -0.2794 0.1778)
							(mid -0.249642 0.249642)
							(end -0.1778 0.2794)
						)
						(arc
							(start 0.1778 0.2794)
							(mid 0.249642 0.249642)
							(end 0.2794 0.1778)
						)
						(arc
							(start 0.2794 -0.1778)
							(mid 0.249642 -0.249642)
							(end 0.1778 -0.2794)
						)
					)
					(width 0)
					(fill yes)
				)
			)
		)
		(pad "2" smd custom
			(at 0 0.4445)
			(size 0.1397 0.1397)
			(layers "F.Cu" "F.Mask" "F.Paste")
			(net "GND")
			(options
				(clearance outline)
				(anchor circle)
			)
			(primitives
				(gr_poly
					(pts
						(arc
							(start -0.1778 -0.2794)
							(mid -0.249642 -0.249642)
							(end -0.2794 -0.1778)
						)
						(arc
							(start -0.2794 0.1778)
							(mid -0.249642 0.249642)
							(end -0.1778 0.2794)
						)
						(arc
							(start 0.1778 0.2794)
							(mid 0.249642 0.249642)
							(end 0.2794 0.1778)
						)
						(arc
							(start 0.2794 -0.1778)
							(mid 0.249642 -0.249642)
							(end 0.1778 -0.2794)
						)
					)
					(width 0)
					(fill yes)
				)
			)
		)
	)
	(footprint ""
		(layer "F.Cu")
		(at 128.93548 -244.990874 90)
		(property "Reference" "VIA7"
			(at 0 0 90)
			(layer "F.SilkS")
			(hide yes)
			(effects
				(font
					(size 1.27 1.27)
				)
			)
		)
		(property "Value" "100OHM-8L-2D36MM-L18-GP"
			(at 3.8989 0.5715 90)
			(unlocked yes)
			(layer "F.Fab")
			(hide yes)
			(effects
				(font
					(size 1.016 1.016)
					(thickness 0.1524)
				)
			)
		)
		(property "Device Type" "VIA-PCIE-4P-414097"
			(at 3.8989 -0.9525 90)
			(unlocked yes)
			(layer "F.Fab")
			(hide yes)
			(effects
				(font
					(size 1.016 1.016)
					(thickness 0.1524)
				)
			)
		)
		(duplicate_pad_numbers_are_jumpers no)
		(fp_rect
			(start -2.0701 0.4826)
			(end 2.0701 -0.4826)
			(stroke
				(width 0)
				(type default)
			)
			(fill no)
			(layer "F.CrtYd")
		)
		(fp_rect
			(start -2.0701 0.4826)
			(end 2.0701 -0.4826)
			(stroke
				(width 0)
				(type default)
			)
			(fill no)
			(layer "F.Fab")
		)
		(pad "1" thru_hole circle
			(at -1.5875 0 90)
			(size 0.508 0.508)
			(drill 0.254)
			(layers "*.Cu" "*.Mask")
			(remove_unused_layers no)
			(net "GND")
			(clearance 0.2286)
			(thermal_gap 0.2286)
		)
		(pad "2" thru_hole circle
			(at -0.5715 0 90)
			(size 0.508 0.508)
			(drill 0.254)
			(layers "*.Cu" "*.Mask")
			(remove_unused_layers no)
			(net "PHY_SCC_B_TO_DRV_B_3_DP")
			(clearance 0.2286)
			(thermal_gap 0.2286)
		)
		(pad "3" thru_hole circle
			(at 0.5715 0 90)
			(size 0.508 0.508)
			(drill 0.254)
			(layers "*.Cu" "*.Mask")
			(remove_unused_layers no)
			(net "PHY_SCC_B_TO_DRV_B_3_DN")
			(clearance 0.2286)
			(thermal_gap 0.2286)
		)
		(pad "4" thru_hole circle
			(at 1.5875 0 90)
			(size 0.508 0.508)
			(drill 0.254)
			(layers "*.Cu" "*.Mask")
			(remove_unused_layers no)
			(net "GND")
			(clearance 0.2286)
			(thermal_gap 0.2286)
		)
	)
	(footprint ""
		(layer "F.Cu")
		(at 435.324504 -357.8098 90)
		(property "Reference" "R149"
			(at 0 0 90)
			(layer "F.SilkS")
			(hide yes)
			(effects
				(font
					(size 1.27 1.27)
				)
			)
		)
		(property "Value" "300KR2F-GP"
			(at 0.064008 -3.993896 90)
			(unlocked yes)
			(layer "F.Fab")
			(hide yes)
			(effects
				(font
					(size 1.016 1.016)
					(thickness 0.1524)
				)
			)
		)
		(property "Device Type" "R402H16"
			(at 0.064008 -5.517896 90)
			(unlocked yes)
			(layer "F.Fab")
			(hide yes)
			(effects
				(font
					(size 1.016 1.016)
					(thickness 0.1524)
				)
			)
		)
		(duplicate_pad_numbers_are_jumpers no)
		(fp_line
			(start 0.508 -0.9398)
			(end -0.508 -0.9398)
			(stroke
				(width 0.1524)
				(type default)
			)
			(layer "F.SilkS")
		)
		(fp_line
			(start -0.508 -0.9398)
			(end -0.508 0.9398)
			(stroke
				(width 0.1524)
				(type default)
			)
			(layer "F.SilkS")
		)
		(fp_rect
			(start -0.508 0.9398)
			(end 0.508 -0.9398)
			(stroke
				(width 0)
				(type default)
			)
			(fill no)
			(layer "F.CrtYd")
		)
		(fp_rect
			(start -0.508 0.9398)
			(end 0.508 -0.9398)
			(stroke
				(width 0)
				(type default)
			)
			(fill no)
			(layer "F.Fab")
		)
		(pad "1" smd custom
			(at 0 -0.4445 90)
			(size 0.1397 0.1397)
			(layers "F.Cu" "F.Mask" "F.Paste")
			(net "GATE_FAN3_R")
			(options
				(clearance outline)
				(anchor circle)
			)
			(primitives
				(gr_poly
					(pts
						(arc
							(start -0.1778 -0.2794)
							(mid -0.249642 -0.249642)
							(end -0.2794 -0.1778)
						)
						(arc
							(start -0.2794 0.1778)
							(mid -0.249642 0.249642)
							(end -0.1778 0.2794)
						)
						(arc
							(start 0.1778 0.2794)
							(mid 0.249642 0.249642)
							(end 0.2794 0.1778)
						)
						(arc
							(start 0.2794 -0.1778)
							(mid 0.249642 -0.249642)
							(end 0.1778 -0.2794)
						)
					)
					(width 0)
					(fill yes)
				)
			)
		)
		(pad "2" smd custom
			(at 0 0.4445 90)
			(size 0.1397 0.1397)
			(layers "F.Cu" "F.Mask" "F.Paste")
			(net "P12V_IN")
			(options
				(clearance outline)
				(anchor circle)
			)
			(primitives
				(gr_poly
					(pts
						(arc
							(start -0.1778 -0.2794)
							(mid -0.249642 -0.249642)
							(end -0.2794 -0.1778)
						)
						(arc
							(start -0.2794 0.1778)
							(mid -0.249642 0.249642)
							(end -0.1778 0.2794)
						)
						(arc
							(start 0.1778 0.2794)
							(mid 0.249642 0.249642)
							(end 0.2794 0.1778)
						)
						(arc
							(start 0.2794 -0.1778)
							(mid 0.249642 -0.249642)
							(end 0.1778 -0.2794)
						)
					)
					(width 0)
					(fill yes)
				)
			)
		)
	)
	(footprint ""
		(layer "F.Cu")
		(at 341.300054 -13.999972)
		(property "Reference" ""
			(at 0 0 0)
			(layer "F.SilkS")
			(hide yes)
			(effects
				(font
					(size 1.27 1.27)
				)
			)
		)
		(property "Value" "*"
			(at -6.3373 -0.4572 0)
			(unlocked yes)
			(layer "F.Fab")
			(hide yes)
			(effects
				(font
					(size 1.016 1.016)
					(thickness 0.1524)
				)
			)
		)
		(duplicate_pad_numbers_are_jumpers no)
		(fp_poly
			(pts
				(arc
					(start 5.0673 0)
					(mid -5.0673 0)
					(end 5.0673 0)
				)
			)
			(stroke
				(width 0)
				(type default)
			)
			(fill no)
			(layer "B.CrtYd")
		)
		(fp_poly
			(pts
				(arc
					(start 5.0673 0)
					(mid -5.0673 0)
					(end 5.0673 0)
				)
			)
			(stroke
				(width 0)
				(type default)
			)
			(fill no)
			(layer "F.CrtYd")
		)
		(fp_poly
			(pts
				(arc
					(start 5.0673 0)
					(mid -5.0673 0)
					(end 5.0673 0)
				)
			)
			(stroke
				(width 0)
				(type default)
			)
			(fill no)
			(layer "B.Fab")
		)
		(fp_poly
			(pts
				(arc
					(start 5.0673 0)
					(mid -5.0673 0)
					(end 5.0673 0)
				)
			)
			(stroke
				(width 0)
				(type default)
			)
			(fill no)
			(layer "F.Fab")
		)
		(pad "1" thru_hole circle
			(at 0 0)
			(size 9.525 9.525)
			(drill 3.556)
			(layers "*.Cu" "*.Mask")
			(remove_unused_layers no)
			(net "Net_34")
			(clearance -2.4765)
			(thermal_gap 0.3048)
			(padstack
				(mode front_inner_back)
				(layer "Inner"
					(shape circle)
					(size 3.9624 3.9624)
					(clearance 0.3048)
				)
				(layer "B.Cu"
					(shape circle)
					(size 9.525 9.525)
					(clearance -2.4765)
				)
			)
		)
		(zone
			(layers "F.Cu" "B.Cu" "In1.Cu" "In2.Cu" "In3.Cu" "In4.Cu" "In5.Cu" "In6.Cu")
			(hatch none 0.5)
			(connect_pads
				(clearance 0)
			)
			(min_thickness 0.25)
			(keepout
				(tracks not_allowed)
				(vias allowed)
				(pads allowed)
				(copperpour not_allowed)
				(footprints allowed)
			)
			(placement
				(enabled no)
				(sheetname "")
			)
			(fill
				(thermal_gap 0.5)
				(thermal_bridge_width 0.5)
				(island_removal_mode 0)
			)
			(polygon
				(pts
					(arc
						(start 346.062554 -13.999972)
						(mid 336.537554 -13.999972)
						(end 346.062554 -13.999972)
					)
				)
			)
		)
	)
	(footprint ""
		(layer "F.Cu")
		(at 102.708202 -361.530392 90)
		(property "Reference" "D45"
			(at 0 0 90)
			(layer "F.SilkS")
			(hide yes)
			(effects
				(font
					(size 1.27 1.27)
				)
			)
		)
		(property "Value" "SMCJ14A-13-F-GP"
			(at -4.445 1.1684 90)
			(unlocked yes)
			(layer "F.Fab")
			(hide yes)
			(effects
				(font
					(size 1.016 1.016)
					(thickness 0.1524)
				)
			)
		)
		(property "Device Type" "D795930AKH104"
			(at -4.445 -0.3556 90)
			(unlocked yes)
			(layer "F.Fab")
			(hide yes)
			(effects
				(font
					(size 1.016 1.016)
					(thickness 0.1524)
				)
			)
		)
		(duplicate_pad_numbers_are_jumpers no)
		(fp_line
			(start 3.2004 -4.8641)
			(end -3.2004 -4.8641)
			(stroke
				(width 0.1524)
				(type default)
			)
			(layer "F.SilkS")
		)
		(fp_line
			(start -3.2004 -4.8641)
			(end -3.2004 4.8641)
			(stroke
				(width 0.1524)
				(type default)
			)
			(layer "F.SilkS")
		)
		(fp_line
			(start 3.2004 4.8641)
			(end 3.2004 -4.8641)
			(stroke
				(width 0.1524)
				(type default)
			)
			(layer "F.SilkS")
		)
		(fp_line
			(start -3.2004 4.8641)
			(end 3.2004 4.8641)
			(stroke
				(width 0.1524)
				(type default)
			)
			(layer "F.SilkS")
		)
		(fp_line
			(start 3.2004 5.0419)
			(end -3.2004 5.0419)
			(stroke
				(width 0.508)
				(type default)
			)
			(layer "F.SilkS")
		)
		(fp_poly
			(pts
				(xy -2.9464 3.429) (xy -1.4859 3.429) (xy -1.4859 3.9751) (xy 1.4859 3.9751) (xy 1.4859 3.429) (xy 2.9464 3.429)
				(xy 2.9464 -3.429) (xy 1.4859 -3.429) (xy 1.4859 -3.9751) (xy -1.4859 -3.9751) (xy -1.4859 -3.429)
				(xy -2.9464 -3.429)
			)
			(stroke
				(width 0)
				(type default)
			)
			(fill no)
			(layer "F.CrtYd")
		)
		(fp_poly
			(pts
				(xy -3.4544 4.9403) (xy -3.4544 -4.9403) (xy 3.4544 -4.9403) (xy 3.4544 -3.429) (xy 1.4859 -3.429)
				(xy 1.4859 -3.9751) (xy -1.4859 -3.9751) (xy -1.4859 -3.429) (xy -2.9464 -3.429) (xy -2.9464 3.429)
				(xy -1.4859 3.429) (xy -1.4859 3.9751) (xy 1.4859 3.9751) (xy 1.4859 3.429) (xy 2.9464 3.429) (xy 2.9464 -3.4163)
				(xy 3.4544 -3.4163) (xy 3.4544 4.9403)
			)
			(stroke
				(width 0)
				(type default)
			)
			(fill no)
			(layer "F.CrtYd")
		)
		(fp_rect
			(start -3.4544 4.9403)
			(end 3.4544 -4.9403)
			(stroke
				(width 0)
				(type default)
			)
			(fill no)
			(layer "F.Fab")
		)
		(pad "A" smd rect
			(at 0 -3.592068 90)
			(size 3.2258 2.032)
			(layers "F.Cu" "F.Mask" "F.Paste")
			(net "GND")
		)
		(pad "K" smd rect
			(at 0 3.592068 90)
			(size 3.2258 2.032)
			(layers "F.Cu" "F.Mask" "F.Paste")
			(net "P12V_CLIP")
		)
	)
	(footprint ""
		(layer "F.Cu")
		(at 241.698526 -355.963728 180)
		(property "Reference" "C557"
			(at 0 0 180)
			(layer "F.SilkS")
			(hide yes)
			(effects
				(font
					(size 1.27 1.27)
				)
			)
		)
		(property "Value" "SCD015U25V2KX-GP"
			(at 1.1811 -2.7051 180)
			(unlocked yes)
			(layer "F.Fab")
			(hide yes)
			(effects
				(font
					(size 1.016 1.016)
					(thickness 0.1524)
				)
			)
		)
		(property "Device Type" "C402H22"
			(at 1.1811 -4.2291 180)
			(unlocked yes)
			(layer "F.Fab")
			(hide yes)
			(effects
				(font
					(size 1.016 1.016)
					(thickness 0.1524)
				)
			)
		)
		(duplicate_pad_numbers_are_jumpers no)
		(fp_rect
			(start -0.4318 0.9525)
			(end 0.4318 -0.9525)
			(stroke
				(width 0)
				(type default)
			)
			(fill no)
			(layer "F.CrtYd")
		)
		(fp_rect
			(start -0.4318 0.9525)
			(end 0.4318 -0.9525)
			(stroke
				(width 0)
				(type default)
			)
			(fill no)
			(layer "F.Fab")
		)
		(pad "1" smd custom
			(at 0 -0.4445 180)
			(size 0.1524 0.1524)
			(layers "F.Cu" "F.Mask" "F.Paste")
			(net "MB3_CM_SENSE_P")
			(options
				(clearance outline)
				(anchor circle)
			)
			(primitives
				(gr_poly
					(pts
						(arc
							(start 0.3048 -0.2032)
							(mid 0.275042 -0.275042)
							(end 0.2032 -0.3048)
						)
						(arc
							(start -0.2032 -0.3048)
							(mid -0.275042 -0.275042)
							(end -0.3048 -0.2032)
						)
						(arc
							(start -0.3048 0.2032)
							(mid -0.275042 0.275042)
							(end -0.2032 0.3048)
						)
						(arc
							(start 0.2032 0.3048)
							(mid 0.275042 0.275042)
							(end 0.3048 0.2032)
						)
					)
					(width 0)
					(fill yes)
				)
			)
		)
		(pad "2" smd custom
			(at 0 0.4445 180)
			(size 0.1524 0.1524)
			(layers "F.Cu" "F.Mask" "F.Paste")
			(net "MB3_CM_SENSE_N")
			(options
				(clearance outline)
				(anchor circle)
			)
			(primitives
				(gr_poly
					(pts
						(arc
							(start 0.3048 -0.2032)
							(mid 0.275042 -0.275042)
							(end 0.2032 -0.3048)
						)
						(arc
							(start -0.2032 -0.3048)
							(mid -0.275042 -0.275042)
							(end -0.3048 -0.2032)
						)
						(arc
							(start -0.3048 0.2032)
							(mid -0.275042 0.275042)
							(end -0.2032 0.3048)
						)
						(arc
							(start 0.2032 0.3048)
							(mid 0.275042 0.275042)
							(end 0.3048 0.2032)
						)
					)
					(width 0)
					(fill yes)
				)
			)
		)
	)
	(footprint ""
		(layer "F.Cu")
		(at 49.068228 -117.166898 -90)
		(property "Reference" "R1124"
			(at 0 0 270)
			(layer "F.SilkS")
			(hide yes)
			(effects
				(font
					(size 1.27 1.27)
				)
			)
		)
		(property "Value" "15KR2F-GP"
			(at 0.064008 -3.993896 270)
			(unlocked yes)
			(layer "F.Fab")
			(hide yes)
			(effects
				(font
					(size 1.016 1.016)
					(thickness 0.1524)
				)
			)
		)
		(property "Device Type" "R402H16"
			(at 0.064008 -5.517896 270)
			(unlocked yes)
			(layer "F.Fab")
			(hide yes)
			(effects
				(font
					(size 1.016 1.016)
					(thickness 0.1524)
				)
			)
		)
		(duplicate_pad_numbers_are_jumpers no)
		(fp_line
			(start -0.508 -0.9398)
			(end -0.508 0.9398)
			(stroke
				(width 0.1524)
				(type default)
			)
			(layer "F.SilkS")
		)
		(fp_line
			(start 0.508 -0.9398)
			(end -0.508 -0.9398)
			(stroke
				(width 0.1524)
				(type default)
			)
			(layer "F.SilkS")
		)
		(fp_rect
			(start -0.508 0.9398)
			(end 0.508 -0.9398)
			(stroke
				(width 0)
				(type default)
			)
			(fill no)
			(layer "F.CrtYd")
		)
		(fp_rect
			(start -0.508 0.9398)
			(end 0.508 -0.9398)
			(stroke
				(width 0)
				(type default)
			)
			(fill no)
			(layer "F.Fab")
		)
		(pad "1" smd custom
			(at 0 -0.4445 270)
			(size 0.1397 0.1397)
			(layers "F.Cu" "F.Mask" "F.Paste")
			(net "P5V_B_2_PGOOD")
			(options
				(clearance outline)
				(anchor circle)
			)
			(primitives
				(gr_poly
					(pts
						(arc
							(start -0.1778 -0.2794)
							(mid -0.249642 -0.249642)
							(end -0.2794 -0.1778)
						)
						(arc
							(start -0.2794 0.1778)
							(mid -0.249642 0.249642)
							(end -0.1778 0.2794)
						)
						(arc
							(start 0.1778 0.2794)
							(mid 0.249642 0.249642)
							(end 0.2794 0.1778)
						)
						(arc
							(start 0.2794 -0.1778)
							(mid 0.249642 -0.249642)
							(end 0.1778 -0.2794)
						)
					)
					(width 0)
					(fill yes)
				)
			)
		)
		(pad "2" smd custom
			(at 0 0.4445 270)
			(size 0.1397 0.1397)
			(layers "F.Cu" "F.Mask" "F.Paste")
			(net "GND")
			(options
				(clearance outline)
				(anchor circle)
			)
			(primitives
				(gr_poly
					(pts
						(arc
							(start -0.1778 -0.2794)
							(mid -0.249642 -0.249642)
							(end -0.2794 -0.1778)
						)
						(arc
							(start -0.2794 0.1778)
							(mid -0.249642 0.249642)
							(end -0.1778 0.2794)
						)
						(arc
							(start 0.1778 0.2794)
							(mid 0.249642 0.249642)
							(end 0.2794 0.1778)
						)
						(arc
							(start 0.2794 -0.1778)
							(mid 0.249642 -0.249642)
							(end 0.1778 -0.2794)
						)
					)
					(width 0)
					(fill yes)
				)
			)
		)
	)
	(footprint ""
		(layer "F.Cu")
		(at 354.866702 -132.437124)
		(property "Reference" "VIA40"
			(at 0 0 0)
			(layer "F.SilkS")
			(hide yes)
			(effects
				(font
					(size 1.27 1.27)
				)
			)
		)
		(property "Value" "100OHM-8L-2D36MM-L16-GP"
			(at -3.4036 -0.4572 0)
			(unlocked yes)
			(layer "F.Fab")
			(hide yes)
			(effects
				(font
					(size 1.016 1.016)
					(thickness 0.1524)
				)
			)
		)
		(property "Device Type" "VIA-PCIE-4P-427097"
			(at -3.4036 -1.9812 0)
			(unlocked yes)
			(layer "F.Fab")
			(hide yes)
			(effects
				(font
					(size 1.016 1.016)
					(thickness 0.1524)
				)
			)
		)
		(duplicate_pad_numbers_are_jumpers no)
		(fp_rect
			(start -2.1336 0.4826)
			(end 2.1336 -0.4826)
			(stroke
				(width 0)
				(type default)
			)
			(fill no)
			(layer "F.CrtYd")
		)
		(fp_rect
			(start -2.1336 0.4826)
			(end 2.1336 -0.4826)
			(stroke
				(width 0)
				(type default)
			)
			(fill no)
			(layer "F.Fab")
		)
		(pad "1" thru_hole circle
			(at -1.651 0)
			(size 0.508 0.508)
			(drill 0.254)
			(layers "*.Cu" "*.Mask")
			(remove_unused_layers no)
			(net "GND")
			(clearance 0.2286)
			(thermal_gap 0.2286)
		)
		(pad "2" thru_hole circle
			(at -0.635 0)
			(size 0.508 0.508)
			(drill 0.254)
			(layers "*.Cu" "*.Mask")
			(remove_unused_layers no)
			(net "PHY_DRV_B_TO_SCC_B_19_DP")
			(clearance 0.2286)
			(thermal_gap 0.2286)
		)
		(pad "3" thru_hole circle
			(at 0.635 0)
			(size 0.508 0.508)
			(drill 0.254)
			(layers "*.Cu" "*.Mask")
			(remove_unused_layers no)
			(net "PHY_DRV_B_TO_SCC_B_19_DN")
			(clearance 0.2286)
			(thermal_gap 0.2286)
		)
		(pad "4" thru_hole circle
			(at 1.651 0)
			(size 0.508 0.508)
			(drill 0.254)
			(layers "*.Cu" "*.Mask")
			(remove_unused_layers no)
			(net "GND")
			(clearance 0.2286)
			(thermal_gap 0.2286)
		)
	)
	(footprint ""
		(layer "F.Cu")
		(at 428.2186 -270.5862 -90)
		(property "Reference" "R304"
			(at 0 0 270)
			(layer "F.SilkS")
			(hide yes)
			(effects
				(font
					(size 1.27 1.27)
				)
			)
		)
		(property "Value" "2R6F-GP"
			(at -0.0508 -4.8514 270)
			(unlocked yes)
			(layer "F.Fab")
			(hide yes)
			(effects
				(font
					(size 1.016 1.016)
					(thickness 0.1524)
				)
			)
		)
		(property "Device Type" "R1206H26"
			(at 0 -6.3754 270)
			(unlocked yes)
			(layer "F.Fab")
			(hide yes)
			(effects
				(font
					(size 1.016 1.016)
					(thickness 0.1524)
				)
			)
		)
		(duplicate_pad_numbers_are_jumpers no)
		(fp_line
			(start -1.016 2.2352)
			(end -1.016 -2.2352)
			(stroke
				(width 0.1524)
				(type default)
			)
			(layer "F.SilkS")
		)
		(fp_line
			(start 1.016 2.2352)
			(end -1.016 2.2352)
			(stroke
				(width 0.1524)
				(type default)
			)
			(layer "F.SilkS")
		)
		(fp_line
			(start -1.016 -2.2352)
			(end 1.016 -2.2352)
			(stroke
				(width 0.1524)
				(type default)
			)
			(layer "F.SilkS")
		)
		(fp_line
			(start 1.016 -2.2352)
			(end 1.016 2.2352)
			(stroke
				(width 0.1524)
				(type default)
			)
			(layer "F.SilkS")
		)
		(fp_rect
			(start -1.0922 2.3114)
			(end 1.0922 -2.3114)
			(stroke
				(width 0)
				(type default)
			)
			(fill no)
			(layer "F.CrtYd")
		)
		(fp_poly
			(pts
				(xy -1.0922 -2.3114) (xy 1.0922 -2.3114) (xy 1.0922 2.3114) (xy -1.0922 2.3114)
			)
			(stroke
				(width 0)
				(type default)
			)
			(fill no)
			(layer "F.Fab")
		)
		(pad "1" smd rect
			(at 0 -1.397 270)
			(size 1.651 1.27)
			(layers "F.Cu" "F.Mask" "F.Paste")
			(net "P12V_HDD9")
		)
		(pad "2" smd rect
			(at 0 1.397 270)
			(size 1.651 1.27)
			(layers "F.Cu" "F.Mask" "F.Paste")
			(net "12V_PRE_9")
		)
	)
	(footprint ""
		(layer "F.Cu")
		(at 454.717404 -371.8814)
		(property "Reference" "C713"
			(at 0 0 0)
			(layer "F.SilkS")
			(hide yes)
			(effects
				(font
					(size 1.27 1.27)
				)
			)
		)
		(property "Value" "SCD1U16V2KX-3GP"
			(at 1.1811 -2.7051 0)
			(unlocked yes)
			(layer "F.Fab")
			(hide yes)
			(effects
				(font
					(size 1.016 1.016)
					(thickness 0.1524)
				)
			)
		)
		(property "Device Type" "C402H22"
			(at 1.1811 -4.2291 0)
			(unlocked yes)
			(layer "F.Fab")
			(hide yes)
			(effects
				(font
					(size 1.016 1.016)
					(thickness 0.1524)
				)
			)
		)
		(duplicate_pad_numbers_are_jumpers no)
		(fp_rect
			(start -0.4318 0.9525)
			(end 0.4318 -0.9525)
			(stroke
				(width 0)
				(type default)
			)
			(fill no)
			(layer "F.CrtYd")
		)
		(fp_rect
			(start -0.4318 0.9525)
			(end 0.4318 -0.9525)
			(stroke
				(width 0)
				(type default)
			)
			(fill no)
			(layer "F.Fab")
		)
		(pad "1" smd custom
			(at 0 -0.4445)
			(size 0.1524 0.1524)
			(layers "F.Cu" "F.Mask" "F.Paste")
			(net "P3V3_IN")
			(options
				(clearance outline)
				(anchor circle)
			)
			(primitives
				(gr_poly
					(pts
						(arc
							(start 0.3048 -0.2032)
							(mid 0.275042 -0.275042)
							(end 0.2032 -0.3048)
						)
						(arc
							(start -0.2032 -0.3048)
							(mid -0.275042 -0.275042)
							(end -0.3048 -0.2032)
						)
						(arc
							(start -0.3048 0.2032)
							(mid -0.275042 0.275042)
							(end -0.2032 0.3048)
						)
						(arc
							(start 0.2032 0.3048)
							(mid 0.275042 0.275042)
							(end 0.3048 0.2032)
						)
					)
					(width 0)
					(fill yes)
				)
			)
		)
		(pad "2" smd custom
			(at 0 0.4445)
			(size 0.1524 0.1524)
			(layers "F.Cu" "F.Mask" "F.Paste")
			(net "GND")
			(options
				(clearance outline)
				(anchor circle)
			)
			(primitives
				(gr_poly
					(pts
						(arc
							(start 0.3048 -0.2032)
							(mid 0.275042 -0.275042)
							(end 0.2032 -0.3048)
						)
						(arc
							(start -0.2032 -0.3048)
							(mid -0.275042 -0.275042)
							(end -0.3048 -0.2032)
						)
						(arc
							(start -0.3048 0.2032)
							(mid -0.275042 0.275042)
							(end -0.2032 0.3048)
						)
						(arc
							(start 0.2032 0.3048)
							(mid 0.275042 0.275042)
							(end 0.3048 0.2032)
						)
					)
					(width 0)
					(fill yes)
				)
			)
		)
	)
	(footprint ""
		(layer "F.Cu")
		(at 459.74 -40.5638 -90)
		(property "Reference" "R853"
			(at 0 0 270)
			(layer "F.SilkS")
			(hide yes)
			(effects
				(font
					(size 1.27 1.27)
				)
			)
		)
		(property "Value" "2R6F-GP"
			(at -0.0508 -4.8514 270)
			(unlocked yes)
			(layer "F.Fab")
			(hide yes)
			(effects
				(font
					(size 1.016 1.016)
					(thickness 0.1524)
				)
			)
		)
		(property "Device Type" "R1206H26"
			(at 0 -6.3754 270)
			(unlocked yes)
			(layer "F.Fab")
			(hide yes)
			(effects
				(font
					(size 1.016 1.016)
					(thickness 0.1524)
				)
			)
		)
		(duplicate_pad_numbers_are_jumpers no)
		(fp_line
			(start -1.016 2.2352)
			(end -1.016 -2.2352)
			(stroke
				(width 0.1524)
				(type default)
			)
			(layer "F.SilkS")
		)
		(fp_line
			(start 1.016 2.2352)
			(end -1.016 2.2352)
			(stroke
				(width 0.1524)
				(type default)
			)
			(layer "F.SilkS")
		)
		(fp_line
			(start -1.016 -2.2352)
			(end 1.016 -2.2352)
			(stroke
				(width 0.1524)
				(type default)
			)
			(layer "F.SilkS")
		)
		(fp_line
			(start 1.016 -2.2352)
			(end 1.016 2.2352)
			(stroke
				(width 0.1524)
				(type default)
			)
			(layer "F.SilkS")
		)
		(fp_rect
			(start -1.0922 2.3114)
			(end 1.0922 -2.3114)
			(stroke
				(width 0)
				(type default)
			)
			(fill no)
			(layer "F.CrtYd")
		)
		(fp_poly
			(pts
				(xy -1.0922 -2.3114) (xy 1.0922 -2.3114) (xy 1.0922 2.3114) (xy -1.0922 2.3114)
			)
			(stroke
				(width 0)
				(type default)
			)
			(fill no)
			(layer "F.Fab")
		)
		(pad "1" smd rect
			(at 0 -1.397 270)
			(size 1.651 1.27)
			(layers "F.Cu" "F.Mask" "F.Paste")
			(net "P12V_HDD34")
		)
		(pad "2" smd rect
			(at 0 1.397 270)
			(size 1.651 1.27)
			(layers "F.Cu" "F.Mask" "F.Paste")
			(net "12V_PRE_34")
		)
	)
	(footprint ""
		(layer "F.Cu")
		(at 459.806802 -224.31375)
		(property "Reference" "R1139"
			(at 0 0 0)
			(layer "F.SilkS")
			(hide yes)
			(effects
				(font
					(size 1.27 1.27)
				)
			)
		)
		(property "Value" "0R3J-0-U-GP"
			(at -0.0254 -2.5146 0)
			(unlocked yes)
			(layer "F.Fab")
			(hide yes)
			(effects
				(font
					(size 1.016 1.016)
					(thickness 0.1524)
				)
			)
		)
		(property "Device Type" "R603H22"
			(at -0.0254 -4.0386 0)
			(unlocked yes)
			(layer "F.Fab")
			(hide yes)
			(effects
				(font
					(size 1.016 1.016)
					(thickness 0.1524)
				)
			)
		)
		(duplicate_pad_numbers_are_jumpers no)
		(fp_line
			(start -0.4826 0)
			(end -0.2032 0)
			(stroke
				(width 0.2032)
				(type default)
			)
			(layer "F.SilkS")
		)
		(fp_line
			(start 0.2032 0)
			(end 0.4826 0)
			(stroke
				(width 0.2032)
				(type default)
			)
			(layer "F.SilkS")
		)
		(fp_rect
			(start -0.5842 1.3335)
			(end 0.5842 -1.3335)
			(stroke
				(width 0)
				(type default)
			)
			(fill no)
			(layer "F.CrtYd")
		)
		(fp_rect
			(start -0.5842 1.3335)
			(end 0.5842 -1.3335)
			(stroke
				(width 0)
				(type default)
			)
			(fill no)
			(layer "F.Fab")
		)
		(pad "1" smd custom
			(at 0 -0.762)
			(size 0.2159 0.2159)
			(layers "F.Cu" "F.Mask" "F.Paste")
			(net "P5V_B_3_VBST")
			(options
				(clearance outline)
				(anchor circle)
			)
			(primitives
				(gr_poly
					(pts
						(arc
							(start -0.3302 -0.4318)
							(mid -0.402042 -0.402042)
							(end -0.4318 -0.3302)
						)
						(arc
							(start -0.4318 0.3302)
							(mid -0.402042 0.402042)
							(end -0.3302 0.4318)
						)
						(arc
							(start 0.3302 0.4318)
							(mid 0.402042 0.402042)
							(end 0.4318 0.3302)
						)
						(arc
							(start 0.4318 -0.3302)
							(mid 0.402042 -0.402042)
							(end 0.3302 -0.4318)
						)
					)
					(width 0)
					(fill yes)
				)
			)
		)
		(pad "2" smd custom
			(at 0 0.762)
			(size 0.2159 0.2159)
			(layers "F.Cu" "F.Mask" "F.Paste")
			(net "P5V_B_3_VBST_RC")
			(options
				(clearance outline)
				(anchor circle)
			)
			(primitives
				(gr_poly
					(pts
						(arc
							(start -0.3302 -0.4318)
							(mid -0.402042 -0.402042)
							(end -0.4318 -0.3302)
						)
						(arc
							(start -0.4318 0.3302)
							(mid -0.402042 0.402042)
							(end -0.3302 0.4318)
						)
						(arc
							(start 0.3302 0.4318)
							(mid 0.402042 0.402042)
							(end 0.4318 0.3302)
						)
						(arc
							(start 0.4318 -0.3302)
							(mid 0.402042 -0.402042)
							(end 0.3302 -0.4318)
						)
					)
					(width 0)
					(fill yes)
				)
			)
		)
	)
	(footprint ""
		(layer "F.Cu")
		(at 91.300046 -143.91005 -90)
		(property "Reference" "HDDSAS14"
			(at 0 0 270)
			(layer "F.SilkS")
			(hide yes)
			(effects
				(font
					(size 1.27 1.27)
				)
			)
		)
		(property "Value" "SKT-SAS15P-14P-45-GP"
			(at -20.7645 -8.9789 270)
			(unlocked yes)
			(layer "F.Fab")
			(hide yes)
			(effects
				(font
					(size 1.016 1.016)
					(thickness 0.1524)
				)
			)
		)
		(property "Device Type" "10120818-001C-TRLF"
			(at -20.7645 -10.5029 270)
			(unlocked yes)
			(layer "F.Fab")
			(hide yes)
			(effects
				(font
					(size 1.016 1.016)
					(thickness 0.1524)
				)
			)
		)
		(duplicate_pad_numbers_are_jumpers no)
		(fp_line
			(start 1.651 4.2926)
			(end 1.651 3.0099)
			(stroke
				(width 0.1524)
				(type default)
			)
			(layer "F.SilkS")
		)
		(fp_line
			(start 8.509 4.2926)
			(end 1.651 4.2926)
			(stroke
				(width 0.1524)
				(type default)
			)
			(layer "F.SilkS")
		)
		(fp_line
			(start -23.4188 3.0099)
			(end -23.4188 -3.2512)
			(stroke
				(width 0.1524)
				(type default)
			)
			(layer "F.SilkS")
		)
		(fp_line
			(start 1.651 3.0099)
			(end -23.4188 3.0099)
			(stroke
				(width 0.1524)
				(type default)
			)
			(layer "F.SilkS")
		)
		(fp_line
			(start 8.509 3.0099)
			(end 8.509 4.2926)
			(stroke
				(width 0.1524)
				(type default)
			)
			(layer "F.SilkS")
		)
		(fp_line
			(start 23.4188 3.0099)
			(end 8.509 3.0099)
			(stroke
				(width 0.1524)
				(type default)
			)
			(layer "F.SilkS")
		)
		(fp_line
			(start -23.4188 -3.2512)
			(end 23.4188 -3.2512)
			(stroke
				(width 0.1524)
				(type default)
			)
			(layer "F.SilkS")
		)
		(fp_line
			(start 23.4188 -3.2512)
			(end 23.4188 3.0099)
			(stroke
				(width 0.1524)
				(type default)
			)
			(layer "F.SilkS")
		)
		(fp_line
			(start 15.5067 -3.3401)
			(end 16.2687 -3.3401)
			(stroke
				(width 0.3302)
				(type default)
			)
			(layer "F.SilkS")
		)
		(fp_poly
			(pts
				(xy 15.868904 -3.230372) (xy 16.503904 -3.865372) (xy 15.233904 -3.865372)
			)
			(stroke
				(width 0)
				(type default)
			)
			(fill yes)
			(layer "F.SilkS")
		)
		(fp_poly
			(pts
				(xy -22.8727 -2.7559) (xy 22.8727 -2.7559) (xy 22.8727 2.7559) (xy 8.255 2.7559) (xy 8.255 3.5179)
				(xy 1.905 3.5179) (xy 1.905 2.7559) (xy -22.8727 2.7559)
			)
			(stroke
				(width 0)
				(type default)
			)
			(fill no)
			(layer "F.CrtYd")
		)
		(fp_poly
			(pts
				(xy 1.397 4.5466) (xy 1.397 3.2639) (xy -23.6728 3.2639) (xy -23.6728 -3.5052) (xy 23.6728 -3.5052)
				(xy 23.6728 -0.00635) (xy 22.8727 -0.00635) (xy 22.8727 -2.7559) (xy -22.8727 -2.7559) (xy -22.8727 2.7559)
				(xy 1.905 2.7559) (xy 1.905 3.5179) (xy 8.255 3.5179) (xy 8.255 2.7559) (xy 22.8727 2.7559) (xy 22.8727 0.00635)
				(xy 23.6728 0.00635) (xy 23.6728 3.2639) (xy 8.763 3.2639) (xy 8.763 4.5466)
			)
			(stroke
				(width 0)
				(type default)
			)
			(fill no)
			(layer "F.CrtYd")
		)
		(fp_poly
			(pts
				(xy 1.397 4.5466) (xy 1.397 3.2639) (xy -23.6728 3.2639) (xy -23.6728 -3.5052) (xy 23.6728 -3.5052)
				(xy 23.6728 3.2639) (xy 8.763 3.2639) (xy 8.763 4.5466)
			)
			(stroke
				(width 0)
				(type default)
			)
			(fill no)
			(layer "F.Fab")
		)
		(pad "" np_thru_hole circle
			(at -18.874994 0 270)
			(size 0.254 0.254)
			(drill 1.3462)
			(layers "*.Cu" "*.Mask")
			(clearance 0.9017)
			(thermal_gap 0.9017)
		)
		(pad "" np_thru_hole circle
			(at 18.874994 0 270)
			(size 0.254 0.254)
			(drill 0.9398)
			(layers "*.Cu" "*.Mask")
			(clearance 0.6985)
			(thermal_gap 0.6985)
		)
		(pad "G1" smd rect
			(at 21.874988 0 270)
			(size 2.5908 2.5908)
			(layers "F.Cu" "F.Mask" "F.Paste")
			(net "GND")
		)
		(pad "G2" smd rect
			(at -21.874988 0 270)
			(size 2.5908 2.5908)
			(layers "F.Cu" "F.Mask" "F.Paste")
			(net "GND")
		)
		(pad "P1" smd rect
			(at 1.905 -1.82499 270)
			(size 0.6096 2.3622)
			(layers "F.Cu" "F.Mask" "F.Paste")
			(net "Net_1734")
		)
		(pad "P2" smd rect
			(at 0.635 -1.82499 270)
			(size 0.6096 2.3622)
			(layers "F.Cu" "F.Mask" "F.Paste")
			(net "Net_1735")
		)
		(pad "P3" smd rect
			(at -0.635 -1.82499 270)
			(size 0.6096 2.3622)
			(layers "F.Cu" "F.Mask" "F.Paste")
			(net "Net_1736")
		)
		(pad "P4" smd rect
			(at -1.905 -1.82499 270)
			(size 0.6096 2.3622)
			(layers "F.Cu" "F.Mask" "F.Paste")
			(net "GND")
		)
		(pad "P5" smd rect
			(at -3.175 -1.82499 270)
			(size 0.6096 2.3622)
			(layers "F.Cu" "F.Mask" "F.Paste")
			(net "HDD_PRSNT_14")
		)
		(pad "P6" smd rect
			(at -4.445 -1.82499 270)
			(size 0.6096 2.3622)
			(layers "F.Cu" "F.Mask" "F.Paste")
			(net "GND")
		)
		(pad "P7" smd rect
			(at -5.715 -1.82499 270)
			(size 0.6096 2.3622)
			(layers "F.Cu" "F.Mask" "F.Paste")
			(net "5V_PRE_14")
		)
		(pad "P8" smd rect
			(at -6.985 -1.82499 270)
			(size 0.6096 2.3622)
			(layers "F.Cu" "F.Mask" "F.Paste")
			(net "P5V_HDD14")
		)
		(pad "P9" smd rect
			(at -8.255 -1.82499 270)
			(size 0.6096 2.3622)
			(layers "F.Cu" "F.Mask" "F.Paste")
			(net "P5V_HDD14")
		)
		(pad "P10" smd rect
			(at -9.525 -1.82499 270)
			(size 0.6096 2.3622)
			(layers "F.Cu" "F.Mask" "F.Paste")
			(net "GND")
		)
		(pad "P11" smd rect
			(at -10.795 -1.82499 270)
			(size 0.6096 2.3622)
			(layers "F.Cu" "F.Mask" "F.Paste")
			(net "ACT_HDD_14")
		)
		(pad "P12" smd rect
			(at -12.065 -1.82499 270)
			(size 0.6096 2.3622)
			(layers "F.Cu" "F.Mask" "F.Paste")
			(net "GND")
		)
		(pad "P13" smd rect
			(at -13.335 -1.82499 270)
			(size 0.6096 2.3622)
			(layers "F.Cu" "F.Mask" "F.Paste")
			(net "12V_PRE_14")
		)
		(pad "P14" smd rect
			(at -14.605 -1.82499 270)
			(size 0.6096 2.3622)
			(layers "F.Cu" "F.Mask" "F.Paste")
			(net "P12V_HDD14")
		)
		(pad "P15" smd rect
			(at -15.875 -1.82499 270)
			(size 0.6096 2.3622)
			(layers "F.Cu" "F.Mask" "F.Paste")
			(net "P12V_HDD14")
		)
		(pad "S1" smd rect
			(at 15.875 -1.82499 270)
			(size 0.6096 2.3622)
			(layers "F.Cu" "F.Mask" "F.Paste")
			(net "GND")
		)
		(pad "S2" smd rect
			(at 14.605 -1.82499 270)
			(size 0.6096 2.3622)
			(layers "F.Cu" "F.Mask" "F.Paste")
			(net "SAS_HDD_RX_P14")
		)
		(pad "S3" smd rect
			(at 13.335 -1.82499 270)
			(size 0.6096 2.3622)
			(layers "F.Cu" "F.Mask" "F.Paste")
			(net "SAS_HDD_RX_N14")
		)
		(pad "S4" smd rect
			(at 12.065 -1.82499 270)
			(size 0.6096 2.3622)
			(layers "F.Cu" "F.Mask" "F.Paste")
			(net "GND")
		)
		(pad "S5" smd rect
			(at 10.795 -1.82499 270)
			(size 0.6096 2.3622)
			(layers "F.Cu" "F.Mask" "F.Paste")
			(net "PHY_DRV_B_TO_SCC_B_14_DN")
		)
		(pad "S6" smd rect
			(at 9.525 -1.82499 270)
			(size 0.6096 2.3622)
			(layers "F.Cu" "F.Mask" "F.Paste")
			(net "PHY_DRV_B_TO_SCC_B_14_DP")
		)
		(pad "S7" smd rect
			(at 8.255 -1.82499 270)
			(size 0.6096 2.3622)
			(layers "F.Cu" "F.Mask" "F.Paste")
			(net "GND")
		)
		(pad "S8" smd rect
			(at 7.480046 2.845054 270)
			(size 0.508 2.3622)
			(layers "F.Cu" "F.Mask" "F.Paste")
			(net "GND")
		)
		(pad "S9" smd rect
			(at 6.679946 2.845054 270)
			(size 0.508 2.3622)
			(layers "F.Cu" "F.Mask" "F.Paste")
			(net "Net_437")
		)
		(pad "S10" smd rect
			(at 5.8801 2.845054 270)
			(size 0.508 2.3622)
			(layers "F.Cu" "F.Mask" "F.Paste")
			(net "Net_329")
		)
		(pad "S11" smd rect
			(at 5.08 2.845054 270)
			(size 0.508 2.3622)
			(layers "F.Cu" "F.Mask" "F.Paste")
			(net "GND")
		)
		(pad "S12" smd rect
			(at 4.2799 2.845054 270)
			(size 0.508 2.3622)
			(layers "F.Cu" "F.Mask" "F.Paste")
			(net "Net_365")
		)
		(pad "S13" smd rect
			(at 3.480054 2.845054 270)
			(size 0.508 2.3622)
			(layers "F.Cu" "F.Mask" "F.Paste")
			(net "Net_401")
		)
		(pad "S14" smd rect
			(at 2.679954 2.845054 270)
			(size 0.508 2.3622)
			(layers "F.Cu" "F.Mask" "F.Paste")
			(net "GND")
		)
		(zone
			(layer "F.Cu")
			(hatch none 0.5)
			(connect_pads
				(clearance 0)
			)
			(min_thickness 0.25)
			(keepout
				(tracks allowed)
				(vias not_allowed)
				(pads allowed)
				(copperpour not_allowed)
				(footprints allowed)
			)
			(placement
				(enabled no)
				(sheetname "")
			)
			(fill
				(thermal_gap 0.5)
				(thermal_bridge_width 0.5)
				(island_removal_mode 0)
			)
			(polygon
				(pts
					(xy 94.957646 -160.64865) (xy 87.883746 -160.64865) (xy 87.883746 -167.58285) (xy 88.988646 -167.58285)
					(xy 88.988646 -163.46805) (xy 93.611446 -163.46805) (xy 93.611446 -167.58285) (xy 94.957646 -167.58285)
				)
			)
		)
		(zone
			(layer "F.Cu")
			(hatch none 0.5)
			(connect_pads
				(clearance 0)
			)
			(min_thickness 0.25)
			(keepout
				(tracks not_allowed)
				(vias allowed)
				(pads allowed)
				(copperpour not_allowed)
				(footprints allowed)
			)
			(placement
				(enabled no)
				(sheetname "")
			)
			(fill
				(thermal_gap 0.5)
				(thermal_bridge_width 0.5)
				(island_removal_mode 0)
			)
			(polygon
				(pts
					(xy 94.957646 -160.64865) (xy 87.883746 -160.64865) (xy 87.883746 -167.58285) (xy 88.988646 -167.58285)
					(xy 88.988646 -163.46805) (xy 93.611446 -163.46805) (xy 93.611446 -167.58285) (xy 94.957646 -167.58285)
				)
			)
		)
		(zone
			(layer "F.Cu")
			(hatch none 0.5)
			(connect_pads
				(clearance 0)
			)
			(min_thickness 0.25)
			(keepout
				(tracks not_allowed)
				(vias allowed)
				(pads allowed)
				(copperpour not_allowed)
				(footprints allowed)
			)
			(placement
				(enabled no)
				(sheetname "")
			)
			(fill
				(thermal_gap 0.5)
				(thermal_bridge_width 0.5)
				(island_removal_mode 0)
			)
			(polygon
				(pts
					(xy 94.957646 -127.17145) (xy 87.883746 -127.17145) (xy 87.883746 -120.23725) (xy 88.988646 -120.23725)
					(xy 88.988646 -124.35205) (xy 93.611446 -124.35205) (xy 93.611446 -120.23725) (xy 94.957646 -120.23725)
				)
			)
		)
		(zone
			(layer "F.Cu")
			(hatch none 0.5)
			(connect_pads
				(clearance 0)
			)
			(min_thickness 0.25)
			(keepout
				(tracks allowed)
				(vias not_allowed)
				(pads allowed)
				(copperpour not_allowed)
				(footprints allowed)
			)
			(placement
				(enabled no)
				(sheetname "")
			)
			(fill
				(thermal_gap 0.5)
				(thermal_bridge_width 0.5)
				(island_removal_mode 0)
			)
			(polygon
				(pts
					(xy 94.957646 -127.17145) (xy 87.883746 -127.17145) (xy 87.883746 -120.23725) (xy 88.988646 -120.23725)
					(xy 88.988646 -124.35205) (xy 93.611446 -124.35205) (xy 93.611446 -120.23725) (xy 94.957646 -120.23725)
				)
			)
		)
		(zone
			(layers "F.Cu" "B.Cu" "In1.Cu" "In2.Cu" "In3.Cu" "In4.Cu" "In5.Cu" "In6.Cu")
			(hatch none 0.5)
			(connect_pads
				(clearance 0)
			)
			(min_thickness 0.25)
			(keepout
				(tracks not_allowed)
				(vias allowed)
				(pads allowed)
				(copperpour not_allowed)
				(footprints allowed)
			)
			(placement
				(enabled no)
				(sheetname "")
			)
			(fill
				(thermal_gap 0.5)
				(thermal_bridge_width 0.5)
				(island_removal_mode 0)
			)
			(polygon
				(pts
					(arc
						(start 92.074746 -125.035056)
						(mid 90.525346 -125.035056)
						(end 92.074746 -125.035056)
					)
				)
			)
		)
		(zone
			(layers "F.Cu" "B.Cu" "In1.Cu" "In2.Cu" "In3.Cu" "In4.Cu" "In5.Cu" "In6.Cu")
			(hatch none 0.5)
			(connect_pads
				(clearance 0)
			)
			(min_thickness 0.25)
			(keepout
				(tracks not_allowed)
				(vias allowed)
				(pads allowed)
				(copperpour not_allowed)
				(footprints allowed)
			)
			(placement
				(enabled no)
				(sheetname "")
			)
			(fill
				(thermal_gap 0.5)
				(thermal_bridge_width 0.5)
				(island_removal_mode 0)
			)
			(polygon
				(pts
					(arc
						(start 92.277946 -162.785044)
						(mid 90.322146 -162.785044)
						(end 92.277946 -162.785044)
					)
				)
			)
		)
	)
	(footprint ""
		(layer "F.Cu")
		(at 83.2866 -263.779 -90)
		(property "Reference" "C56"
			(at 0 0 270)
			(layer "F.SilkS")
			(hide yes)
			(effects
				(font
					(size 1.27 1.27)
				)
			)
		)
		(property "Value" "SC1U16V3KX-5GP"
			(at 0 -2.8194 270)
			(unlocked yes)
			(layer "F.Fab")
			(hide yes)
			(effects
				(font
					(size 1.016 1.016)
					(thickness 0.1524)
				)
			)
		)
		(property "Device Type" "C603H36"
			(at 0 -4.3434 270)
			(unlocked yes)
			(layer "F.Fab")
			(hide yes)
			(effects
				(font
					(size 1.016 1.016)
					(thickness 0.1524)
				)
			)
		)
		(duplicate_pad_numbers_are_jumpers no)
		(fp_line
			(start 0.508 0)
			(end -0.508 0)
			(stroke
				(width 0.2032)
				(type default)
			)
			(layer "F.SilkS")
		)
		(fp_rect
			(start -0.5842 1.3335)
			(end 0.5842 -1.3335)
			(stroke
				(width 0)
				(type default)
			)
			(fill no)
			(layer "F.CrtYd")
		)
		(fp_rect
			(start -0.5842 1.3335)
			(end 0.5842 -1.3335)
			(stroke
				(width 0)
				(type default)
			)
			(fill no)
			(layer "F.Fab")
		)
		(pad "1" smd custom
			(at 0 -0.762 270)
			(size 0.2159 0.2159)
			(layers "F.Cu" "F.Mask" "F.Paste")
			(net "P5V_HDD2")
			(options
				(clearance outline)
				(anchor circle)
			)
			(primitives
				(gr_poly
					(pts
						(arc
							(start -0.3302 -0.4318)
							(mid -0.402042 -0.402042)
							(end -0.4318 -0.3302)
						)
						(arc
							(start -0.4318 0.3302)
							(mid -0.402042 0.402042)
							(end -0.3302 0.4318)
						)
						(arc
							(start 0.3302 0.4318)
							(mid 0.402042 0.402042)
							(end 0.4318 0.3302)
						)
						(arc
							(start 0.4318 -0.3302)
							(mid 0.402042 -0.402042)
							(end 0.3302 -0.4318)
						)
					)
					(width 0)
					(fill yes)
				)
			)
		)
		(pad "2" smd custom
			(at 0 0.762 270)
			(size 0.2159 0.2159)
			(layers "F.Cu" "F.Mask" "F.Paste")
			(net "GND")
			(options
				(clearance outline)
				(anchor circle)
			)
			(primitives
				(gr_poly
					(pts
						(arc
							(start -0.3302 -0.4318)
							(mid -0.402042 -0.402042)
							(end -0.4318 -0.3302)
						)
						(arc
							(start -0.4318 0.3302)
							(mid -0.402042 0.402042)
							(end -0.3302 0.4318)
						)
						(arc
							(start 0.3302 0.4318)
							(mid 0.402042 0.402042)
							(end 0.4318 0.3302)
						)
						(arc
							(start 0.4318 -0.3302)
							(mid 0.402042 -0.402042)
							(end 0.3302 -0.4318)
						)
					)
					(width 0)
					(fill yes)
				)
			)
		)
	)
	(footprint ""
		(layer "F.Cu")
		(at 129.286 -374.523 -90)
		(property "Reference" "C524"
			(at 0 0 270)
			(layer "F.SilkS")
			(hide yes)
			(effects
				(font
					(size 1.27 1.27)
				)
			)
		)
		(property "Value" "SCD1U25V2KX-2-GP"
			(at 1.1811 -2.7051 270)
			(unlocked yes)
			(layer "F.Fab")
			(hide yes)
			(effects
				(font
					(size 1.016 1.016)
					(thickness 0.1524)
				)
			)
		)
		(property "Device Type" "C402H22"
			(at 1.1811 -4.2291 270)
			(unlocked yes)
			(layer "F.Fab")
			(hide yes)
			(effects
				(font
					(size 1.016 1.016)
					(thickness 0.1524)
				)
			)
		)
		(duplicate_pad_numbers_are_jumpers no)
		(fp_rect
			(start -0.4318 0.9525)
			(end 0.4318 -0.9525)
			(stroke
				(width 0)
				(type default)
			)
			(fill no)
			(layer "F.CrtYd")
		)
		(fp_rect
			(start -0.4318 0.9525)
			(end 0.4318 -0.9525)
			(stroke
				(width 0)
				(type default)
			)
			(fill no)
			(layer "F.Fab")
		)
		(pad "1" smd custom
			(at 0 -0.4445 270)
			(size 0.1524 0.1524)
			(layers "F.Cu" "F.Mask" "F.Paste")
			(net "FAN_1_TACH0")
			(options
				(clearance outline)
				(anchor circle)
			)
			(primitives
				(gr_poly
					(pts
						(arc
							(start 0.3048 -0.2032)
							(mid 0.275042 -0.275042)
							(end 0.2032 -0.3048)
						)
						(arc
							(start -0.2032 -0.3048)
							(mid -0.275042 -0.275042)
							(end -0.3048 -0.2032)
						)
						(arc
							(start -0.3048 0.2032)
							(mid -0.275042 0.275042)
							(end -0.2032 0.3048)
						)
						(arc
							(start 0.2032 0.3048)
							(mid 0.275042 0.275042)
							(end 0.3048 0.2032)
						)
					)
					(width 0)
					(fill yes)
				)
			)
		)
		(pad "2" smd custom
			(at 0 0.4445 270)
			(size 0.1524 0.1524)
			(layers "F.Cu" "F.Mask" "F.Paste")
			(net "GND")
			(options
				(clearance outline)
				(anchor circle)
			)
			(primitives
				(gr_poly
					(pts
						(arc
							(start 0.3048 -0.2032)
							(mid 0.275042 -0.275042)
							(end 0.2032 -0.3048)
						)
						(arc
							(start -0.2032 -0.3048)
							(mid -0.275042 -0.275042)
							(end -0.3048 -0.2032)
						)
						(arc
							(start -0.3048 0.2032)
							(mid -0.275042 0.275042)
							(end -0.2032 0.3048)
						)
						(arc
							(start 0.2032 0.3048)
							(mid 0.275042 0.275042)
							(end 0.3048 0.2032)
						)
					)
					(width 0)
					(fill yes)
				)
			)
		)
	)
	(footprint ""
		(layer "F.Cu")
		(at 381.2032 -146.2532)
		(property "Reference" "R534"
			(at 0 0 0)
			(layer "F.SilkS")
			(hide yes)
			(effects
				(font
					(size 1.27 1.27)
				)
			)
		)
		(property "Value" "220R3F-1-GP"
			(at -0.0254 -2.5146 0)
			(unlocked yes)
			(layer "F.Fab")
			(hide yes)
			(effects
				(font
					(size 1.016 1.016)
					(thickness 0.1524)
				)
			)
		)
		(property "Device Type" "R603H22"
			(at -0.0254 -4.0386 0)
			(unlocked yes)
			(layer "F.Fab")
			(hide yes)
			(effects
				(font
					(size 1.016 1.016)
					(thickness 0.1524)
				)
			)
		)
		(duplicate_pad_numbers_are_jumpers no)
		(fp_line
			(start -0.4826 0)
			(end -0.2032 0)
			(stroke
				(width 0.2032)
				(type default)
			)
			(layer "F.SilkS")
		)
		(fp_line
			(start 0.2032 0)
			(end 0.4826 0)
			(stroke
				(width 0.2032)
				(type default)
			)
			(layer "F.SilkS")
		)
		(fp_rect
			(start -0.5842 1.3335)
			(end 0.5842 -1.3335)
			(stroke
				(width 0)
				(type default)
			)
			(fill no)
			(layer "F.CrtYd")
		)
		(fp_rect
			(start -0.5842 1.3335)
			(end 0.5842 -1.3335)
			(stroke
				(width 0)
				(type default)
			)
			(fill no)
			(layer "F.Fab")
		)
		(pad "1" smd custom
			(at 0 -0.762)
			(size 0.2159 0.2159)
			(layers "F.Cu" "F.Mask" "F.Paste")
			(net "HDD_PRSNT_20")
			(options
				(clearance outline)
				(anchor circle)
			)
			(primitives
				(gr_poly
					(pts
						(arc
							(start -0.3302 -0.4318)
							(mid -0.402042 -0.402042)
							(end -0.4318 -0.3302)
						)
						(arc
							(start -0.4318 0.3302)
							(mid -0.402042 0.402042)
							(end -0.3302 0.4318)
						)
						(arc
							(start 0.3302 0.4318)
							(mid 0.402042 0.402042)
							(end 0.4318 0.3302)
						)
						(arc
							(start 0.4318 -0.3302)
							(mid 0.402042 -0.402042)
							(end 0.3302 -0.4318)
						)
					)
					(width 0)
					(fill yes)
				)
			)
		)
		(pad "2" smd custom
			(at 0 0.762)
			(size 0.2159 0.2159)
			(layers "F.Cu" "F.Mask" "F.Paste")
			(net "DRIVE_B_20_INS")
			(options
				(clearance outline)
				(anchor circle)
			)
			(primitives
				(gr_poly
					(pts
						(arc
							(start -0.3302 -0.4318)
							(mid -0.402042 -0.402042)
							(end -0.4318 -0.3302)
						)
						(arc
							(start -0.4318 0.3302)
							(mid -0.402042 0.402042)
							(end -0.3302 0.4318)
						)
						(arc
							(start 0.3302 0.4318)
							(mid 0.402042 0.402042)
							(end 0.4318 0.3302)
						)
						(arc
							(start 0.4318 -0.3302)
							(mid 0.402042 -0.402042)
							(end 0.3302 -0.4318)
						)
					)
					(width 0)
					(fill yes)
				)
			)
		)
	)
	(footprint ""
		(layer "F.Cu")
		(at 461.899 -243.586 180)
		(property "Reference" "R326"
			(at 0 0 180)
			(layer "F.SilkS")
			(hide yes)
			(effects
				(font
					(size 1.27 1.27)
				)
			)
		)
		(property "Value" "0R2J-2-GP"
			(at 0.064008 -3.993896 180)
			(unlocked yes)
			(layer "F.Fab")
			(hide yes)
			(effects
				(font
					(size 1.016 1.016)
					(thickness 0.1524)
				)
			)
		)
		(property "Device Type" "R402H16"
			(at 0.064008 -5.517896 180)
			(unlocked yes)
			(layer "F.Fab")
			(hide yes)
			(effects
				(font
					(size 1.016 1.016)
					(thickness 0.1524)
				)
			)
		)
		(duplicate_pad_numbers_are_jumpers no)
		(fp_line
			(start 0.508 -0.9398)
			(end -0.508 -0.9398)
			(stroke
				(width 0.1524)
				(type default)
			)
			(layer "F.SilkS")
		)
		(fp_line
			(start -0.508 -0.9398)
			(end -0.508 0.9398)
			(stroke
				(width 0.1524)
				(type default)
			)
			(layer "F.SilkS")
		)
		(fp_rect
			(start -0.508 0.9398)
			(end 0.508 -0.9398)
			(stroke
				(width 0)
				(type default)
			)
			(fill no)
			(layer "F.CrtYd")
		)
		(fp_rect
			(start -0.508 0.9398)
			(end 0.508 -0.9398)
			(stroke
				(width 0)
				(type default)
			)
			(fill no)
			(layer "F.Fab")
		)
		(pad "1" smd custom
			(at 0 -0.4445 180)
			(size 0.1397 0.1397)
			(layers "F.Cu" "F.Mask" "F.Paste")
			(net "DRIVE_B_10_PWR")
			(options
				(clearance outline)
				(anchor circle)
			)
			(primitives
				(gr_poly
					(pts
						(arc
							(start -0.1778 -0.2794)
							(mid -0.249642 -0.249642)
							(end -0.2794 -0.1778)
						)
						(arc
							(start -0.2794 0.1778)
							(mid -0.249642 0.249642)
							(end -0.1778 0.2794)
						)
						(arc
							(start 0.1778 0.2794)
							(mid 0.249642 0.249642)
							(end 0.2794 0.1778)
						)
						(arc
							(start 0.2794 -0.1778)
							(mid 0.249642 -0.249642)
							(end 0.1778 -0.2794)
						)
					)
					(width 0)
					(fill yes)
				)
			)
		)
		(pad "2" smd custom
			(at 0 0.4445 180)
			(size 0.1397 0.1397)
			(layers "F.Cu" "F.Mask" "F.Paste")
			(net "SW_PWR_R_HDD10")
			(options
				(clearance outline)
				(anchor circle)
			)
			(primitives
				(gr_poly
					(pts
						(arc
							(start -0.1778 -0.2794)
							(mid -0.249642 -0.249642)
							(end -0.2794 -0.1778)
						)
						(arc
							(start -0.2794 0.1778)
							(mid -0.249642 0.249642)
							(end -0.1778 0.2794)
						)
						(arc
							(start 0.1778 0.2794)
							(mid 0.249642 0.249642)
							(end 0.2794 0.1778)
						)
						(arc
							(start 0.2794 -0.1778)
							(mid 0.249642 -0.249642)
							(end 0.1778 -0.2794)
						)
					)
					(width 0)
					(fill yes)
				)
			)
		)
	)
	(footprint ""
		(layer "F.Cu")
		(at 115.062 -249.555 180)
		(property "Reference" "Q11"
			(at 0 0 180)
			(layer "F.SilkS")
			(hide yes)
			(effects
				(font
					(size 1.27 1.27)
				)
			)
		)
		(property "Value" "2N7002KDW-GP"
			(at -2.3622 -8.2042 180)
			(unlocked yes)
			(layer "F.Fab")
			(hide yes)
			(effects
				(font
					(size 1.016 1.016)
					(thickness 0.1524)
				)
			)
		)
		(property "Device Type" "SOT-363H44"
			(at -2.3622 -10.1092 180)
			(unlocked yes)
			(layer "F.Fab")
			(hide yes)
			(effects
				(font
					(size 1.016 1.016)
					(thickness 0.1524)
				)
			)
		)
		(duplicate_pad_numbers_are_jumpers no)
		(fp_line
			(start 1.4478 1.7018)
			(end 1.4478 -1.7018)
			(stroke
				(width 0.1524)
				(type default)
			)
			(layer "F.SilkS")
		)
		(fp_line
			(start 1.4478 -1.7018)
			(end -1.4478 -1.7018)
			(stroke
				(width 0.1524)
				(type default)
			)
			(layer "F.SilkS")
		)
		(fp_line
			(start -1.27 1.524)
			(end -1.27 0.6604)
			(stroke
				(width 0.4826)
				(type default)
			)
			(layer "F.SilkS")
		)
		(fp_line
			(start -1.4478 1.7018)
			(end 1.4478 1.7018)
			(stroke
				(width 0.1524)
				(type default)
			)
			(layer "F.SilkS")
		)
		(fp_line
			(start -1.4478 -1.7018)
			(end -1.4478 1.7018)
			(stroke
				(width 0.1524)
				(type default)
			)
			(layer "F.SilkS")
		)
		(fp_poly
			(pts
				(xy -1.524 -1.778) (xy 1.524 -1.778) (xy 1.524 1.778) (xy -1.524 1.778)
			)
			(stroke
				(width 0)
				(type default)
			)
			(fill no)
			(layer "F.CrtYd")
		)
		(fp_poly
			(pts
				(xy -1.524 -1.778) (xy 1.524 -1.778) (xy 1.524 1.778) (xy -1.524 1.778)
			)
			(stroke
				(width 0)
				(type default)
			)
			(fill no)
			(layer "F.Fab")
		)
		(pad "1" smd rect
			(at -0.65024 0.9398 180)
			(size 0.4064 1.016)
			(layers "F.Cu" "F.Mask" "F.Paste")
			(net "GND")
		)
		(pad "2" smd rect
			(at 0 0.9398 180)
			(size 0.4064 1.016)
			(layers "F.Cu" "F.Mask" "F.Paste")
			(net "SW_PWR_R_HDD3")
		)
		(pad "3" smd rect
			(at 0.65024 0.9398 180)
			(size 0.4064 1.016)
			(layers "F.Cu" "F.Mask" "F.Paste")
			(net "SW_HDD_P3")
		)
		(pad "4" smd rect
			(at 0.65024 -0.9398 180)
			(size 0.4064 1.016)
			(layers "F.Cu" "F.Mask" "F.Paste")
			(net "GND")
		)
		(pad "5" smd rect
			(at 0 -0.9398 180)
			(size 0.4064 1.016)
			(layers "F.Cu" "F.Mask" "F.Paste")
			(net "SW_HDD_G3")
		)
		(pad "6" smd rect
			(at -0.65024 -0.9398 180)
			(size 0.4064 1.016)
			(layers "F.Cu" "F.Mask" "F.Paste")
			(net "SW_HDD_R3")
		)
	)
	(footprint ""
		(layer "F.Cu")
		(at 312.5724 -327.858882)
		(property "Reference" "R158"
			(at 0 0 0)
			(layer "F.SilkS")
			(hide yes)
			(effects
				(font
					(size 1.27 1.27)
				)
			)
		)
		(property "Value" "100KR2F-L1-GP"
			(at 0.064008 -3.993896 0)
			(unlocked yes)
			(layer "F.Fab")
			(hide yes)
			(effects
				(font
					(size 1.016 1.016)
					(thickness 0.1524)
				)
			)
		)
		(property "Device Type" "R402H16"
			(at 0.064008 -5.517896 0)
			(unlocked yes)
			(layer "F.Fab")
			(hide yes)
			(effects
				(font
					(size 1.016 1.016)
					(thickness 0.1524)
				)
			)
		)
		(duplicate_pad_numbers_are_jumpers no)
		(fp_line
			(start -0.508 -0.9398)
			(end -0.508 0.9398)
			(stroke
				(width 0.1524)
				(type default)
			)
			(layer "F.SilkS")
		)
		(fp_line
			(start 0.508 -0.9398)
			(end -0.508 -0.9398)
			(stroke
				(width 0.1524)
				(type default)
			)
			(layer "F.SilkS")
		)
		(fp_rect
			(start -0.508 0.9398)
			(end 0.508 -0.9398)
			(stroke
				(width 0)
				(type default)
			)
			(fill no)
			(layer "F.CrtYd")
		)
		(fp_rect
			(start -0.508 0.9398)
			(end 0.508 -0.9398)
			(stroke
				(width 0)
				(type default)
			)
			(fill no)
			(layer "F.Fab")
		)
		(pad "1" smd custom
			(at 0 -0.4445)
			(size 0.1397 0.1397)
			(layers "F.Cu" "F.Mask" "F.Paste")
			(net "PWM_BMC_A_ZONE_D")
			(options
				(clearance outline)
				(anchor circle)
			)
			(primitives
				(gr_poly
					(pts
						(arc
							(start -0.1778 -0.2794)
							(mid -0.249642 -0.249642)
							(end -0.2794 -0.1778)
						)
						(arc
							(start -0.2794 0.1778)
							(mid -0.249642 0.249642)
							(end -0.1778 0.2794)
						)
						(arc
							(start 0.1778 0.2794)
							(mid 0.249642 0.249642)
							(end 0.2794 0.1778)
						)
						(arc
							(start 0.2794 -0.1778)
							(mid 0.249642 -0.249642)
							(end 0.1778 -0.2794)
						)
					)
					(width 0)
					(fill yes)
				)
			)
		)
		(pad "2" smd custom
			(at 0 0.4445)
			(size 0.1397 0.1397)
			(layers "F.Cu" "F.Mask" "F.Paste")
			(net "GND")
			(options
				(clearance outline)
				(anchor circle)
			)
			(primitives
				(gr_poly
					(pts
						(arc
							(start -0.1778 -0.2794)
							(mid -0.249642 -0.249642)
							(end -0.2794 -0.1778)
						)
						(arc
							(start -0.2794 0.1778)
							(mid -0.249642 0.249642)
							(end -0.1778 0.2794)
						)
						(arc
							(start 0.1778 0.2794)
							(mid 0.249642 0.249642)
							(end 0.2794 0.1778)
						)
						(arc
							(start 0.2794 -0.1778)
							(mid 0.249642 -0.249642)
							(end 0.1778 -0.2794)
						)
					)
					(width 0)
					(fill yes)
				)
			)
		)
	)
	(footprint ""
		(layer "F.Cu")
		(at 321.6656 -261.62)
		(property "Reference" "C115"
			(at 0 0 0)
			(layer "F.SilkS")
			(hide yes)
			(effects
				(font
					(size 1.27 1.27)
				)
			)
		)
		(property "Value" "SCD01U50V2KX-1GP"
			(at 1.1811 -2.7051 0)
			(unlocked yes)
			(layer "F.Fab")
			(hide yes)
			(effects
				(font
					(size 1.016 1.016)
					(thickness 0.1524)
				)
			)
		)
		(property "Device Type" "C402H22"
			(at 1.1811 -4.2291 0)
			(unlocked yes)
			(layer "F.Fab")
			(hide yes)
			(effects
				(font
					(size 1.016 1.016)
					(thickness 0.1524)
				)
			)
		)
		(duplicate_pad_numbers_are_jumpers no)
		(fp_rect
			(start -0.4318 0.9525)
			(end 0.4318 -0.9525)
			(stroke
				(width 0)
				(type default)
			)
			(fill no)
			(layer "F.CrtYd")
		)
		(fp_rect
			(start -0.4318 0.9525)
			(end 0.4318 -0.9525)
			(stroke
				(width 0)
				(type default)
			)
			(fill no)
			(layer "F.Fab")
		)
		(pad "1" smd custom
			(at 0 -0.4445)
			(size 0.1524 0.1524)
			(layers "F.Cu" "F.Mask" "F.Paste")
			(net "HDD_PRSNT_6")
			(options
				(clearance outline)
				(anchor circle)
			)
			(primitives
				(gr_poly
					(pts
						(arc
							(start 0.3048 -0.2032)
							(mid 0.275042 -0.275042)
							(end 0.2032 -0.3048)
						)
						(arc
							(start -0.2032 -0.3048)
							(mid -0.275042 -0.275042)
							(end -0.3048 -0.2032)
						)
						(arc
							(start -0.3048 0.2032)
							(mid -0.275042 0.275042)
							(end -0.2032 0.3048)
						)
						(arc
							(start 0.2032 0.3048)
							(mid 0.275042 0.275042)
							(end 0.3048 0.2032)
						)
					)
					(width 0)
					(fill yes)
				)
			)
		)
		(pad "2" smd custom
			(at 0 0.4445)
			(size 0.1524 0.1524)
			(layers "F.Cu" "F.Mask" "F.Paste")
			(net "GND")
			(options
				(clearance outline)
				(anchor circle)
			)
			(primitives
				(gr_poly
					(pts
						(arc
							(start 0.3048 -0.2032)
							(mid 0.275042 -0.275042)
							(end 0.2032 -0.3048)
						)
						(arc
							(start -0.2032 -0.3048)
							(mid -0.275042 -0.275042)
							(end -0.3048 -0.2032)
						)
						(arc
							(start -0.3048 0.2032)
							(mid -0.275042 0.275042)
							(end -0.2032 0.3048)
						)
						(arc
							(start 0.2032 0.3048)
							(mid 0.275042 0.275042)
							(end 0.3048 0.2032)
						)
					)
					(width 0)
					(fill yes)
				)
			)
		)
	)
	(footprint ""
		(layer "F.Cu")
		(at 52.285646 -118.316756 -90)
		(property "Reference" "R1121"
			(at 0 0 270)
			(layer "F.SilkS")
			(hide yes)
			(effects
				(font
					(size 1.27 1.27)
				)
			)
		)
		(property "Value" "10KR2F-2-GP"
			(at 0.064008 -3.993896 270)
			(unlocked yes)
			(layer "F.Fab")
			(hide yes)
			(effects
				(font
					(size 1.016 1.016)
					(thickness 0.1524)
				)
			)
		)
		(property "Device Type" "R402H16"
			(at 0.064008 -5.517896 270)
			(unlocked yes)
			(layer "F.Fab")
			(hide yes)
			(effects
				(font
					(size 1.016 1.016)
					(thickness 0.1524)
				)
			)
		)
		(duplicate_pad_numbers_are_jumpers no)
		(fp_line
			(start -0.508 -0.9398)
			(end -0.508 0.9398)
			(stroke
				(width 0.1524)
				(type default)
			)
			(layer "F.SilkS")
		)
		(fp_line
			(start 0.508 -0.9398)
			(end -0.508 -0.9398)
			(stroke
				(width 0.1524)
				(type default)
			)
			(layer "F.SilkS")
		)
		(fp_rect
			(start -0.508 0.9398)
			(end 0.508 -0.9398)
			(stroke
				(width 0)
				(type default)
			)
			(fill no)
			(layer "F.CrtYd")
		)
		(fp_rect
			(start -0.508 0.9398)
			(end 0.508 -0.9398)
			(stroke
				(width 0)
				(type default)
			)
			(fill no)
			(layer "F.Fab")
		)
		(pad "1" smd custom
			(at 0 -0.4445 270)
			(size 0.1397 0.1397)
			(layers "F.Cu" "F.Mask" "F.Paste")
			(net "P5V_B_2")
			(options
				(clearance outline)
				(anchor circle)
			)
			(primitives
				(gr_poly
					(pts
						(arc
							(start -0.1778 -0.2794)
							(mid -0.249642 -0.249642)
							(end -0.2794 -0.1778)
						)
						(arc
							(start -0.2794 0.1778)
							(mid -0.249642 0.249642)
							(end -0.1778 0.2794)
						)
						(arc
							(start 0.1778 0.2794)
							(mid 0.249642 0.249642)
							(end 0.2794 0.1778)
						)
						(arc
							(start 0.2794 -0.1778)
							(mid 0.249642 -0.249642)
							(end 0.1778 -0.2794)
						)
					)
					(width 0)
					(fill yes)
				)
			)
		)
		(pad "2" smd custom
			(at 0 0.4445 270)
			(size 0.1397 0.1397)
			(layers "F.Cu" "F.Mask" "F.Paste")
			(net "P5V_B_2_PGOOD")
			(options
				(clearance outline)
				(anchor circle)
			)
			(primitives
				(gr_poly
					(pts
						(arc
							(start -0.1778 -0.2794)
							(mid -0.249642 -0.249642)
							(end -0.2794 -0.1778)
						)
						(arc
							(start -0.2794 0.1778)
							(mid -0.249642 0.249642)
							(end -0.1778 0.2794)
						)
						(arc
							(start 0.1778 0.2794)
							(mid 0.249642 0.249642)
							(end 0.2794 0.1778)
						)
						(arc
							(start 0.2794 -0.1778)
							(mid 0.249642 -0.249642)
							(end 0.1778 -0.2794)
						)
					)
					(width 0)
					(fill yes)
				)
			)
		)
	)
	(footprint ""
		(layer "F.Cu")
		(at 317.975996 -376.60199)
		(property "Reference" "R1303"
			(at 0 0 0)
			(layer "F.SilkS")
			(hide yes)
			(effects
				(font
					(size 1.27 1.27)
				)
			)
		)
		(property "Value" "4K7R2F-GP"
			(at 0.064008 -3.993896 0)
			(unlocked yes)
			(layer "F.Fab")
			(hide yes)
			(effects
				(font
					(size 1.016 1.016)
					(thickness 0.1524)
				)
			)
		)
		(property "Device Type" "R402H16"
			(at 0.064008 -5.517896 0)
			(unlocked yes)
			(layer "F.Fab")
			(hide yes)
			(effects
				(font
					(size 1.016 1.016)
					(thickness 0.1524)
				)
			)
		)
		(duplicate_pad_numbers_are_jumpers no)
		(fp_line
			(start -0.508 -0.9398)
			(end -0.508 0.9398)
			(stroke
				(width 0.1524)
				(type default)
			)
			(layer "F.SilkS")
		)
		(fp_line
			(start 0.508 -0.9398)
			(end -0.508 -0.9398)
			(stroke
				(width 0.1524)
				(type default)
			)
			(layer "F.SilkS")
		)
		(fp_rect
			(start -0.508 0.9398)
			(end 0.508 -0.9398)
			(stroke
				(width 0)
				(type default)
			)
			(fill no)
			(layer "F.CrtYd")
		)
		(fp_rect
			(start -0.508 0.9398)
			(end 0.508 -0.9398)
			(stroke
				(width 0)
				(type default)
			)
			(fill no)
			(layer "F.Fab")
		)
		(pad "1" smd custom
			(at 0 -0.4445)
			(size 0.1397 0.1397)
			(layers "F.Cu" "F.Mask" "F.Paste")
			(net "FAN_BLUE_LED2")
			(options
				(clearance outline)
				(anchor circle)
			)
			(primitives
				(gr_poly
					(pts
						(arc
							(start -0.1778 -0.2794)
							(mid -0.249642 -0.249642)
							(end -0.2794 -0.1778)
						)
						(arc
							(start -0.2794 0.1778)
							(mid -0.249642 0.249642)
							(end -0.1778 0.2794)
						)
						(arc
							(start 0.1778 0.2794)
							(mid 0.249642 0.249642)
							(end 0.2794 0.1778)
						)
						(arc
							(start 0.2794 -0.1778)
							(mid 0.249642 -0.249642)
							(end 0.1778 -0.2794)
						)
					)
					(width 0)
					(fill yes)
				)
			)
		)
		(pad "2" smd custom
			(at 0 0.4445)
			(size 0.1397 0.1397)
			(layers "F.Cu" "F.Mask" "F.Paste")
			(net "FAN_LED2_D")
			(options
				(clearance outline)
				(anchor circle)
			)
			(primitives
				(gr_poly
					(pts
						(arc
							(start -0.1778 -0.2794)
							(mid -0.249642 -0.249642)
							(end -0.2794 -0.1778)
						)
						(arc
							(start -0.2794 0.1778)
							(mid -0.249642 0.249642)
							(end -0.1778 0.2794)
						)
						(arc
							(start 0.1778 0.2794)
							(mid 0.249642 0.249642)
							(end 0.2794 0.1778)
						)
						(arc
							(start 0.2794 -0.1778)
							(mid 0.249642 -0.249642)
							(end 0.1778 -0.2794)
						)
					)
					(width 0)
					(fill yes)
				)
			)
		)
	)
	(footprint ""
		(layer "F.Cu")
		(at 83.185 -262.001 -90)
		(property "Reference" "C57"
			(at 0 0 270)
			(layer "F.SilkS")
			(hide yes)
			(effects
				(font
					(size 1.27 1.27)
				)
			)
		)
		(property "Value" "SC10U16V6KX-2GP"
			(at -0.0762 -5.1308 270)
			(unlocked yes)
			(layer "F.Fab")
			(hide yes)
			(effects
				(font
					(size 1.016 1.016)
					(thickness 0.1524)
				)
			)
		)
		(property "Device Type" "C1206H71"
			(at -0.127 -6.6548 270)
			(unlocked yes)
			(layer "F.Fab")
			(hide yes)
			(effects
				(font
					(size 1.016 1.016)
					(thickness 0.1524)
				)
			)
		)
		(duplicate_pad_numbers_are_jumpers no)
		(fp_line
			(start -1.016 2.2352)
			(end -1.016 0.8382)
			(stroke
				(width 0.1524)
				(type default)
			)
			(layer "F.SilkS")
		)
		(fp_line
			(start 1.016 2.2352)
			(end -1.016 2.2352)
			(stroke
				(width 0.1524)
				(type default)
			)
			(layer "F.SilkS")
		)
		(fp_line
			(start 1.016 0.8382)
			(end 1.016 2.2352)
			(stroke
				(width 0.1524)
				(type default)
			)
			(layer "F.SilkS")
		)
		(fp_line
			(start -1.016 -0.8382)
			(end -1.016 -2.2352)
			(stroke
				(width 0.1524)
				(type default)
			)
			(layer "F.SilkS")
		)
		(fp_line
			(start -1.016 -2.2352)
			(end 1.016 -2.2352)
			(stroke
				(width 0.1524)
				(type default)
			)
			(layer "F.SilkS")
		)
		(fp_line
			(start 1.016 -2.2352)
			(end 1.016 -0.8382)
			(stroke
				(width 0.1524)
				(type default)
			)
			(layer "F.SilkS")
		)
		(fp_rect
			(start -1.0922 2.3114)
			(end 1.0922 -2.3114)
			(stroke
				(width 0)
				(type default)
			)
			(fill no)
			(layer "F.CrtYd")
		)
		(fp_poly
			(pts
				(xy 1.0922 -2.3114) (xy 1.0922 2.3114) (xy -1.0922 2.3114) (xy -1.0922 -2.3114)
			)
			(stroke
				(width 0)
				(type default)
			)
			(fill no)
			(layer "F.Fab")
		)
		(pad "1" smd rect
			(at 0 -1.397 270)
			(size 1.651 1.27)
			(layers "F.Cu" "F.Mask" "F.Paste")
			(net "P5V_HDD2")
		)
		(pad "2" smd rect
			(at 0 1.397 270)
			(size 1.651 1.27)
			(layers "F.Cu" "F.Mask" "F.Paste")
			(net "GND")
		)
	)
	(footprint ""
		(layer "F.Cu")
		(at 170.119294 -369.697 180)
		(property "Reference" "C569"
			(at 0 0 180)
			(layer "F.SilkS")
			(hide yes)
			(effects
				(font
					(size 1.27 1.27)
				)
			)
		)
		(property "Value" "SCD015U25V2KX-GP"
			(at 1.1811 -2.7051 180)
			(unlocked yes)
			(layer "F.Fab")
			(hide yes)
			(effects
				(font
					(size 1.016 1.016)
					(thickness 0.1524)
				)
			)
		)
		(property "Device Type" "C402H22"
			(at 1.1811 -4.2291 180)
			(unlocked yes)
			(layer "F.Fab")
			(hide yes)
			(effects
				(font
					(size 1.016 1.016)
					(thickness 0.1524)
				)
			)
		)
		(duplicate_pad_numbers_are_jumpers no)
		(fp_rect
			(start -0.4318 0.9525)
			(end 0.4318 -0.9525)
			(stroke
				(width 0)
				(type default)
			)
			(fill no)
			(layer "F.CrtYd")
		)
		(fp_rect
			(start -0.4318 0.9525)
			(end 0.4318 -0.9525)
			(stroke
				(width 0)
				(type default)
			)
			(fill no)
			(layer "F.Fab")
		)
		(pad "1" smd custom
			(at 0 -0.4445 180)
			(size 0.1524 0.1524)
			(layers "F.Cu" "F.Mask" "F.Paste")
			(net "MB0_HS_SENSE_P")
			(options
				(clearance outline)
				(anchor circle)
			)
			(primitives
				(gr_poly
					(pts
						(arc
							(start 0.3048 -0.2032)
							(mid 0.275042 -0.275042)
							(end 0.2032 -0.3048)
						)
						(arc
							(start -0.2032 -0.3048)
							(mid -0.275042 -0.275042)
							(end -0.3048 -0.2032)
						)
						(arc
							(start -0.3048 0.2032)
							(mid -0.275042 0.275042)
							(end -0.2032 0.3048)
						)
						(arc
							(start 0.2032 0.3048)
							(mid 0.275042 0.275042)
							(end 0.3048 0.2032)
						)
					)
					(width 0)
					(fill yes)
				)
			)
		)
		(pad "2" smd custom
			(at 0 0.4445 180)
			(size 0.1524 0.1524)
			(layers "F.Cu" "F.Mask" "F.Paste")
			(net "MB0_HS_SENSE_N")
			(options
				(clearance outline)
				(anchor circle)
			)
			(primitives
				(gr_poly
					(pts
						(arc
							(start 0.3048 -0.2032)
							(mid 0.275042 -0.275042)
							(end 0.2032 -0.3048)
						)
						(arc
							(start -0.2032 -0.3048)
							(mid -0.275042 -0.275042)
							(end -0.3048 -0.2032)
						)
						(arc
							(start -0.3048 0.2032)
							(mid -0.275042 0.275042)
							(end -0.2032 0.3048)
						)
						(arc
							(start 0.2032 0.3048)
							(mid 0.275042 0.275042)
							(end 0.3048 0.2032)
						)
					)
					(width 0)
					(fill yes)
				)
			)
		)
	)
	(footprint ""
		(layer "F.Cu")
		(at 455.311002 -229.49535 180)
		(property "Reference" "R1152"
			(at 0 0 180)
			(layer "F.SilkS")
			(hide yes)
			(effects
				(font
					(size 1.27 1.27)
				)
			)
		)
		(property "Value" "619KR2F-GP"
			(at 0.064008 -3.993896 180)
			(unlocked yes)
			(layer "F.Fab")
			(hide yes)
			(effects
				(font
					(size 1.016 1.016)
					(thickness 0.1524)
				)
			)
		)
		(property "Device Type" "R402H16"
			(at 0.064008 -5.517896 180)
			(unlocked yes)
			(layer "F.Fab")
			(hide yes)
			(effects
				(font
					(size 1.016 1.016)
					(thickness 0.1524)
				)
			)
		)
		(duplicate_pad_numbers_are_jumpers no)
		(fp_line
			(start 0.508 -0.9398)
			(end -0.508 -0.9398)
			(stroke
				(width 0.1524)
				(type default)
			)
			(layer "F.SilkS")
		)
		(fp_line
			(start -0.508 -0.9398)
			(end -0.508 0.9398)
			(stroke
				(width 0.1524)
				(type default)
			)
			(layer "F.SilkS")
		)
		(fp_rect
			(start -0.508 0.9398)
			(end 0.508 -0.9398)
			(stroke
				(width 0)
				(type default)
			)
			(fill no)
			(layer "F.CrtYd")
		)
		(fp_rect
			(start -0.508 0.9398)
			(end 0.508 -0.9398)
			(stroke
				(width 0)
				(type default)
			)
			(fill no)
			(layer "F.Fab")
		)
		(pad "1" smd custom
			(at 0 -0.4445 180)
			(size 0.1397 0.1397)
			(layers "F.Cu" "F.Mask" "F.Paste")
			(net "P5V_B_3_RF")
			(options
				(clearance outline)
				(anchor circle)
			)
			(primitives
				(gr_poly
					(pts
						(arc
							(start -0.1778 -0.2794)
							(mid -0.249642 -0.249642)
							(end -0.2794 -0.1778)
						)
						(arc
							(start -0.2794 0.1778)
							(mid -0.249642 0.249642)
							(end -0.1778 0.2794)
						)
						(arc
							(start 0.1778 0.2794)
							(mid 0.249642 0.249642)
							(end 0.2794 0.1778)
						)
						(arc
							(start 0.2794 -0.1778)
							(mid 0.249642 -0.249642)
							(end 0.1778 -0.2794)
						)
					)
					(width 0)
					(fill yes)
				)
			)
		)
		(pad "2" smd custom
			(at 0 0.4445 180)
			(size 0.1397 0.1397)
			(layers "F.Cu" "F.Mask" "F.Paste")
			(net "AGND_P5V_B_3")
			(options
				(clearance outline)
				(anchor circle)
			)
			(primitives
				(gr_poly
					(pts
						(arc
							(start -0.1778 -0.2794)
							(mid -0.249642 -0.249642)
							(end -0.2794 -0.1778)
						)
						(arc
							(start -0.2794 0.1778)
							(mid -0.249642 0.249642)
							(end -0.1778 0.2794)
						)
						(arc
							(start 0.1778 0.2794)
							(mid 0.249642 0.249642)
							(end 0.2794 0.1778)
						)
						(arc
							(start 0.2794 -0.1778)
							(mid 0.249642 -0.249642)
							(end 0.1778 -0.2794)
						)
					)
					(width 0)
					(fill yes)
				)
			)
		)
	)
	(footprint ""
		(layer "F.Cu")
		(at 346.075 -99.187)
		(property "Reference" "R434"
			(at 0 0 0)
			(layer "F.SilkS")
			(hide yes)
			(effects
				(font
					(size 1.27 1.27)
				)
			)
		)
		(property "Value" "130R3F-GP"
			(at -0.0254 -2.5146 0)
			(unlocked yes)
			(layer "F.Fab")
			(hide yes)
			(effects
				(font
					(size 1.016 1.016)
					(thickness 0.1524)
				)
			)
		)
		(property "Device Type" "R603H22"
			(at -0.0254 -4.0386 0)
			(unlocked yes)
			(layer "F.Fab")
			(hide yes)
			(effects
				(font
					(size 1.016 1.016)
					(thickness 0.1524)
				)
			)
		)
		(duplicate_pad_numbers_are_jumpers no)
		(fp_line
			(start -0.4826 0)
			(end -0.2032 0)
			(stroke
				(width 0.2032)
				(type default)
			)
			(layer "F.SilkS")
		)
		(fp_line
			(start 0.2032 0)
			(end 0.4826 0)
			(stroke
				(width 0.2032)
				(type default)
			)
			(layer "F.SilkS")
		)
		(fp_rect
			(start -0.5842 1.3335)
			(end 0.5842 -1.3335)
			(stroke
				(width 0)
				(type default)
			)
			(fill no)
			(layer "F.CrtYd")
		)
		(fp_rect
			(start -0.5842 1.3335)
			(end 0.5842 -1.3335)
			(stroke
				(width 0)
				(type default)
			)
			(fill no)
			(layer "F.Fab")
		)
		(pad "1" smd custom
			(at 0 -0.762)
			(size 0.2159 0.2159)
			(layers "F.Cu" "F.Mask" "F.Paste")
			(net "P5V_B_3")
			(options
				(clearance outline)
				(anchor circle)
			)
			(primitives
				(gr_poly
					(pts
						(arc
							(start -0.3302 -0.4318)
							(mid -0.402042 -0.402042)
							(end -0.4318 -0.3302)
						)
						(arc
							(start -0.4318 0.3302)
							(mid -0.402042 0.402042)
							(end -0.3302 0.4318)
						)
						(arc
							(start 0.3302 0.4318)
							(mid 0.402042 0.402042)
							(end 0.4318 0.3302)
						)
						(arc
							(start 0.4318 -0.3302)
							(mid 0.402042 -0.402042)
							(end 0.3302 -0.4318)
						)
					)
					(width 0)
					(fill yes)
				)
			)
		)
		(pad "2" smd custom
			(at 0 0.762)
			(size 0.2159 0.2159)
			(layers "F.Cu" "F.Mask" "F.Paste")
			(net "FLT_HDD19")
			(options
				(clearance outline)
				(anchor circle)
			)
			(primitives
				(gr_poly
					(pts
						(arc
							(start -0.3302 -0.4318)
							(mid -0.402042 -0.402042)
							(end -0.4318 -0.3302)
						)
						(arc
							(start -0.4318 0.3302)
							(mid -0.402042 0.402042)
							(end -0.3302 0.4318)
						)
						(arc
							(start 0.3302 0.4318)
							(mid 0.402042 0.402042)
							(end 0.4318 0.3302)
						)
						(arc
							(start 0.4318 -0.3302)
							(mid 0.402042 -0.402042)
							(end 0.3302 -0.4318)
						)
					)
					(width 0)
					(fill yes)
				)
			)
		)
	)
	(footprint ""
		(layer "F.Cu")
		(at 111.8616 -9.525 180)
		(property "Reference" "C390"
			(at 0 0 180)
			(layer "F.SilkS")
			(hide yes)
			(effects
				(font
					(size 1.27 1.27)
				)
			)
		)
		(property "Value" "SCD033U25V2KX-GP"
			(at 1.1811 -2.7051 180)
			(unlocked yes)
			(layer "F.Fab")
			(hide yes)
			(effects
				(font
					(size 1.016 1.016)
					(thickness 0.1524)
				)
			)
		)
		(property "Device Type" "C402H22"
			(at 1.1811 -4.2291 180)
			(unlocked yes)
			(layer "F.Fab")
			(hide yes)
			(effects
				(font
					(size 1.016 1.016)
					(thickness 0.1524)
				)
			)
		)
		(duplicate_pad_numbers_are_jumpers no)
		(fp_rect
			(start -0.4318 0.9525)
			(end 0.4318 -0.9525)
			(stroke
				(width 0)
				(type default)
			)
			(fill no)
			(layer "F.CrtYd")
		)
		(fp_rect
			(start -0.4318 0.9525)
			(end 0.4318 -0.9525)
			(stroke
				(width 0)
				(type default)
			)
			(fill no)
			(layer "F.Fab")
		)
		(pad "1" smd custom
			(at 0 -0.4445 180)
			(size 0.1524 0.1524)
			(layers "F.Cu" "F.Mask" "F.Paste")
			(net "P12V_B")
			(options
				(clearance outline)
				(anchor circle)
			)
			(primitives
				(gr_poly
					(pts
						(arc
							(start 0.3048 -0.2032)
							(mid 0.275042 -0.275042)
							(end 0.2032 -0.3048)
						)
						(arc
							(start -0.2032 -0.3048)
							(mid -0.275042 -0.275042)
							(end -0.3048 -0.2032)
						)
						(arc
							(start -0.3048 0.2032)
							(mid -0.275042 0.275042)
							(end -0.2032 0.3048)
						)
						(arc
							(start 0.2032 0.3048)
							(mid 0.275042 0.275042)
							(end 0.3048 0.2032)
						)
					)
					(width 0)
					(fill yes)
				)
			)
		)
		(pad "2" smd custom
			(at 0 0.4445 180)
			(size 0.1524 0.1524)
			(layers "F.Cu" "F.Mask" "F.Paste")
			(net "SW_HDD_N27")
			(options
				(clearance outline)
				(anchor circle)
			)
			(primitives
				(gr_poly
					(pts
						(arc
							(start 0.3048 -0.2032)
							(mid 0.275042 -0.275042)
							(end 0.2032 -0.3048)
						)
						(arc
							(start -0.2032 -0.3048)
							(mid -0.275042 -0.275042)
							(end -0.3048 -0.2032)
						)
						(arc
							(start -0.3048 0.2032)
							(mid -0.275042 0.275042)
							(end -0.2032 0.3048)
						)
						(arc
							(start 0.2032 0.3048)
							(mid 0.275042 0.275042)
							(end 0.3048 0.2032)
						)
					)
					(width 0)
					(fill yes)
				)
			)
		)
	)
	(footprint ""
		(layer "F.Cu")
		(at 326.738996 -373.761 -90)
		(property "Reference" "R946"
			(at 0 0 270)
			(layer "F.SilkS")
			(hide yes)
			(effects
				(font
					(size 1.27 1.27)
				)
			)
		)
		(property "Value" "0R2J-2-GP"
			(at 0.064008 -3.993896 270)
			(unlocked yes)
			(layer "F.Fab")
			(hide yes)
			(effects
				(font
					(size 1.016 1.016)
					(thickness 0.1524)
				)
			)
		)
		(property "Device Type" "R402H16"
			(at 0.064008 -5.517896 270)
			(unlocked yes)
			(layer "F.Fab")
			(hide yes)
			(effects
				(font
					(size 1.016 1.016)
					(thickness 0.1524)
				)
			)
		)
		(duplicate_pad_numbers_are_jumpers no)
		(fp_line
			(start -0.508 -0.9398)
			(end -0.508 0.9398)
			(stroke
				(width 0.1524)
				(type default)
			)
			(layer "F.SilkS")
		)
		(fp_line
			(start 0.508 -0.9398)
			(end -0.508 -0.9398)
			(stroke
				(width 0.1524)
				(type default)
			)
			(layer "F.SilkS")
		)
		(fp_rect
			(start -0.508 0.9398)
			(end 0.508 -0.9398)
			(stroke
				(width 0)
				(type default)
			)
			(fill no)
			(layer "F.CrtYd")
		)
		(fp_rect
			(start -0.508 0.9398)
			(end 0.508 -0.9398)
			(stroke
				(width 0)
				(type default)
			)
			(fill no)
			(layer "F.Fab")
		)
		(pad "1" smd custom
			(at 0 -0.4445 270)
			(size 0.1397 0.1397)
			(layers "F.Cu" "F.Mask" "F.Paste")
			(net "FAN_2_PWM")
			(options
				(clearance outline)
				(anchor circle)
			)
			(primitives
				(gr_poly
					(pts
						(arc
							(start -0.1778 -0.2794)
							(mid -0.249642 -0.249642)
							(end -0.2794 -0.1778)
						)
						(arc
							(start -0.2794 0.1778)
							(mid -0.249642 0.249642)
							(end -0.1778 0.2794)
						)
						(arc
							(start 0.1778 0.2794)
							(mid 0.249642 0.249642)
							(end 0.2794 0.1778)
						)
						(arc
							(start 0.2794 -0.1778)
							(mid 0.249642 -0.249642)
							(end 0.1778 -0.2794)
						)
					)
					(width 0)
					(fill yes)
				)
			)
		)
		(pad "2" smd custom
			(at 0 0.4445 270)
			(size 0.1397 0.1397)
			(layers "F.Cu" "F.Mask" "F.Paste")
			(net "PWM_OUT_FAN2")
			(options
				(clearance outline)
				(anchor circle)
			)
			(primitives
				(gr_poly
					(pts
						(arc
							(start -0.1778 -0.2794)
							(mid -0.249642 -0.249642)
							(end -0.2794 -0.1778)
						)
						(arc
							(start -0.2794 0.1778)
							(mid -0.249642 0.249642)
							(end -0.1778 0.2794)
						)
						(arc
							(start 0.1778 0.2794)
							(mid 0.249642 0.249642)
							(end 0.2794 0.1778)
						)
						(arc
							(start 0.2794 -0.1778)
							(mid 0.249642 -0.249642)
							(end 0.1778 -0.2794)
						)
					)
					(width 0)
					(fill yes)
				)
			)
		)
	)
	(footprint ""
		(layer "F.Cu")
		(at 243.0907 -356.4636 -90)
		(property "Reference" "R1038"
			(at 0 0 270)
			(layer "F.SilkS")
			(hide yes)
			(effects
				(font
					(size 1.27 1.27)
				)
			)
		)
		(property "Value" "10R2F-L-GP"
			(at 0.064008 -3.993896 270)
			(unlocked yes)
			(layer "F.Fab")
			(hide yes)
			(effects
				(font
					(size 1.016 1.016)
					(thickness 0.1524)
				)
			)
		)
		(property "Device Type" "R402H14"
			(at 0.064008 -5.517896 270)
			(unlocked yes)
			(layer "F.Fab")
			(hide yes)
			(effects
				(font
					(size 1.016 1.016)
					(thickness 0.1524)
				)
			)
		)
		(duplicate_pad_numbers_are_jumpers no)
		(fp_line
			(start -0.508 -0.9398)
			(end -0.508 0.9398)
			(stroke
				(width 0.1524)
				(type default)
			)
			(layer "F.SilkS")
		)
		(fp_line
			(start 0.508 -0.9398)
			(end -0.508 -0.9398)
			(stroke
				(width 0.1524)
				(type default)
			)
			(layer "F.SilkS")
		)
		(fp_rect
			(start -0.508 0.9398)
			(end 0.508 -0.9398)
			(stroke
				(width 0)
				(type default)
			)
			(fill no)
			(layer "F.CrtYd")
		)
		(fp_rect
			(start -0.508 0.9398)
			(end 0.508 -0.9398)
			(stroke
				(width 0)
				(type default)
			)
			(fill no)
			(layer "F.Fab")
		)
		(pad "1" smd custom
			(at 0 -0.4445 270)
			(size 0.1397 0.1397)
			(layers "F.Cu" "F.Mask" "F.Paste")
			(net "MB3_CM_SENSE_R1_N")
			(options
				(clearance outline)
				(anchor circle)
			)
			(primitives
				(gr_poly
					(pts
						(arc
							(start -0.1778 -0.2794)
							(mid -0.249642 -0.249642)
							(end -0.2794 -0.1778)
						)
						(arc
							(start -0.2794 0.1778)
							(mid -0.249642 0.249642)
							(end -0.1778 0.2794)
						)
						(arc
							(start 0.1778 0.2794)
							(mid 0.249642 0.249642)
							(end 0.2794 0.1778)
						)
						(arc
							(start 0.2794 -0.1778)
							(mid 0.249642 -0.249642)
							(end 0.1778 -0.2794)
						)
					)
					(width 0)
					(fill yes)
				)
			)
		)
		(pad "2" smd custom
			(at 0 0.4445 270)
			(size 0.1397 0.1397)
			(layers "F.Cu" "F.Mask" "F.Paste")
			(net "MB3_CM_SENSE_N")
			(options
				(clearance outline)
				(anchor circle)
			)
			(primitives
				(gr_poly
					(pts
						(arc
							(start -0.1778 -0.2794)
							(mid -0.249642 -0.249642)
							(end -0.2794 -0.1778)
						)
						(arc
							(start -0.2794 0.1778)
							(mid -0.249642 0.249642)
							(end -0.1778 0.2794)
						)
						(arc
							(start 0.1778 0.2794)
							(mid 0.249642 0.249642)
							(end 0.2794 0.1778)
						)
						(arc
							(start 0.2794 -0.1778)
							(mid 0.249642 -0.249642)
							(end 0.1778 -0.2794)
						)
					)
					(width 0)
					(fill yes)
				)
			)
		)
	)
	(footprint ""
		(layer "F.Cu")
		(at 113.03 -246.634)
		(property "Reference" "R219"
			(at 0 0 0)
			(layer "F.SilkS")
			(hide yes)
			(effects
				(font
					(size 1.27 1.27)
				)
			)
		)
		(property "Value" "0R2J-2-GP"
			(at 0.064008 -3.993896 0)
			(unlocked yes)
			(layer "F.Fab")
			(hide yes)
			(effects
				(font
					(size 1.016 1.016)
					(thickness 0.1524)
				)
			)
		)
		(property "Device Type" "R402H16"
			(at 0.064008 -5.517896 0)
			(unlocked yes)
			(layer "F.Fab")
			(hide yes)
			(effects
				(font
					(size 1.016 1.016)
					(thickness 0.1524)
				)
			)
		)
		(duplicate_pad_numbers_are_jumpers no)
		(fp_line
			(start -0.508 -0.9398)
			(end -0.508 0.9398)
			(stroke
				(width 0.1524)
				(type default)
			)
			(layer "F.SilkS")
		)
		(fp_line
			(start 0.508 -0.9398)
			(end -0.508 -0.9398)
			(stroke
				(width 0.1524)
				(type default)
			)
			(layer "F.SilkS")
		)
		(fp_rect
			(start -0.508 0.9398)
			(end 0.508 -0.9398)
			(stroke
				(width 0)
				(type default)
			)
			(fill no)
			(layer "F.CrtYd")
		)
		(fp_rect
			(start -0.508 0.9398)
			(end 0.508 -0.9398)
			(stroke
				(width 0)
				(type default)
			)
			(fill no)
			(layer "F.Fab")
		)
		(pad "1" smd custom
			(at 0 -0.4445)
			(size 0.1397 0.1397)
			(layers "F.Cu" "F.Mask" "F.Paste")
			(net "SW_HDD_G3")
			(options
				(clearance outline)
				(anchor circle)
			)
			(primitives
				(gr_poly
					(pts
						(arc
							(start -0.1778 -0.2794)
							(mid -0.249642 -0.249642)
							(end -0.2794 -0.1778)
						)
						(arc
							(start -0.2794 0.1778)
							(mid -0.249642 0.249642)
							(end -0.1778 0.2794)
						)
						(arc
							(start 0.1778 0.2794)
							(mid 0.249642 0.249642)
							(end 0.2794 0.1778)
						)
						(arc
							(start 0.2794 -0.1778)
							(mid 0.249642 -0.249642)
							(end 0.1778 -0.2794)
						)
					)
					(width 0)
					(fill yes)
				)
			)
		)
		(pad "2" smd custom
			(at 0 0.4445)
			(size 0.1397 0.1397)
			(layers "F.Cu" "F.Mask" "F.Paste")
			(net "SW_HDD_R3")
			(options
				(clearance outline)
				(anchor circle)
			)
			(primitives
				(gr_poly
					(pts
						(arc
							(start -0.1778 -0.2794)
							(mid -0.249642 -0.249642)
							(end -0.2794 -0.1778)
						)
						(arc
							(start -0.2794 0.1778)
							(mid -0.249642 0.249642)
							(end -0.1778 0.2794)
						)
						(arc
							(start 0.1778 0.2794)
							(mid 0.249642 0.249642)
							(end 0.2794 0.1778)
						)
						(arc
							(start 0.2794 -0.1778)
							(mid 0.249642 -0.249642)
							(end 0.1778 -0.2794)
						)
					)
					(width 0)
					(fill yes)
				)
			)
		)
	)
	(footprint ""
		(layer "F.Cu")
		(at 189.799976 -93.999812)
		(property "Reference" ""
			(at 0 0 0)
			(layer "F.SilkS")
			(hide yes)
			(effects
				(font
					(size 1.27 1.27)
				)
			)
		)
		(property "Value" "*"
			(at -8.398764 -8.057642 0)
			(unlocked yes)
			(layer "F.Fab")
			(hide yes)
			(effects
				(font
					(size 1.016 1.016)
					(thickness 0.1524)
				)
			)
		)
		(duplicate_pad_numbers_are_jumpers no)
		(fp_poly
			(pts
				(arc
					(start 7.3152 0)
					(mid 0 7.3152)
					(end -7.3152 0)
				)
				(arc
					(start -7.3152 -5.9944)
					(mid 0 -13.3096)
					(end 7.3152 -5.9944)
				)
			)
			(stroke
				(width 0)
				(type default)
			)
			(fill no)
			(layer "B.CrtYd")
		)
		(fp_poly
			(pts
				(arc
					(start 7.3152 0)
					(mid 0 7.3152)
					(end -7.3152 0)
				)
				(arc
					(start -7.3152 -5.9944)
					(mid 0 -13.3096)
					(end 7.3152 -5.9944)
				)
			)
			(stroke
				(width 0)
				(type default)
			)
			(fill no)
			(layer "F.CrtYd")
		)
		(fp_poly
			(pts
				(arc
					(start 7.3152 0)
					(mid 0 7.3152)
					(end -7.3152 0)
				)
				(arc
					(start -7.3152 -5.9944)
					(mid 0 -13.3096)
					(end 7.3152 -5.9944)
				)
			)
			(stroke
				(width 0)
				(type default)
			)
			(fill no)
			(layer "B.Fab")
		)
		(fp_poly
			(pts
				(arc
					(start 7.3152 0)
					(mid 0 7.3152)
					(end -7.3152 0)
				)
				(arc
					(start -7.3152 -5.9944)
					(mid 0 -13.3096)
					(end 7.3152 -5.9944)
				)
			)
			(stroke
				(width 0)
				(type default)
			)
			(fill no)
			(layer "F.Fab")
		)
		(pad "1" thru_hole oval
			(at 0 0)
			(size 14.0208 20.0152)
			(drill 0.0254
				(offset 0 -2.9972)
			)
			(layers "*.Cu" "*.Mask")
			(remove_unused_layers no)
			(net "Net_19")
			(clearance -1.002284)
			(thermal_gap 0.1524)
			(padstack
				(mode front_inner_back)
				(layer "Inner"
					(shape custom)
					(size 2.928012 2.928012)
					(options
						(anchor circle)
					)
					(primitives
						(gr_poly
							(pts
								(arc
									(start 4.571746 -2.084324)
									(mid 0.000333 7.430372)
									(end -4.571492 -2.084324)
								)
								(arc
									(start -4.571492 -2.084324)
									(mid -3.570296 -3.611977)
									(end -2.875026 -5.30098)
								)
								(arc
									(start -2.875026 -5.30098)
									(mid 0.000217 -7.43089)
									(end 2.87528 -5.30098)
								)
								(arc
									(start 2.87528 -5.30098)
									(mid 3.570511 -3.611956)
									(end 4.571746 -2.084324)
								)
							)
							(width 0)
							(fill yes)
						)
					)
					(clearance 0.1524)
				)
				(layer "B.Cu"
					(shape oval)
					(size 14.0208 20.0152)
					(offset 0 -2.9972)
					(clearance -1.002284)
				)
			)
		)
		(zone
			(layers "F.Cu" "B.Cu" "In1.Cu" "In2.Cu" "In3.Cu" "In4.Cu" "In5.Cu" "In6.Cu")
			(hatch none 0.5)
			(connect_pads
				(clearance 0)
			)
			(min_thickness 0.25)
			(keepout
				(tracks not_allowed)
				(vias allowed)
				(pads allowed)
				(copperpour not_allowed)
				(footprints allowed)
			)
			(placement
				(enabled no)
				(sheetname "")
			)
			(fill
				(thermal_gap 0.5)
				(thermal_bridge_width 0.5)
				(island_removal_mode 0)
			)
			(polygon
				(pts
					(arc
						(start 182.789576 -99.994212)
						(mid 189.799976 -107.004612)
						(end 196.810376 -99.994212)
					)
					(arc
						(start 196.810376 -93.999812)
						(mid 189.799976 -86.989412)
						(end 182.789576 -93.999812)
					)
				)
			)
		)
	)
	(footprint ""
		(layer "F.Cu")
		(at 368.427 -131.826 180)
		(property "Reference" "R521"
			(at 0 0 180)
			(layer "F.SilkS")
			(hide yes)
			(effects
				(font
					(size 1.27 1.27)
				)
			)
		)
		(property "Value" "4K7R2J-2-GP"
			(at 0.064008 -3.993896 180)
			(unlocked yes)
			(layer "F.Fab")
			(hide yes)
			(effects
				(font
					(size 1.016 1.016)
					(thickness 0.1524)
				)
			)
		)
		(property "Device Type" "R402H16"
			(at 0.064008 -5.517896 180)
			(unlocked yes)
			(layer "F.Fab")
			(hide yes)
			(effects
				(font
					(size 1.016 1.016)
					(thickness 0.1524)
				)
			)
		)
		(duplicate_pad_numbers_are_jumpers no)
		(fp_line
			(start 0.508 -0.9398)
			(end -0.508 -0.9398)
			(stroke
				(width 0.1524)
				(type default)
			)
			(layer "F.SilkS")
		)
		(fp_line
			(start -0.508 -0.9398)
			(end -0.508 0.9398)
			(stroke
				(width 0.1524)
				(type default)
			)
			(layer "F.SilkS")
		)
		(fp_rect
			(start -0.508 0.9398)
			(end 0.508 -0.9398)
			(stroke
				(width 0)
				(type default)
			)
			(fill no)
			(layer "F.CrtYd")
		)
		(fp_rect
			(start -0.508 0.9398)
			(end 0.508 -0.9398)
			(stroke
				(width 0)
				(type default)
			)
			(fill no)
			(layer "F.Fab")
		)
		(pad "1" smd custom
			(at 0 -0.4445 180)
			(size 0.1397 0.1397)
			(layers "F.Cu" "F.Mask" "F.Paste")
			(net "P12V_B")
			(options
				(clearance outline)
				(anchor circle)
			)
			(primitives
				(gr_poly
					(pts
						(arc
							(start -0.1778 -0.2794)
							(mid -0.249642 -0.249642)
							(end -0.2794 -0.1778)
						)
						(arc
							(start -0.2794 0.1778)
							(mid -0.249642 0.249642)
							(end -0.1778 0.2794)
						)
						(arc
							(start 0.1778 0.2794)
							(mid 0.249642 0.249642)
							(end 0.2794 0.1778)
						)
						(arc
							(start 0.2794 -0.1778)
							(mid 0.249642 -0.249642)
							(end 0.1778 -0.2794)
						)
					)
					(width 0)
					(fill yes)
				)
			)
		)
		(pad "2" smd custom
			(at 0 0.4445 180)
			(size 0.1397 0.1397)
			(layers "F.Cu" "F.Mask" "F.Paste")
			(net "SW_HDD_R19")
			(options
				(clearance outline)
				(anchor circle)
			)
			(primitives
				(gr_poly
					(pts
						(arc
							(start -0.1778 -0.2794)
							(mid -0.249642 -0.249642)
							(end -0.2794 -0.1778)
						)
						(arc
							(start -0.2794 0.1778)
							(mid -0.249642 0.249642)
							(end -0.1778 0.2794)
						)
						(arc
							(start 0.1778 0.2794)
							(mid 0.249642 0.249642)
							(end 0.2794 0.1778)
						)
						(arc
							(start 0.2794 -0.1778)
							(mid 0.249642 -0.249642)
							(end 0.1778 -0.2794)
						)
					)
					(width 0)
					(fill yes)
				)
			)
		)
	)
	(footprint ""
		(layer "F.Cu")
		(at 248.285 -304.038 90)
		(property "Reference" "R1089"
			(at 0 0 90)
			(layer "F.SilkS")
			(hide yes)
			(effects
				(font
					(size 1.27 1.27)
				)
			)
		)
		(property "Value" "0R2J-2-GP"
			(at 0.064008 -3.993896 90)
			(unlocked yes)
			(layer "F.Fab")
			(hide yes)
			(effects
				(font
					(size 1.016 1.016)
					(thickness 0.1524)
				)
			)
		)
		(property "Device Type" "R402H16"
			(at 0.064008 -5.517896 90)
			(unlocked yes)
			(layer "F.Fab")
			(hide yes)
			(effects
				(font
					(size 1.016 1.016)
					(thickness 0.1524)
				)
			)
		)
		(duplicate_pad_numbers_are_jumpers no)
		(fp_line
			(start 0.508 -0.9398)
			(end -0.508 -0.9398)
			(stroke
				(width 0.1524)
				(type default)
			)
			(layer "F.SilkS")
		)
		(fp_line
			(start -0.508 -0.9398)
			(end -0.508 0.9398)
			(stroke
				(width 0.1524)
				(type default)
			)
			(layer "F.SilkS")
		)
		(fp_rect
			(start -0.508 0.9398)
			(end 0.508 -0.9398)
			(stroke
				(width 0)
				(type default)
			)
			(fill no)
			(layer "F.CrtYd")
		)
		(fp_rect
			(start -0.508 0.9398)
			(end 0.508 -0.9398)
			(stroke
				(width 0)
				(type default)
			)
			(fill no)
			(layer "F.Fab")
		)
		(pad "1" smd custom
			(at 0 -0.4445 90)
			(size 0.1397 0.1397)
			(layers "F.Cu" "F.Mask" "F.Paste")
			(net "MAX31790_A_SDA")
			(options
				(clearance outline)
				(anchor circle)
			)
			(primitives
				(gr_poly
					(pts
						(arc
							(start -0.1778 -0.2794)
							(mid -0.249642 -0.249642)
							(end -0.2794 -0.1778)
						)
						(arc
							(start -0.2794 0.1778)
							(mid -0.249642 0.249642)
							(end -0.1778 0.2794)
						)
						(arc
							(start 0.1778 0.2794)
							(mid 0.249642 0.249642)
							(end 0.2794 0.1778)
						)
						(arc
							(start 0.2794 -0.1778)
							(mid 0.249642 -0.249642)
							(end 0.1778 -0.2794)
						)
					)
					(width 0)
					(fill yes)
				)
			)
		)
		(pad "2" smd custom
			(at 0 0.4445 90)
			(size 0.1397 0.1397)
			(layers "F.Cu" "F.Mask" "F.Paste")
			(net "I2C_DPB_A_SDA_BUF")
			(options
				(clearance outline)
				(anchor circle)
			)
			(primitives
				(gr_poly
					(pts
						(arc
							(start -0.1778 -0.2794)
							(mid -0.249642 -0.249642)
							(end -0.2794 -0.1778)
						)
						(arc
							(start -0.2794 0.1778)
							(mid -0.249642 0.249642)
							(end -0.1778 0.2794)
						)
						(arc
							(start 0.1778 0.2794)
							(mid 0.249642 0.249642)
							(end 0.2794 0.1778)
						)
						(arc
							(start 0.2794 -0.1778)
							(mid 0.249642 -0.249642)
							(end 0.1778 -0.2794)
						)
					)
					(width 0)
					(fill yes)
				)
			)
		)
	)
	(footprint ""
		(layer "F.Cu")
		(at 260.73481 -224.785174)
		(property "Reference" "C53"
			(at 0 0 0)
			(layer "F.SilkS")
			(hide yes)
			(effects
				(font
					(size 1.27 1.27)
				)
			)
		)
		(property "Value" "SCD1U16V2KX-3GP"
			(at 1.1811 -2.7051 0)
			(unlocked yes)
			(layer "F.Fab")
			(hide yes)
			(effects
				(font
					(size 1.016 1.016)
					(thickness 0.1524)
				)
			)
		)
		(property "Device Type" "C402H22"
			(at 1.1811 -4.2291 0)
			(unlocked yes)
			(layer "F.Fab")
			(hide yes)
			(effects
				(font
					(size 1.016 1.016)
					(thickness 0.1524)
				)
			)
		)
		(duplicate_pad_numbers_are_jumpers no)
		(fp_rect
			(start -0.4318 0.9525)
			(end 0.4318 -0.9525)
			(stroke
				(width 0)
				(type default)
			)
			(fill no)
			(layer "F.CrtYd")
		)
		(fp_rect
			(start -0.4318 0.9525)
			(end 0.4318 -0.9525)
			(stroke
				(width 0)
				(type default)
			)
			(fill no)
			(layer "F.Fab")
		)
		(pad "1" smd custom
			(at 0 -0.4445)
			(size 0.1524 0.1524)
			(layers "F.Cu" "F.Mask" "F.Paste")
			(net "P5V_B_4_SENSE")
			(options
				(clearance outline)
				(anchor circle)
			)
			(primitives
				(gr_poly
					(pts
						(arc
							(start 0.3048 -0.2032)
							(mid 0.275042 -0.275042)
							(end 0.2032 -0.3048)
						)
						(arc
							(start -0.2032 -0.3048)
							(mid -0.275042 -0.275042)
							(end -0.3048 -0.2032)
						)
						(arc
							(start -0.3048 0.2032)
							(mid -0.275042 0.275042)
							(end -0.2032 0.3048)
						)
						(arc
							(start 0.2032 0.3048)
							(mid 0.275042 0.275042)
							(end 0.3048 0.2032)
						)
					)
					(width 0)
					(fill yes)
				)
			)
		)
		(pad "2" smd custom
			(at 0 0.4445)
			(size 0.1524 0.1524)
			(layers "F.Cu" "F.Mask" "F.Paste")
			(net "GND")
			(options
				(clearance outline)
				(anchor circle)
			)
			(primitives
				(gr_poly
					(pts
						(arc
							(start 0.3048 -0.2032)
							(mid 0.275042 -0.275042)
							(end 0.2032 -0.3048)
						)
						(arc
							(start -0.2032 -0.3048)
							(mid -0.275042 -0.275042)
							(end -0.3048 -0.2032)
						)
						(arc
							(start -0.3048 0.2032)
							(mid -0.275042 0.275042)
							(end -0.2032 0.3048)
						)
						(arc
							(start 0.2032 0.3048)
							(mid 0.275042 0.275042)
							(end 0.3048 0.2032)
						)
					)
					(width 0)
					(fill yes)
				)
			)
		)
	)
	(footprint ""
		(layer "F.Cu")
		(at 111.379 -254.127 -90)
		(property "Reference" "C77"
			(at 0 0 270)
			(layer "F.SilkS")
			(hide yes)
			(effects
				(font
					(size 1.27 1.27)
				)
			)
		)
		(property "Value" "SCD033U25V2KX-GP"
			(at 1.1811 -2.7051 270)
			(unlocked yes)
			(layer "F.Fab")
			(hide yes)
			(effects
				(font
					(size 1.016 1.016)
					(thickness 0.1524)
				)
			)
		)
		(property "Device Type" "C402H22"
			(at 1.1811 -4.2291 270)
			(unlocked yes)
			(layer "F.Fab")
			(hide yes)
			(effects
				(font
					(size 1.016 1.016)
					(thickness 0.1524)
				)
			)
		)
		(duplicate_pad_numbers_are_jumpers no)
		(fp_rect
			(start -0.4318 0.9525)
			(end 0.4318 -0.9525)
			(stroke
				(width 0)
				(type default)
			)
			(fill no)
			(layer "F.CrtYd")
		)
		(fp_rect
			(start -0.4318 0.9525)
			(end 0.4318 -0.9525)
			(stroke
				(width 0)
				(type default)
			)
			(fill no)
			(layer "F.Fab")
		)
		(pad "1" smd custom
			(at 0 -0.4445 270)
			(size 0.1524 0.1524)
			(layers "F.Cu" "F.Mask" "F.Paste")
			(net "SW_HDD_P3")
			(options
				(clearance outline)
				(anchor circle)
			)
			(primitives
				(gr_poly
					(pts
						(arc
							(start 0.3048 -0.2032)
							(mid 0.275042 -0.275042)
							(end 0.2032 -0.3048)
						)
						(arc
							(start -0.2032 -0.3048)
							(mid -0.275042 -0.275042)
							(end -0.3048 -0.2032)
						)
						(arc
							(start -0.3048 0.2032)
							(mid -0.275042 0.275042)
							(end -0.2032 0.3048)
						)
						(arc
							(start 0.2032 0.3048)
							(mid 0.275042 0.275042)
							(end 0.3048 0.2032)
						)
					)
					(width 0)
					(fill yes)
				)
			)
		)
		(pad "2" smd custom
			(at 0 0.4445 270)
			(size 0.1524 0.1524)
			(layers "F.Cu" "F.Mask" "F.Paste")
			(net "GND")
			(options
				(clearance outline)
				(anchor circle)
			)
			(primitives
				(gr_poly
					(pts
						(arc
							(start 0.3048 -0.2032)
							(mid 0.275042 -0.275042)
							(end 0.2032 -0.3048)
						)
						(arc
							(start -0.2032 -0.3048)
							(mid -0.275042 -0.275042)
							(end -0.3048 -0.2032)
						)
						(arc
							(start -0.3048 0.2032)
							(mid -0.275042 0.275042)
							(end -0.2032 0.3048)
						)
						(arc
							(start 0.2032 0.3048)
							(mid 0.275042 0.275042)
							(end 0.3048 0.2032)
						)
					)
					(width 0)
					(fill yes)
				)
			)
		)
	)
	(footprint ""
		(layer "F.Cu")
		(at 458.1652 -25.6794 180)
		(property "Reference" "Q177"
			(at 0 0 180)
			(layer "F.SilkS")
			(hide yes)
			(effects
				(font
					(size 1.27 1.27)
				)
			)
		)
		(property "Value" "AO4406AL-GP"
			(at -3.707384 -1.5367 180)
			(unlocked yes)
			(layer "F.Fab")
			(hide yes)
			(effects
				(font
					(size 1.016 1.016)
					(thickness 0.1524)
				)
			)
		)
		(property "Device Type" "SOIC8H69"
			(at -3.707384 -3.0607 180)
			(unlocked yes)
			(layer "F.Fab")
			(hide yes)
			(effects
				(font
					(size 1.016 1.016)
					(thickness 0.1524)
				)
			)
		)
		(duplicate_pad_numbers_are_jumpers no)
		(fp_line
			(start 2.1336 1.4224)
			(end 2.1336 -1.4224)
			(stroke
				(width 0.1524)
				(type default)
			)
			(layer "F.SilkS")
		)
		(fp_line
			(start 2.1336 -1.4224)
			(end -2.7432 -1.4224)
			(stroke
				(width 0.1524)
				(type default)
			)
			(layer "F.SilkS")
		)
		(fp_line
			(start -2.1844 -0.0508)
			(end -2.7178 0.508)
			(stroke
				(width 0.1524)
				(type default)
			)
			(layer "F.SilkS")
		)
		(fp_line
			(start -2.6289 3.4417)
			(end -2.6289 1.4732)
			(stroke
				(width 0.381)
				(type default)
			)
			(layer "F.SilkS")
		)
		(fp_line
			(start -2.7178 -0.508)
			(end -2.1844 -0.0508)
			(stroke
				(width 0.1524)
				(type default)
			)
			(layer "F.SilkS")
		)
		(fp_line
			(start -2.7432 1.4224)
			(end 2.1336 1.4224)
			(stroke
				(width 0.1524)
				(type default)
			)
			(layer "F.SilkS")
		)
		(fp_line
			(start -2.7432 1.4224)
			(end -2.6416 1.4224)
			(stroke
				(width 0.1524)
				(type default)
			)
			(layer "F.SilkS")
		)
		(fp_line
			(start -2.7432 -1.4224)
			(end -2.7432 1.4224)
			(stroke
				(width 0.1524)
				(type default)
			)
			(layer "F.SilkS")
		)
		(fp_poly
			(pts
				(xy -2.2098 -1.4224) (xy -2.2098 1.4224) (xy 2.2098 1.4224) (xy 2.2098 -1.4224)
			)
			(stroke
				(width 0)
				(type default)
			)
			(fill yes)
			(layer "F.SilkS")
		)
		(fp_rect
			(start -2.450084 2.999994)
			(end 2.450084 -2.999994)
			(stroke
				(width 0)
				(type default)
			)
			(fill no)
			(layer "F.CrtYd")
		)
		(fp_poly
			(pts
				(xy -2.8194 3.6322) (xy -2.8194 -3.6322) (xy 2.8194 -3.6322) (xy 2.8194 1.18364) (xy 2.450084 1.18364)
				(xy 2.450084 -2.999994) (xy -2.450084 -2.999994) (xy -2.450084 2.999994) (xy 2.450084 2.999994)
				(xy 2.450084 1.18618) (xy 2.8194 1.18618) (xy 2.8194 3.6322)
			)
			(stroke
				(width 0)
				(type default)
			)
			(fill no)
			(layer "F.CrtYd")
		)
		(fp_rect
			(start -2.8194 3.6322)
			(end 2.8194 -3.6322)
			(stroke
				(width 0)
				(type default)
			)
			(fill no)
			(layer "F.Fab")
		)
		(pad "1" smd rect
			(at -1.905 2.54 180)
			(size 0.635 1.651)
			(layers "F.Cu" "F.Mask" "F.Paste")
			(net "P5V_HDD34")
		)
		(pad "2" smd rect
			(at -0.635 2.54 180)
			(size 0.635 1.651)
			(layers "F.Cu" "F.Mask" "F.Paste")
			(net "P5V_HDD34")
		)
		(pad "3" smd rect
			(at 0.635 2.54 180)
			(size 0.635 1.651)
			(layers "F.Cu" "F.Mask" "F.Paste")
			(net "P5V_HDD34")
		)
		(pad "4" smd rect
			(at 1.905 2.54 180)
			(size 0.635 1.651)
			(layers "F.Cu" "F.Mask" "F.Paste")
			(net "SW_HDD_P34")
		)
		(pad "5" smd rect
			(at 1.905 -2.54 180)
			(size 0.635 1.651)
			(layers "F.Cu" "F.Mask" "F.Paste")
			(net "P5V_B_4")
		)
		(pad "6" smd rect
			(at 0.635 -2.54 180)
			(size 0.635 1.651)
			(layers "F.Cu" "F.Mask" "F.Paste")
			(net "P5V_B_4")
		)
		(pad "7" smd rect
			(at -0.635 -2.54 180)
			(size 0.635 1.651)
			(layers "F.Cu" "F.Mask" "F.Paste")
			(net "P5V_B_4")
		)
		(pad "8" smd rect
			(at -1.905 -2.54 180)
			(size 0.635 1.651)
			(layers "F.Cu" "F.Mask" "F.Paste")
			(net "P5V_B_4")
		)
	)
	(footprint ""
		(layer "F.Cu")
		(at 333.629 -40.5892 -90)
		(property "Reference" "R761"
			(at 0 0 270)
			(layer "F.SilkS")
			(hide yes)
			(effects
				(font
					(size 1.27 1.27)
				)
			)
		)
		(property "Value" "2R6F-GP"
			(at -0.0508 -4.8514 270)
			(unlocked yes)
			(layer "F.Fab")
			(hide yes)
			(effects
				(font
					(size 1.016 1.016)
					(thickness 0.1524)
				)
			)
		)
		(property "Device Type" "R1206H26"
			(at 0 -6.3754 270)
			(unlocked yes)
			(layer "F.Fab")
			(hide yes)
			(effects
				(font
					(size 1.016 1.016)
					(thickness 0.1524)
				)
			)
		)
		(duplicate_pad_numbers_are_jumpers no)
		(fp_line
			(start -1.016 2.2352)
			(end -1.016 -2.2352)
			(stroke
				(width 0.1524)
				(type default)
			)
			(layer "F.SilkS")
		)
		(fp_line
			(start 1.016 2.2352)
			(end -1.016 2.2352)
			(stroke
				(width 0.1524)
				(type default)
			)
			(layer "F.SilkS")
		)
		(fp_line
			(start -1.016 -2.2352)
			(end 1.016 -2.2352)
			(stroke
				(width 0.1524)
				(type default)
			)
			(layer "F.SilkS")
		)
		(fp_line
			(start 1.016 -2.2352)
			(end 1.016 2.2352)
			(stroke
				(width 0.1524)
				(type default)
			)
			(layer "F.SilkS")
		)
		(fp_rect
			(start -1.0922 2.3114)
			(end 1.0922 -2.3114)
			(stroke
				(width 0)
				(type default)
			)
			(fill no)
			(layer "F.CrtYd")
		)
		(fp_poly
			(pts
				(xy -1.0922 -2.3114) (xy 1.0922 -2.3114) (xy 1.0922 2.3114) (xy -1.0922 2.3114)
			)
			(stroke
				(width 0)
				(type default)
			)
			(fill no)
			(layer "F.Fab")
		)
		(pad "1" smd rect
			(at 0 -1.397 270)
			(size 1.651 1.27)
			(layers "F.Cu" "F.Mask" "F.Paste")
			(net "P12V_HDD30")
		)
		(pad "2" smd rect
			(at 0 1.397 270)
			(size 1.651 1.27)
			(layers "F.Cu" "F.Mask" "F.Paste")
			(net "12V_PRE_30")
		)
	)
	(footprint ""
		(layer "F.Cu")
		(at 77.978 -139.446 -90)
		(property "Reference" "R407"
			(at 0 0 270)
			(layer "F.SilkS")
			(hide yes)
			(effects
				(font
					(size 1.27 1.27)
				)
			)
		)
		(property "Value" "300KR2F-GP"
			(at 0.064008 -3.993896 270)
			(unlocked yes)
			(layer "F.Fab")
			(hide yes)
			(effects
				(font
					(size 1.016 1.016)
					(thickness 0.1524)
				)
			)
		)
		(property "Device Type" "R402H16"
			(at 0.064008 -5.517896 270)
			(unlocked yes)
			(layer "F.Fab")
			(hide yes)
			(effects
				(font
					(size 1.016 1.016)
					(thickness 0.1524)
				)
			)
		)
		(duplicate_pad_numbers_are_jumpers no)
		(fp_line
			(start -0.508 -0.9398)
			(end -0.508 0.9398)
			(stroke
				(width 0.1524)
				(type default)
			)
			(layer "F.SilkS")
		)
		(fp_line
			(start 0.508 -0.9398)
			(end -0.508 -0.9398)
			(stroke
				(width 0.1524)
				(type default)
			)
			(layer "F.SilkS")
		)
		(fp_rect
			(start -0.508 0.9398)
			(end 0.508 -0.9398)
			(stroke
				(width 0)
				(type default)
			)
			(fill no)
			(layer "F.CrtYd")
		)
		(fp_rect
			(start -0.508 0.9398)
			(end 0.508 -0.9398)
			(stroke
				(width 0)
				(type default)
			)
			(fill no)
			(layer "F.Fab")
		)
		(pad "1" smd custom
			(at 0 -0.4445 270)
			(size 0.1397 0.1397)
			(layers "F.Cu" "F.Mask" "F.Paste")
			(net "SW_HDD_N14")
			(options
				(clearance outline)
				(anchor circle)
			)
			(primitives
				(gr_poly
					(pts
						(arc
							(start -0.1778 -0.2794)
							(mid -0.249642 -0.249642)
							(end -0.2794 -0.1778)
						)
						(arc
							(start -0.2794 0.1778)
							(mid -0.249642 0.249642)
							(end -0.1778 0.2794)
						)
						(arc
							(start 0.1778 0.2794)
							(mid 0.249642 0.249642)
							(end 0.2794 0.1778)
						)
						(arc
							(start 0.2794 -0.1778)
							(mid 0.249642 -0.249642)
							(end 0.1778 -0.2794)
						)
					)
					(width 0)
					(fill yes)
				)
			)
		)
		(pad "2" smd custom
			(at 0 0.4445 270)
			(size 0.1397 0.1397)
			(layers "F.Cu" "F.Mask" "F.Paste")
			(net "P12V_B")
			(options
				(clearance outline)
				(anchor circle)
			)
			(primitives
				(gr_poly
					(pts
						(arc
							(start -0.1778 -0.2794)
							(mid -0.249642 -0.249642)
							(end -0.2794 -0.1778)
						)
						(arc
							(start -0.2794 0.1778)
							(mid -0.249642 0.249642)
							(end -0.1778 0.2794)
						)
						(arc
							(start 0.1778 0.2794)
							(mid 0.249642 0.249642)
							(end 0.2794 0.1778)
						)
						(arc
							(start 0.2794 -0.1778)
							(mid 0.249642 -0.249642)
							(end 0.1778 -0.2794)
						)
					)
					(width 0)
					(fill yes)
				)
			)
		)
	)
	(footprint ""
		(layer "F.Cu")
		(at 109.474 -139.446 -90)
		(property "Reference" "R430"
			(at 0 0 270)
			(layer "F.SilkS")
			(hide yes)
			(effects
				(font
					(size 1.27 1.27)
				)
			)
		)
		(property "Value" "300KR2F-GP"
			(at 0.064008 -3.993896 270)
			(unlocked yes)
			(layer "F.Fab")
			(hide yes)
			(effects
				(font
					(size 1.016 1.016)
					(thickness 0.1524)
				)
			)
		)
		(property "Device Type" "R402H16"
			(at 0.064008 -5.517896 270)
			(unlocked yes)
			(layer "F.Fab")
			(hide yes)
			(effects
				(font
					(size 1.016 1.016)
					(thickness 0.1524)
				)
			)
		)
		(duplicate_pad_numbers_are_jumpers no)
		(fp_line
			(start -0.508 -0.9398)
			(end -0.508 0.9398)
			(stroke
				(width 0.1524)
				(type default)
			)
			(layer "F.SilkS")
		)
		(fp_line
			(start 0.508 -0.9398)
			(end -0.508 -0.9398)
			(stroke
				(width 0.1524)
				(type default)
			)
			(layer "F.SilkS")
		)
		(fp_rect
			(start -0.508 0.9398)
			(end 0.508 -0.9398)
			(stroke
				(width 0)
				(type default)
			)
			(fill no)
			(layer "F.CrtYd")
		)
		(fp_rect
			(start -0.508 0.9398)
			(end 0.508 -0.9398)
			(stroke
				(width 0)
				(type default)
			)
			(fill no)
			(layer "F.Fab")
		)
		(pad "1" smd custom
			(at 0 -0.4445 270)
			(size 0.1397 0.1397)
			(layers "F.Cu" "F.Mask" "F.Paste")
			(net "SW_HDD_N15")
			(options
				(clearance outline)
				(anchor circle)
			)
			(primitives
				(gr_poly
					(pts
						(arc
							(start -0.1778 -0.2794)
							(mid -0.249642 -0.249642)
							(end -0.2794 -0.1778)
						)
						(arc
							(start -0.2794 0.1778)
							(mid -0.249642 0.249642)
							(end -0.1778 0.2794)
						)
						(arc
							(start 0.1778 0.2794)
							(mid 0.249642 0.249642)
							(end 0.2794 0.1778)
						)
						(arc
							(start 0.2794 -0.1778)
							(mid 0.249642 -0.249642)
							(end 0.1778 -0.2794)
						)
					)
					(width 0)
					(fill yes)
				)
			)
		)
		(pad "2" smd custom
			(at 0 0.4445 270)
			(size 0.1397 0.1397)
			(layers "F.Cu" "F.Mask" "F.Paste")
			(net "P12V_B")
			(options
				(clearance outline)
				(anchor circle)
			)
			(primitives
				(gr_poly
					(pts
						(arc
							(start -0.1778 -0.2794)
							(mid -0.249642 -0.249642)
							(end -0.2794 -0.1778)
						)
						(arc
							(start -0.2794 0.1778)
							(mid -0.249642 0.249642)
							(end -0.1778 0.2794)
						)
						(arc
							(start 0.1778 0.2794)
							(mid 0.249642 0.249642)
							(end 0.2794 0.1778)
						)
						(arc
							(start 0.2794 -0.1778)
							(mid 0.249642 -0.249642)
							(end 0.1778 -0.2794)
						)
					)
					(width 0)
					(fill yes)
				)
			)
		)
	)
	(footprint ""
		(layer "F.Cu")
		(at 337.312 -133.858 90)
		(property "Reference" "D18"
			(at 0 0 90)
			(layer "F.SilkS")
			(hide yes)
			(effects
				(font
					(size 1.27 1.27)
				)
			)
		)
		(property "Value" "RB551V30-GP"
			(at 0 -6.7818 90)
			(unlocked yes)
			(layer "F.Fab")
			(hide yes)
			(effects
				(font
					(size 1.016 1.016)
					(thickness 0.1524)
				)
			)
		)
		(property "Device Type" "SOD323AKH38"
			(at 0 -8.6868 90)
			(unlocked yes)
			(layer "F.Fab")
			(hide yes)
			(effects
				(font
					(size 1.016 1.016)
					(thickness 0.1524)
				)
			)
		)
		(duplicate_pad_numbers_are_jumpers no)
		(fp_line
			(start 0.889 -1.9304)
			(end 0.889 2.159)
			(stroke
				(width 0.1524)
				(type default)
			)
			(layer "F.SilkS")
		)
		(fp_line
			(start -0.889 -1.9304)
			(end 0.889 -1.9304)
			(stroke
				(width 0.1524)
				(type default)
			)
			(layer "F.SilkS")
		)
		(fp_line
			(start 0.762 2.0574)
			(end -0.762 2.0574)
			(stroke
				(width 0.508)
				(type default)
			)
			(layer "F.SilkS")
		)
		(fp_line
			(start 0.889 2.159)
			(end -0.889 2.159)
			(stroke
				(width 0.1524)
				(type default)
			)
			(layer "F.SilkS")
		)
		(fp_line
			(start -0.889 2.159)
			(end -0.889 -1.9304)
			(stroke
				(width 0.1524)
				(type default)
			)
			(layer "F.SilkS")
		)
		(fp_rect
			(start -1.016 2.3114)
			(end 1.016 -2.0066)
			(stroke
				(width 0)
				(type default)
			)
			(fill no)
			(layer "F.CrtYd")
		)
		(fp_poly
			(pts
				(xy -1.016 -2.0066) (xy 1.016 -2.0066) (xy 1.016 2.3114) (xy -1.016 2.3114)
			)
			(stroke
				(width 0)
				(type default)
			)
			(fill no)
			(layer "F.Fab")
		)
		(pad "A" smd rect
			(at 0 -1.143 90)
			(size 0.5588 1.016)
			(layers "F.Cu" "F.Mask" "F.Paste")
			(net "SW_HDD_R18")
		)
		(pad "K" smd rect
			(at 0 1.143 90)
			(size 0.5588 1.016)
			(layers "F.Cu" "F.Mask" "F.Paste")
			(net "SW_HDD_N18")
		)
	)
	(footprint ""
		(layer "F.Cu")
		(at 319.786 -13.6271 180)
		(property "Reference" "VIA61"
			(at 0 0 180)
			(layer "F.SilkS")
			(hide yes)
			(effects
				(font
					(size 1.27 1.27)
				)
			)
		)
		(property "Value" "100OHM-8L-2D36MM-L18-GP"
			(at 3.8989 0.5715 180)
			(unlocked yes)
			(layer "F.Fab")
			(hide yes)
			(effects
				(font
					(size 1.016 1.016)
					(thickness 0.1524)
				)
			)
		)
		(property "Device Type" "VIA-PCIE-4P-414097"
			(at 3.8989 -0.9525 180)
			(unlocked yes)
			(layer "F.Fab")
			(hide yes)
			(effects
				(font
					(size 1.016 1.016)
					(thickness 0.1524)
				)
			)
		)
		(duplicate_pad_numbers_are_jumpers no)
		(fp_rect
			(start -2.0701 0.4826)
			(end 2.0701 -0.4826)
			(stroke
				(width 0)
				(type default)
			)
			(fill no)
			(layer "F.CrtYd")
		)
		(fp_rect
			(start -2.0701 0.4826)
			(end 2.0701 -0.4826)
			(stroke
				(width 0)
				(type default)
			)
			(fill no)
			(layer "F.Fab")
		)
		(pad "1" thru_hole circle
			(at -1.5875 0 180)
			(size 0.508 0.508)
			(drill 0.254)
			(layers "*.Cu" "*.Mask")
			(remove_unused_layers no)
			(net "GND")
			(clearance 0.2286)
			(thermal_gap 0.2286)
		)
		(pad "2" thru_hole circle
			(at -0.5715 0 180)
			(size 0.508 0.508)
			(drill 0.254)
			(layers "*.Cu" "*.Mask")
			(remove_unused_layers no)
			(net "PHY_SCC_B_TO_DRV_B_30_DP")
			(clearance 0.2286)
			(thermal_gap 0.2286)
		)
		(pad "3" thru_hole circle
			(at 0.5715 0 180)
			(size 0.508 0.508)
			(drill 0.254)
			(layers "*.Cu" "*.Mask")
			(remove_unused_layers no)
			(net "PHY_SCC_B_TO_DRV_B_30_DN")
			(clearance 0.2286)
			(thermal_gap 0.2286)
		)
		(pad "4" thru_hole circle
			(at 1.5875 0 180)
			(size 0.508 0.508)
			(drill 0.254)
			(layers "*.Cu" "*.Mask")
			(remove_unused_layers no)
			(net "GND")
			(clearance 0.2286)
			(thermal_gap 0.2286)
		)
	)
	(footprint ""
		(layer "F.Cu")
		(at 49.911 -131.572)
		(property "Reference" "R386"
			(at 0 0 0)
			(layer "F.SilkS")
			(hide yes)
			(effects
				(font
					(size 1.27 1.27)
				)
			)
		)
		(property "Value" "0R2J-2-GP"
			(at 0.064008 -3.993896 0)
			(unlocked yes)
			(layer "F.Fab")
			(hide yes)
			(effects
				(font
					(size 1.016 1.016)
					(thickness 0.1524)
				)
			)
		)
		(property "Device Type" "R402H16"
			(at 0.064008 -5.517896 0)
			(unlocked yes)
			(layer "F.Fab")
			(hide yes)
			(effects
				(font
					(size 1.016 1.016)
					(thickness 0.1524)
				)
			)
		)
		(duplicate_pad_numbers_are_jumpers no)
		(fp_line
			(start -0.508 -0.9398)
			(end -0.508 0.9398)
			(stroke
				(width 0.1524)
				(type default)
			)
			(layer "F.SilkS")
		)
		(fp_line
			(start 0.508 -0.9398)
			(end -0.508 -0.9398)
			(stroke
				(width 0.1524)
				(type default)
			)
			(layer "F.SilkS")
		)
		(fp_rect
			(start -0.508 0.9398)
			(end 0.508 -0.9398)
			(stroke
				(width 0)
				(type default)
			)
			(fill no)
			(layer "F.CrtYd")
		)
		(fp_rect
			(start -0.508 0.9398)
			(end 0.508 -0.9398)
			(stroke
				(width 0)
				(type default)
			)
			(fill no)
			(layer "F.Fab")
		)
		(pad "1" smd custom
			(at 0 -0.4445)
			(size 0.1397 0.1397)
			(layers "F.Cu" "F.Mask" "F.Paste")
			(net "SW_HDD_G13")
			(options
				(clearance outline)
				(anchor circle)
			)
			(primitives
				(gr_poly
					(pts
						(arc
							(start -0.1778 -0.2794)
							(mid -0.249642 -0.249642)
							(end -0.2794 -0.1778)
						)
						(arc
							(start -0.2794 0.1778)
							(mid -0.249642 0.249642)
							(end -0.1778 0.2794)
						)
						(arc
							(start 0.1778 0.2794)
							(mid 0.249642 0.249642)
							(end 0.2794 0.1778)
						)
						(arc
							(start 0.2794 -0.1778)
							(mid 0.249642 -0.249642)
							(end 0.1778 -0.2794)
						)
					)
					(width 0)
					(fill yes)
				)
			)
		)
		(pad "2" smd custom
			(at 0 0.4445)
			(size 0.1397 0.1397)
			(layers "F.Cu" "F.Mask" "F.Paste")
			(net "SW_HDD_R13")
			(options
				(clearance outline)
				(anchor circle)
			)
			(primitives
				(gr_poly
					(pts
						(arc
							(start -0.1778 -0.2794)
							(mid -0.249642 -0.249642)
							(end -0.2794 -0.1778)
						)
						(arc
							(start -0.2794 0.1778)
							(mid -0.249642 0.249642)
							(end -0.1778 0.2794)
						)
						(arc
							(start 0.1778 0.2794)
							(mid 0.249642 0.249642)
							(end 0.2794 0.1778)
						)
						(arc
							(start 0.2794 -0.1778)
							(mid 0.249642 -0.249642)
							(end 0.1778 -0.2794)
						)
					)
					(width 0)
					(fill yes)
				)
			)
		)
	)
	(footprint ""
		(layer "F.Cu")
		(at 329.819 -37.846 180)
		(property "Reference" "C420"
			(at 0 0 180)
			(layer "F.SilkS")
			(hide yes)
			(effects
				(font
					(size 1.27 1.27)
				)
			)
		)
		(property "Value" "SC1U16V3KX-5GP"
			(at 0 -2.8194 180)
			(unlocked yes)
			(layer "F.Fab")
			(hide yes)
			(effects
				(font
					(size 1.016 1.016)
					(thickness 0.1524)
				)
			)
		)
		(property "Device Type" "C603H36"
			(at 0 -4.3434 180)
			(unlocked yes)
			(layer "F.Fab")
			(hide yes)
			(effects
				(font
					(size 1.016 1.016)
					(thickness 0.1524)
				)
			)
		)
		(duplicate_pad_numbers_are_jumpers no)
		(fp_line
			(start 0.508 0)
			(end -0.508 0)
			(stroke
				(width 0.2032)
				(type default)
			)
			(layer "F.SilkS")
		)
		(fp_rect
			(start -0.5842 1.3335)
			(end 0.5842 -1.3335)
			(stroke
				(width 0)
				(type default)
			)
			(fill no)
			(layer "F.CrtYd")
		)
		(fp_rect
			(start -0.5842 1.3335)
			(end 0.5842 -1.3335)
			(stroke
				(width 0)
				(type default)
			)
			(fill no)
			(layer "F.Fab")
		)
		(pad "1" smd custom
			(at 0 -0.762 180)
			(size 0.2159 0.2159)
			(layers "F.Cu" "F.Mask" "F.Paste")
			(net "P5V_HDD30")
			(options
				(clearance outline)
				(anchor circle)
			)
			(primitives
				(gr_poly
					(pts
						(arc
							(start -0.3302 -0.4318)
							(mid -0.402042 -0.402042)
							(end -0.4318 -0.3302)
						)
						(arc
							(start -0.4318 0.3302)
							(mid -0.402042 0.402042)
							(end -0.3302 0.4318)
						)
						(arc
							(start 0.3302 0.4318)
							(mid 0.402042 0.402042)
							(end 0.4318 0.3302)
						)
						(arc
							(start 0.4318 -0.3302)
							(mid 0.402042 -0.402042)
							(end 0.3302 -0.4318)
						)
					)
					(width 0)
					(fill yes)
				)
			)
		)
		(pad "2" smd custom
			(at 0 0.762 180)
			(size 0.2159 0.2159)
			(layers "F.Cu" "F.Mask" "F.Paste")
			(net "GND")
			(options
				(clearance outline)
				(anchor circle)
			)
			(primitives
				(gr_poly
					(pts
						(arc
							(start -0.3302 -0.4318)
							(mid -0.402042 -0.402042)
							(end -0.4318 -0.3302)
						)
						(arc
							(start -0.4318 0.3302)
							(mid -0.402042 0.402042)
							(end -0.3302 0.4318)
						)
						(arc
							(start 0.3302 0.4318)
							(mid 0.402042 0.402042)
							(end 0.4318 0.3302)
						)
						(arc
							(start 0.4318 -0.3302)
							(mid 0.402042 -0.402042)
							(end 0.3302 -0.4318)
						)
					)
					(width 0)
					(fill yes)
				)
			)
		)
	)
	(footprint ""
		(layer "F.Cu")
		(at 248.285 -307.086 90)
		(property "Reference" "R1090"
			(at 0 0 90)
			(layer "F.SilkS")
			(hide yes)
			(effects
				(font
					(size 1.27 1.27)
				)
			)
		)
		(property "Value" "0R2J-2-GP"
			(at 0.064008 -3.993896 90)
			(unlocked yes)
			(layer "F.Fab")
			(hide yes)
			(effects
				(font
					(size 1.016 1.016)
					(thickness 0.1524)
				)
			)
		)
		(property "Device Type" "R402H16"
			(at 0.064008 -5.517896 90)
			(unlocked yes)
			(layer "F.Fab")
			(hide yes)
			(effects
				(font
					(size 1.016 1.016)
					(thickness 0.1524)
				)
			)
		)
		(duplicate_pad_numbers_are_jumpers no)
		(fp_line
			(start 0.508 -0.9398)
			(end -0.508 -0.9398)
			(stroke
				(width 0.1524)
				(type default)
			)
			(layer "F.SilkS")
		)
		(fp_line
			(start -0.508 -0.9398)
			(end -0.508 0.9398)
			(stroke
				(width 0.1524)
				(type default)
			)
			(layer "F.SilkS")
		)
		(fp_rect
			(start -0.508 0.9398)
			(end 0.508 -0.9398)
			(stroke
				(width 0)
				(type default)
			)
			(fill no)
			(layer "F.CrtYd")
		)
		(fp_rect
			(start -0.508 0.9398)
			(end 0.508 -0.9398)
			(stroke
				(width 0)
				(type default)
			)
			(fill no)
			(layer "F.Fab")
		)
		(pad "1" smd custom
			(at 0 -0.4445 90)
			(size 0.1397 0.1397)
			(layers "F.Cu" "F.Mask" "F.Paste")
			(net "MAX31790_A_PWM_ST0")
			(options
				(clearance outline)
				(anchor circle)
			)
			(primitives
				(gr_poly
					(pts
						(arc
							(start -0.1778 -0.2794)
							(mid -0.249642 -0.249642)
							(end -0.2794 -0.1778)
						)
						(arc
							(start -0.2794 0.1778)
							(mid -0.249642 0.249642)
							(end -0.1778 0.2794)
						)
						(arc
							(start 0.1778 0.2794)
							(mid 0.249642 0.249642)
							(end 0.2794 0.1778)
						)
						(arc
							(start 0.2794 -0.1778)
							(mid 0.249642 -0.249642)
							(end 0.1778 -0.2794)
						)
					)
					(width 0)
					(fill yes)
				)
			)
		)
		(pad "2" smd custom
			(at 0 0.4445 90)
			(size 0.1397 0.1397)
			(layers "F.Cu" "F.Mask" "F.Paste")
			(net "GND")
			(options
				(clearance outline)
				(anchor circle)
			)
			(primitives
				(gr_poly
					(pts
						(arc
							(start -0.1778 -0.2794)
							(mid -0.249642 -0.249642)
							(end -0.2794 -0.1778)
						)
						(arc
							(start -0.2794 0.1778)
							(mid -0.249642 0.249642)
							(end -0.1778 0.2794)
						)
						(arc
							(start 0.1778 0.2794)
							(mid 0.249642 0.249642)
							(end 0.2794 0.1778)
						)
						(arc
							(start 0.2794 -0.1778)
							(mid 0.249642 -0.249642)
							(end 0.1778 -0.2794)
						)
					)
					(width 0)
					(fill yes)
				)
			)
		)
	)
	(footprint ""
		(layer "F.Cu")
		(at 433.324 -258.826 90)
		(property "Reference" "C156"
			(at 0 0 90)
			(layer "F.SilkS")
			(hide yes)
			(effects
				(font
					(size 1.27 1.27)
				)
			)
		)
		(property "Value" "SCD033U25V2KX-GP"
			(at 1.1811 -2.7051 90)
			(unlocked yes)
			(layer "F.Fab")
			(hide yes)
			(effects
				(font
					(size 1.016 1.016)
					(thickness 0.1524)
				)
			)
		)
		(property "Device Type" "C402H22"
			(at 1.1811 -4.2291 90)
			(unlocked yes)
			(layer "F.Fab")
			(hide yes)
			(effects
				(font
					(size 1.016 1.016)
					(thickness 0.1524)
				)
			)
		)
		(duplicate_pad_numbers_are_jumpers no)
		(fp_rect
			(start -0.4318 0.9525)
			(end 0.4318 -0.9525)
			(stroke
				(width 0)
				(type default)
			)
			(fill no)
			(layer "F.CrtYd")
		)
		(fp_rect
			(start -0.4318 0.9525)
			(end 0.4318 -0.9525)
			(stroke
				(width 0)
				(type default)
			)
			(fill no)
			(layer "F.Fab")
		)
		(pad "1" smd custom
			(at 0 -0.4445 90)
			(size 0.1524 0.1524)
			(layers "F.Cu" "F.Mask" "F.Paste")
			(net "P12V_B")
			(options
				(clearance outline)
				(anchor circle)
			)
			(primitives
				(gr_poly
					(pts
						(arc
							(start 0.3048 -0.2032)
							(mid 0.275042 -0.275042)
							(end 0.2032 -0.3048)
						)
						(arc
							(start -0.2032 -0.3048)
							(mid -0.275042 -0.275042)
							(end -0.3048 -0.2032)
						)
						(arc
							(start -0.3048 0.2032)
							(mid -0.275042 0.275042)
							(end -0.2032 0.3048)
						)
						(arc
							(start 0.2032 0.3048)
							(mid 0.275042 0.275042)
							(end 0.3048 0.2032)
						)
					)
					(width 0)
					(fill yes)
				)
			)
		)
		(pad "2" smd custom
			(at 0 0.4445 90)
			(size 0.1524 0.1524)
			(layers "F.Cu" "F.Mask" "F.Paste")
			(net "SW_HDD_N9")
			(options
				(clearance outline)
				(anchor circle)
			)
			(primitives
				(gr_poly
					(pts
						(arc
							(start 0.3048 -0.2032)
							(mid 0.275042 -0.275042)
							(end 0.2032 -0.3048)
						)
						(arc
							(start -0.2032 -0.3048)
							(mid -0.275042 -0.275042)
							(end -0.3048 -0.2032)
						)
						(arc
							(start -0.3048 0.2032)
							(mid -0.275042 0.275042)
							(end -0.2032 0.3048)
						)
						(arc
							(start 0.2032 0.3048)
							(mid 0.275042 0.275042)
							(end 0.3048 0.2032)
						)
					)
					(width 0)
					(fill yes)
				)
			)
		)
	)
	(footprint ""
		(layer "F.Cu")
		(at 440.931554 -118.03507 -90)
		(property "Reference" "R1161"
			(at 0 0 270)
			(layer "F.SilkS")
			(hide yes)
			(effects
				(font
					(size 1.27 1.27)
				)
			)
		)
		(property "Value" "15KR2F-GP"
			(at 0.064008 -3.993896 270)
			(unlocked yes)
			(layer "F.Fab")
			(hide yes)
			(effects
				(font
					(size 1.016 1.016)
					(thickness 0.1524)
				)
			)
		)
		(property "Device Type" "R402H16"
			(at 0.064008 -5.517896 270)
			(unlocked yes)
			(layer "F.Fab")
			(hide yes)
			(effects
				(font
					(size 1.016 1.016)
					(thickness 0.1524)
				)
			)
		)
		(duplicate_pad_numbers_are_jumpers no)
		(fp_line
			(start -0.508 -0.9398)
			(end -0.508 0.9398)
			(stroke
				(width 0.1524)
				(type default)
			)
			(layer "F.SilkS")
		)
		(fp_line
			(start 0.508 -0.9398)
			(end -0.508 -0.9398)
			(stroke
				(width 0.1524)
				(type default)
			)
			(layer "F.SilkS")
		)
		(fp_rect
			(start -0.508 0.9398)
			(end 0.508 -0.9398)
			(stroke
				(width 0)
				(type default)
			)
			(fill no)
			(layer "F.CrtYd")
		)
		(fp_rect
			(start -0.508 0.9398)
			(end 0.508 -0.9398)
			(stroke
				(width 0)
				(type default)
			)
			(fill no)
			(layer "F.Fab")
		)
		(pad "1" smd custom
			(at 0 -0.4445 270)
			(size 0.1397 0.1397)
			(layers "F.Cu" "F.Mask" "F.Paste")
			(net "P5V_B_4_PGOOD")
			(options
				(clearance outline)
				(anchor circle)
			)
			(primitives
				(gr_poly
					(pts
						(arc
							(start -0.1778 -0.2794)
							(mid -0.249642 -0.249642)
							(end -0.2794 -0.1778)
						)
						(arc
							(start -0.2794 0.1778)
							(mid -0.249642 0.249642)
							(end -0.1778 0.2794)
						)
						(arc
							(start 0.1778 0.2794)
							(mid 0.249642 0.249642)
							(end 0.2794 0.1778)
						)
						(arc
							(start 0.2794 -0.1778)
							(mid 0.249642 -0.249642)
							(end 0.1778 -0.2794)
						)
					)
					(width 0)
					(fill yes)
				)
			)
		)
		(pad "2" smd custom
			(at 0 0.4445 270)
			(size 0.1397 0.1397)
			(layers "F.Cu" "F.Mask" "F.Paste")
			(net "GND")
			(options
				(clearance outline)
				(anchor circle)
			)
			(primitives
				(gr_poly
					(pts
						(arc
							(start -0.1778 -0.2794)
							(mid -0.249642 -0.249642)
							(end -0.2794 -0.1778)
						)
						(arc
							(start -0.2794 0.1778)
							(mid -0.249642 0.249642)
							(end -0.1778 0.2794)
						)
						(arc
							(start 0.1778 0.2794)
							(mid 0.249642 0.249642)
							(end 0.2794 0.1778)
						)
						(arc
							(start 0.2794 -0.1778)
							(mid 0.249642 -0.249642)
							(end 0.1778 -0.2794)
						)
					)
					(width 0)
					(fill yes)
				)
			)
		)
	)
	(footprint ""
		(layer "F.Cu")
		(at 244.37848 -194.43954 -90)
		(property "Reference" "R78"
			(at 0 0 270)
			(layer "F.SilkS")
			(hide yes)
			(effects
				(font
					(size 1.27 1.27)
				)
			)
		)
		(property "Value" "4K7R2F-GP"
			(at 0.064008 -3.993896 270)
			(unlocked yes)
			(layer "F.Fab")
			(hide yes)
			(effects
				(font
					(size 1.016 1.016)
					(thickness 0.1524)
				)
			)
		)
		(property "Device Type" "R402H16"
			(at 0.064008 -5.517896 270)
			(unlocked yes)
			(layer "F.Fab")
			(hide yes)
			(effects
				(font
					(size 1.016 1.016)
					(thickness 0.1524)
				)
			)
		)
		(duplicate_pad_numbers_are_jumpers no)
		(fp_line
			(start -0.508 -0.9398)
			(end -0.508 0.9398)
			(stroke
				(width 0.1524)
				(type default)
			)
			(layer "F.SilkS")
		)
		(fp_line
			(start 0.508 -0.9398)
			(end -0.508 -0.9398)
			(stroke
				(width 0.1524)
				(type default)
			)
			(layer "F.SilkS")
		)
		(fp_rect
			(start -0.508 0.9398)
			(end 0.508 -0.9398)
			(stroke
				(width 0)
				(type default)
			)
			(fill no)
			(layer "F.CrtYd")
		)
		(fp_rect
			(start -0.508 0.9398)
			(end 0.508 -0.9398)
			(stroke
				(width 0)
				(type default)
			)
			(fill no)
			(layer "F.Fab")
		)
		(pad "1" smd custom
			(at 0 -0.4445 270)
			(size 0.1397 0.1397)
			(layers "F.Cu" "F.Mask" "F.Paste")
			(net "P3V3_STBY_B")
			(options
				(clearance outline)
				(anchor circle)
			)
			(primitives
				(gr_poly
					(pts
						(arc
							(start -0.1778 -0.2794)
							(mid -0.249642 -0.249642)
							(end -0.2794 -0.1778)
						)
						(arc
							(start -0.2794 0.1778)
							(mid -0.249642 0.249642)
							(end -0.1778 0.2794)
						)
						(arc
							(start 0.1778 0.2794)
							(mid 0.249642 0.249642)
							(end 0.2794 0.1778)
						)
						(arc
							(start 0.2794 -0.1778)
							(mid 0.249642 -0.249642)
							(end 0.1778 -0.2794)
						)
					)
					(width 0)
					(fill yes)
				)
			)
		)
		(pad "2" smd custom
			(at 0 0.4445 270)
			(size 0.1397 0.1397)
			(layers "F.Cu" "F.Mask" "F.Paste")
			(net "IO_EXP2_A1")
			(options
				(clearance outline)
				(anchor circle)
			)
			(primitives
				(gr_poly
					(pts
						(arc
							(start -0.1778 -0.2794)
							(mid -0.249642 -0.249642)
							(end -0.2794 -0.1778)
						)
						(arc
							(start -0.2794 0.1778)
							(mid -0.249642 0.249642)
							(end -0.1778 0.2794)
						)
						(arc
							(start 0.1778 0.2794)
							(mid 0.249642 0.249642)
							(end 0.2794 0.1778)
						)
						(arc
							(start 0.2794 -0.1778)
							(mid 0.249642 -0.249642)
							(end 0.1778 -0.2794)
						)
					)
					(width 0)
					(fill yes)
				)
			)
		)
	)
	(footprint ""
		(layer "F.Cu")
		(at 225.749104 -353.288854 180)
		(property "Reference" "C514"
			(at 0 0 180)
			(layer "F.SilkS")
			(hide yes)
			(effects
				(font
					(size 1.27 1.27)
				)
			)
		)
		(property "Value" "SC22U25V6KX-2-GP-U"
			(at -2.860802 -5.279644 180)
			(unlocked yes)
			(layer "F.Fab")
			(hide yes)
			(effects
				(font
					(size 1.016 1.016)
					(thickness 0.1524)
				)
			)
		)
		(property "Device Type" "C1206-TO0D3H75"
			(at -2.860802 -6.803644 180)
			(unlocked yes)
			(layer "F.Fab")
			(hide yes)
			(effects
				(font
					(size 1.016 1.016)
					(thickness 0.1524)
				)
			)
		)
		(duplicate_pad_numbers_are_jumpers no)
		(fp_line
			(start 1.3081 2.3749)
			(end -1.3081 2.3749)
			(stroke
				(width 0.1524)
				(type default)
			)
			(layer "F.SilkS")
		)
		(fp_line
			(start 1.3081 -2.3749)
			(end 1.3081 2.3749)
			(stroke
				(width 0.1524)
				(type default)
			)
			(layer "F.SilkS")
		)
		(fp_line
			(start -1.3081 2.3749)
			(end -1.3081 -2.3749)
			(stroke
				(width 0.1524)
				(type default)
			)
			(layer "F.SilkS")
		)
		(fp_line
			(start -1.3081 -2.3749)
			(end 1.3081 -2.3749)
			(stroke
				(width 0.1524)
				(type default)
			)
			(layer "F.SilkS")
		)
		(fp_rect
			(start -0.8001 1.6002)
			(end 0.8001 -1.6002)
			(stroke
				(width 0)
				(type default)
			)
			(fill no)
			(layer "F.CrtYd")
		)
		(fp_poly
			(pts
				(xy -1.5621 2.4511) (xy -1.5621 1.6002) (xy 0.8001 1.6002) (xy 0.8001 -1.6002) (xy -0.8001 -1.6002)
				(xy -0.8001 1.5875) (xy -1.5621 1.5875) (xy -1.5621 -2.4511) (xy 1.5621 -2.4511) (xy 1.5621 2.4511)
			)
			(stroke
				(width 0)
				(type default)
			)
			(fill no)
			(layer "F.CrtYd")
		)
		(fp_rect
			(start -1.5621 2.4511)
			(end 1.5621 -2.4511)
			(stroke
				(width 0)
				(type default)
			)
			(fill no)
			(layer "F.Fab")
		)
		(pad "1" smd rect
			(at 0 -1.392936 180)
			(size 2.1082 1.4478)
			(layers "F.Cu" "F.Mask" "F.Paste")
			(net "P12V_IN")
		)
		(pad "2" smd rect
			(at 0 1.392936 180)
			(size 2.1082 1.4478)
			(layers "F.Cu" "F.Mask" "F.Paste")
			(net "GND")
		)
	)
	(footprint ""
		(layer "F.Cu")
		(at 234.696 -224.409 180)
		(property "Reference" "C14"
			(at 0 0 180)
			(layer "F.SilkS")
			(hide yes)
			(effects
				(font
					(size 1.27 1.27)
				)
			)
		)
		(property "Value" "SCD1U16V2KX-3GP"
			(at 1.1811 -2.7051 180)
			(unlocked yes)
			(layer "F.Fab")
			(hide yes)
			(effects
				(font
					(size 1.016 1.016)
					(thickness 0.1524)
				)
			)
		)
		(property "Device Type" "C402H22"
			(at 1.1811 -4.2291 180)
			(unlocked yes)
			(layer "F.Fab")
			(hide yes)
			(effects
				(font
					(size 1.016 1.016)
					(thickness 0.1524)
				)
			)
		)
		(duplicate_pad_numbers_are_jumpers no)
		(fp_rect
			(start -0.4318 0.9525)
			(end 0.4318 -0.9525)
			(stroke
				(width 0)
				(type default)
			)
			(fill no)
			(layer "F.CrtYd")
		)
		(fp_rect
			(start -0.4318 0.9525)
			(end 0.4318 -0.9525)
			(stroke
				(width 0)
				(type default)
			)
			(fill no)
			(layer "F.Fab")
		)
		(pad "1" smd custom
			(at 0 -0.4445 180)
			(size 0.1524 0.1524)
			(layers "F.Cu" "F.Mask" "F.Paste")
			(net "GPIO_VCC_U8")
			(options
				(clearance outline)
				(anchor circle)
			)
			(primitives
				(gr_poly
					(pts
						(arc
							(start 0.3048 -0.2032)
							(mid 0.275042 -0.275042)
							(end 0.2032 -0.3048)
						)
						(arc
							(start -0.2032 -0.3048)
							(mid -0.275042 -0.275042)
							(end -0.3048 -0.2032)
						)
						(arc
							(start -0.3048 0.2032)
							(mid -0.275042 0.275042)
							(end -0.2032 0.3048)
						)
						(arc
							(start 0.2032 0.3048)
							(mid 0.275042 0.275042)
							(end 0.3048 0.2032)
						)
					)
					(width 0)
					(fill yes)
				)
			)
		)
		(pad "2" smd custom
			(at 0 0.4445 180)
			(size 0.1524 0.1524)
			(layers "F.Cu" "F.Mask" "F.Paste")
			(net "GND")
			(options
				(clearance outline)
				(anchor circle)
			)
			(primitives
				(gr_poly
					(pts
						(arc
							(start 0.3048 -0.2032)
							(mid 0.275042 -0.275042)
							(end 0.2032 -0.3048)
						)
						(arc
							(start -0.2032 -0.3048)
							(mid -0.275042 -0.275042)
							(end -0.3048 -0.2032)
						)
						(arc
							(start -0.3048 0.2032)
							(mid -0.275042 0.275042)
							(end -0.2032 0.3048)
						)
						(arc
							(start 0.2032 0.3048)
							(mid 0.275042 0.275042)
							(end 0.3048 0.2032)
						)
					)
					(width 0)
					(fill yes)
				)
			)
		)
	)
	(footprint ""
		(layer "F.Cu")
		(at 259.700522 -362.305346 90)
		(property "Reference" "R1030"
			(at 0 0 90)
			(layer "F.SilkS")
			(hide yes)
			(effects
				(font
					(size 1.27 1.27)
				)
			)
		)
		(property "Value" "0R2J-2-GP"
			(at 0.064008 -3.993896 90)
			(unlocked yes)
			(layer "F.Fab")
			(hide yes)
			(effects
				(font
					(size 1.016 1.016)
					(thickness 0.1524)
				)
			)
		)
		(property "Device Type" "R402H16"
			(at 0.064008 -5.517896 90)
			(unlocked yes)
			(layer "F.Fab")
			(hide yes)
			(effects
				(font
					(size 1.016 1.016)
					(thickness 0.1524)
				)
			)
		)
		(duplicate_pad_numbers_are_jumpers no)
		(fp_line
			(start 0.508 -0.9398)
			(end -0.508 -0.9398)
			(stroke
				(width 0.1524)
				(type default)
			)
			(layer "F.SilkS")
		)
		(fp_line
			(start -0.508 -0.9398)
			(end -0.508 0.9398)
			(stroke
				(width 0.1524)
				(type default)
			)
			(layer "F.SilkS")
		)
		(fp_rect
			(start -0.508 0.9398)
			(end 0.508 -0.9398)
			(stroke
				(width 0)
				(type default)
			)
			(fill no)
			(layer "F.CrtYd")
		)
		(fp_rect
			(start -0.508 0.9398)
			(end 0.508 -0.9398)
			(stroke
				(width 0)
				(type default)
			)
			(fill no)
			(layer "F.Fab")
		)
		(pad "1" smd custom
			(at 0 -0.4445 90)
			(size 0.1397 0.1397)
			(layers "F.Cu" "F.Mask" "F.Paste")
			(net "MB3_CM_ADR2_R")
			(options
				(clearance outline)
				(anchor circle)
			)
			(primitives
				(gr_poly
					(pts
						(arc
							(start -0.1778 -0.2794)
							(mid -0.249642 -0.249642)
							(end -0.2794 -0.1778)
						)
						(arc
							(start -0.2794 0.1778)
							(mid -0.249642 0.249642)
							(end -0.1778 0.2794)
						)
						(arc
							(start 0.1778 0.2794)
							(mid 0.249642 0.249642)
							(end 0.2794 0.1778)
						)
						(arc
							(start 0.2794 -0.1778)
							(mid 0.249642 -0.249642)
							(end 0.1778 -0.2794)
						)
					)
					(width 0)
					(fill yes)
				)
			)
		)
		(pad "2" smd custom
			(at 0 0.4445 90)
			(size 0.1397 0.1397)
			(layers "F.Cu" "F.Mask" "F.Paste")
			(net "AGND_CURRENT_DPB")
			(options
				(clearance outline)
				(anchor circle)
			)
			(primitives
				(gr_poly
					(pts
						(arc
							(start -0.1778 -0.2794)
							(mid -0.249642 -0.249642)
							(end -0.2794 -0.1778)
						)
						(arc
							(start -0.2794 0.1778)
							(mid -0.249642 0.249642)
							(end -0.1778 0.2794)
						)
						(arc
							(start 0.1778 0.2794)
							(mid 0.249642 0.249642)
							(end 0.2794 0.1778)
						)
						(arc
							(start 0.2794 -0.1778)
							(mid 0.249642 -0.249642)
							(end 0.1778 -0.2794)
						)
					)
					(width 0)
					(fill yes)
				)
			)
		)
	)
	(footprint ""
		(layer "F.Cu")
		(at 347.345 -99.187)
		(property "Reference" "R435"
			(at 0 0 0)
			(layer "F.SilkS")
			(hide yes)
			(effects
				(font
					(size 1.27 1.27)
				)
			)
		)
		(property "Value" "91R3F-1-GP"
			(at -0.0254 -2.5146 0)
			(unlocked yes)
			(layer "F.Fab")
			(hide yes)
			(effects
				(font
					(size 1.016 1.016)
					(thickness 0.1524)
				)
			)
		)
		(property "Device Type" "R603H22"
			(at -0.0254 -4.0386 0)
			(unlocked yes)
			(layer "F.Fab")
			(hide yes)
			(effects
				(font
					(size 1.016 1.016)
					(thickness 0.1524)
				)
			)
		)
		(duplicate_pad_numbers_are_jumpers no)
		(fp_line
			(start -0.4826 0)
			(end -0.2032 0)
			(stroke
				(width 0.2032)
				(type default)
			)
			(layer "F.SilkS")
		)
		(fp_line
			(start 0.2032 0)
			(end 0.4826 0)
			(stroke
				(width 0.2032)
				(type default)
			)
			(layer "F.SilkS")
		)
		(fp_rect
			(start -0.5842 1.3335)
			(end 0.5842 -1.3335)
			(stroke
				(width 0)
				(type default)
			)
			(fill no)
			(layer "F.CrtYd")
		)
		(fp_rect
			(start -0.5842 1.3335)
			(end 0.5842 -1.3335)
			(stroke
				(width 0)
				(type default)
			)
			(fill no)
			(layer "F.Fab")
		)
		(pad "1" smd custom
			(at 0 -0.762)
			(size 0.2159 0.2159)
			(layers "F.Cu" "F.Mask" "F.Paste")
			(net "P5V_B_3")
			(options
				(clearance outline)
				(anchor circle)
			)
			(primitives
				(gr_poly
					(pts
						(arc
							(start -0.3302 -0.4318)
							(mid -0.402042 -0.402042)
							(end -0.4318 -0.3302)
						)
						(arc
							(start -0.4318 0.3302)
							(mid -0.402042 0.402042)
							(end -0.3302 0.4318)
						)
						(arc
							(start 0.3302 0.4318)
							(mid 0.402042 0.402042)
							(end 0.4318 0.3302)
						)
						(arc
							(start 0.4318 -0.3302)
							(mid 0.402042 -0.402042)
							(end 0.3302 -0.4318)
						)
					)
					(width 0)
					(fill yes)
				)
			)
		)
		(pad "2" smd custom
			(at 0 0.762)
			(size 0.2159 0.2159)
			(layers "F.Cu" "F.Mask" "F.Paste")
			(net "DRV_ACT_19")
			(options
				(clearance outline)
				(anchor circle)
			)
			(primitives
				(gr_poly
					(pts
						(arc
							(start -0.3302 -0.4318)
							(mid -0.402042 -0.402042)
							(end -0.4318 -0.3302)
						)
						(arc
							(start -0.4318 0.3302)
							(mid -0.402042 0.402042)
							(end -0.3302 0.4318)
						)
						(arc
							(start 0.3302 0.4318)
							(mid 0.402042 0.402042)
							(end 0.4318 0.3302)
						)
						(arc
							(start 0.4318 -0.3302)
							(mid 0.402042 -0.402042)
							(end 0.3302 -0.4318)
						)
					)
					(width 0)
					(fill yes)
				)
			)
		)
	)
	(footprint ""
		(layer "F.Cu")
		(at 458.47 -36.83 180)
		(property "Reference" "C473"
			(at 0 0 180)
			(layer "F.SilkS")
			(hide yes)
			(effects
				(font
					(size 1.27 1.27)
				)
			)
		)
		(property "Value" "SC10U16V6KX-2GP"
			(at -0.0762 -5.1308 180)
			(unlocked yes)
			(layer "F.Fab")
			(hide yes)
			(effects
				(font
					(size 1.016 1.016)
					(thickness 0.1524)
				)
			)
		)
		(property "Device Type" "C1206H71"
			(at -0.127 -6.6548 180)
			(unlocked yes)
			(layer "F.Fab")
			(hide yes)
			(effects
				(font
					(size 1.016 1.016)
					(thickness 0.1524)
				)
			)
		)
		(duplicate_pad_numbers_are_jumpers no)
		(fp_line
			(start 1.016 2.2352)
			(end -1.016 2.2352)
			(stroke
				(width 0.1524)
				(type default)
			)
			(layer "F.SilkS")
		)
		(fp_line
			(start 1.016 0.8382)
			(end 1.016 2.2352)
			(stroke
				(width 0.1524)
				(type default)
			)
			(layer "F.SilkS")
		)
		(fp_line
			(start 1.016 -2.2352)
			(end 1.016 -0.8382)
			(stroke
				(width 0.1524)
				(type default)
			)
			(layer "F.SilkS")
		)
		(fp_line
			(start -1.016 2.2352)
			(end -1.016 0.8382)
			(stroke
				(width 0.1524)
				(type default)
			)
			(layer "F.SilkS")
		)
		(fp_line
			(start -1.016 -0.8382)
			(end -1.016 -2.2352)
			(stroke
				(width 0.1524)
				(type default)
			)
			(layer "F.SilkS")
		)
		(fp_line
			(start -1.016 -2.2352)
			(end 1.016 -2.2352)
			(stroke
				(width 0.1524)
				(type default)
			)
			(layer "F.SilkS")
		)
		(fp_rect
			(start -1.0922 2.3114)
			(end 1.0922 -2.3114)
			(stroke
				(width 0)
				(type default)
			)
			(fill no)
			(layer "F.CrtYd")
		)
		(fp_poly
			(pts
				(xy 1.0922 -2.3114) (xy 1.0922 2.3114) (xy -1.0922 2.3114) (xy -1.0922 -2.3114)
			)
			(stroke
				(width 0)
				(type default)
			)
			(fill no)
			(layer "F.Fab")
		)
		(pad "1" smd rect
			(at 0 -1.397 180)
			(size 1.651 1.27)
			(layers "F.Cu" "F.Mask" "F.Paste")
			(net "P5V_HDD34")
		)
		(pad "2" smd rect
			(at 0 1.397 180)
			(size 1.651 1.27)
			(layers "F.Cu" "F.Mask" "F.Paste")
			(net "GND")
		)
	)
	(footprint ""
		(layer "F.Cu")
		(at 426.72 -246.253 -90)
		(property "Reference" "Q35"
			(at 0 0 270)
			(layer "F.SilkS")
			(hide yes)
			(effects
				(font
					(size 1.27 1.27)
				)
			)
		)
		(property "Value" "2N7002KDW-GP"
			(at -2.3622 -8.2042 270)
			(unlocked yes)
			(layer "F.Fab")
			(hide yes)
			(effects
				(font
					(size 1.016 1.016)
					(thickness 0.1524)
				)
			)
		)
		(property "Device Type" "SOT-363H44"
			(at -2.3622 -10.1092 270)
			(unlocked yes)
			(layer "F.Fab")
			(hide yes)
			(effects
				(font
					(size 1.016 1.016)
					(thickness 0.1524)
				)
			)
		)
		(duplicate_pad_numbers_are_jumpers no)
		(fp_line
			(start -1.4478 1.7018)
			(end 1.4478 1.7018)
			(stroke
				(width 0.1524)
				(type default)
			)
			(layer "F.SilkS")
		)
		(fp_line
			(start 1.4478 1.7018)
			(end 1.4478 -1.7018)
			(stroke
				(width 0.1524)
				(type default)
			)
			(layer "F.SilkS")
		)
		(fp_line
			(start -1.27 1.524)
			(end -1.27 0.6604)
			(stroke
				(width 0.4826)
				(type default)
			)
			(layer "F.SilkS")
		)
		(fp_line
			(start -1.4478 -1.7018)
			(end -1.4478 1.7018)
			(stroke
				(width 0.1524)
				(type default)
			)
			(layer "F.SilkS")
		)
		(fp_line
			(start 1.4478 -1.7018)
			(end -1.4478 -1.7018)
			(stroke
				(width 0.1524)
				(type default)
			)
			(layer "F.SilkS")
		)
		(fp_poly
			(pts
				(xy -1.524 -1.778) (xy 1.524 -1.778) (xy 1.524 1.778) (xy -1.524 1.778)
			)
			(stroke
				(width 0)
				(type default)
			)
			(fill no)
			(layer "F.CrtYd")
		)
		(fp_poly
			(pts
				(xy -1.524 -1.778) (xy 1.524 -1.778) (xy 1.524 1.778) (xy -1.524 1.778)
			)
			(stroke
				(width 0)
				(type default)
			)
			(fill no)
			(layer "F.Fab")
		)
		(pad "1" smd rect
			(at -0.65024 0.9398 270)
			(size 0.4064 1.016)
			(layers "F.Cu" "F.Mask" "F.Paste")
			(net "GND")
		)
		(pad "2" smd rect
			(at 0 0.9398 270)
			(size 0.4064 1.016)
			(layers "F.Cu" "F.Mask" "F.Paste")
			(net "SW_PWR_R_HDD9")
		)
		(pad "3" smd rect
			(at 0.65024 0.9398 270)
			(size 0.4064 1.016)
			(layers "F.Cu" "F.Mask" "F.Paste")
			(net "SW_HDD_P9")
		)
		(pad "4" smd rect
			(at 0.65024 -0.9398 270)
			(size 0.4064 1.016)
			(layers "F.Cu" "F.Mask" "F.Paste")
			(net "GND")
		)
		(pad "5" smd rect
			(at 0 -0.9398 270)
			(size 0.4064 1.016)
			(layers "F.Cu" "F.Mask" "F.Paste")
			(net "SW_HDD_G9")
		)
		(pad "6" smd rect
			(at -0.65024 -0.9398 270)
			(size 0.4064 1.016)
			(layers "F.Cu" "F.Mask" "F.Paste")
			(net "SW_HDD_R9")
		)
	)
	(footprint ""
		(layer "F.Cu")
		(at 35.654996 -368.935 -90)
		(property "Reference" "R926"
			(at 0 0 270)
			(layer "F.SilkS")
			(hide yes)
			(effects
				(font
					(size 1.27 1.27)
				)
			)
		)
		(property "Value" "10KR2F-2-GP"
			(at 0.064008 -3.993896 270)
			(unlocked yes)
			(layer "F.Fab")
			(hide yes)
			(effects
				(font
					(size 1.016 1.016)
					(thickness 0.1524)
				)
			)
		)
		(property "Device Type" "R402H16"
			(at 0.064008 -5.517896 270)
			(unlocked yes)
			(layer "F.Fab")
			(hide yes)
			(effects
				(font
					(size 1.016 1.016)
					(thickness 0.1524)
				)
			)
		)
		(duplicate_pad_numbers_are_jumpers no)
		(fp_line
			(start -0.508 -0.9398)
			(end -0.508 0.9398)
			(stroke
				(width 0.1524)
				(type default)
			)
			(layer "F.SilkS")
		)
		(fp_line
			(start 0.508 -0.9398)
			(end -0.508 -0.9398)
			(stroke
				(width 0.1524)
				(type default)
			)
			(layer "F.SilkS")
		)
		(fp_rect
			(start -0.508 0.9398)
			(end 0.508 -0.9398)
			(stroke
				(width 0)
				(type default)
			)
			(fill no)
			(layer "F.CrtYd")
		)
		(fp_rect
			(start -0.508 0.9398)
			(end 0.508 -0.9398)
			(stroke
				(width 0)
				(type default)
			)
			(fill no)
			(layer "F.Fab")
		)
		(pad "1" smd custom
			(at 0 -0.4445 270)
			(size 0.1397 0.1397)
			(layers "F.Cu" "F.Mask" "F.Paste")
			(net "GND")
			(options
				(clearance outline)
				(anchor circle)
			)
			(primitives
				(gr_poly
					(pts
						(arc
							(start -0.1778 -0.2794)
							(mid -0.249642 -0.249642)
							(end -0.2794 -0.1778)
						)
						(arc
							(start -0.2794 0.1778)
							(mid -0.249642 0.249642)
							(end -0.1778 0.2794)
						)
						(arc
							(start 0.1778 0.2794)
							(mid 0.249642 0.249642)
							(end 0.2794 0.1778)
						)
						(arc
							(start 0.2794 -0.1778)
							(mid 0.249642 -0.249642)
							(end 0.1778 -0.2794)
						)
					)
					(width 0)
					(fill yes)
				)
			)
		)
		(pad "2" smd custom
			(at 0 0.4445 270)
			(size 0.1397 0.1397)
			(layers "F.Cu" "F.Mask" "F.Paste")
			(net "FANTACH_R0")
			(options
				(clearance outline)
				(anchor circle)
			)
			(primitives
				(gr_poly
					(pts
						(arc
							(start -0.1778 -0.2794)
							(mid -0.249642 -0.249642)
							(end -0.2794 -0.1778)
						)
						(arc
							(start -0.2794 0.1778)
							(mid -0.249642 0.249642)
							(end -0.1778 0.2794)
						)
						(arc
							(start 0.1778 0.2794)
							(mid 0.249642 0.249642)
							(end 0.2794 0.1778)
						)
						(arc
							(start 0.2794 -0.1778)
							(mid 0.249642 -0.249642)
							(end 0.1778 -0.2794)
						)
					)
					(width 0)
					(fill yes)
				)
			)
		)
	)
	(footprint ""
		(layer "F.Cu")
		(at 37.5158 -7.4422 90)
		(property "Reference" "C29"
			(at 0 0 90)
			(layer "F.SilkS")
			(hide yes)
			(effects
				(font
					(size 1.27 1.27)
				)
			)
		)
		(property "Value" "SC1U16V3KX-5GP"
			(at 0 -2.8194 90)
			(unlocked yes)
			(layer "F.Fab")
			(hide yes)
			(effects
				(font
					(size 1.016 1.016)
					(thickness 0.1524)
				)
			)
		)
		(property "Device Type" "C603H36"
			(at 0 -4.3434 90)
			(unlocked yes)
			(layer "F.Fab")
			(hide yes)
			(effects
				(font
					(size 1.016 1.016)
					(thickness 0.1524)
				)
			)
		)
		(duplicate_pad_numbers_are_jumpers no)
		(fp_line
			(start 0.508 0)
			(end -0.508 0)
			(stroke
				(width 0.2032)
				(type default)
			)
			(layer "F.SilkS")
		)
		(fp_rect
			(start -0.5842 1.3335)
			(end 0.5842 -1.3335)
			(stroke
				(width 0)
				(type default)
			)
			(fill no)
			(layer "F.CrtYd")
		)
		(fp_rect
			(start -0.5842 1.3335)
			(end 0.5842 -1.3335)
			(stroke
				(width 0)
				(type default)
			)
			(fill no)
			(layer "F.Fab")
		)
		(pad "1" smd custom
			(at 0 -0.762 90)
			(size 0.2159 0.2159)
			(layers "F.Cu" "F.Mask" "F.Paste")
			(net "P3V3_STBY_A")
			(options
				(clearance outline)
				(anchor circle)
			)
			(primitives
				(gr_poly
					(pts
						(arc
							(start -0.3302 -0.4318)
							(mid -0.402042 -0.402042)
							(end -0.4318 -0.3302)
						)
						(arc
							(start -0.4318 0.3302)
							(mid -0.402042 0.402042)
							(end -0.3302 0.4318)
						)
						(arc
							(start 0.3302 0.4318)
							(mid 0.402042 0.402042)
							(end 0.4318 0.3302)
						)
						(arc
							(start 0.4318 -0.3302)
							(mid 0.402042 -0.402042)
							(end 0.3302 -0.4318)
						)
					)
					(width 0)
					(fill yes)
				)
			)
		)
		(pad "2" smd custom
			(at 0 0.762 90)
			(size 0.2159 0.2159)
			(layers "F.Cu" "F.Mask" "F.Paste")
			(net "GND")
			(options
				(clearance outline)
				(anchor circle)
			)
			(primitives
				(gr_poly
					(pts
						(arc
							(start -0.3302 -0.4318)
							(mid -0.402042 -0.402042)
							(end -0.4318 -0.3302)
						)
						(arc
							(start -0.4318 0.3302)
							(mid -0.402042 0.402042)
							(end -0.3302 0.4318)
						)
						(arc
							(start 0.3302 0.4318)
							(mid 0.402042 0.402042)
							(end 0.4318 0.3302)
						)
						(arc
							(start 0.4318 -0.3302)
							(mid 0.402042 -0.402042)
							(end 0.3302 -0.4318)
						)
					)
					(width 0)
					(fill yes)
				)
			)
		)
	)
	(footprint ""
		(layer "F.Cu")
		(at 398.78 -16.383 180)
		(property "Reference" "D32"
			(at 0 0 180)
			(layer "F.SilkS")
			(hide yes)
			(effects
				(font
					(size 1.27 1.27)
				)
			)
		)
		(property "Value" "RB551V30-GP"
			(at 0 -6.7818 180)
			(unlocked yes)
			(layer "F.Fab")
			(hide yes)
			(effects
				(font
					(size 1.016 1.016)
					(thickness 0.1524)
				)
			)
		)
		(property "Device Type" "SOD323AKH38"
			(at 0 -8.6868 180)
			(unlocked yes)
			(layer "F.Fab")
			(hide yes)
			(effects
				(font
					(size 1.016 1.016)
					(thickness 0.1524)
				)
			)
		)
		(duplicate_pad_numbers_are_jumpers no)
		(fp_line
			(start 0.889 2.159)
			(end -0.889 2.159)
			(stroke
				(width 0.1524)
				(type default)
			)
			(layer "F.SilkS")
		)
		(fp_line
			(start 0.889 -1.9304)
			(end 0.889 2.159)
			(stroke
				(width 0.1524)
				(type default)
			)
			(layer "F.SilkS")
		)
		(fp_line
			(start 0.762 2.0574)
			(end -0.762 2.0574)
			(stroke
				(width 0.508)
				(type default)
			)
			(layer "F.SilkS")
		)
		(fp_line
			(start -0.889 2.159)
			(end -0.889 -1.9304)
			(stroke
				(width 0.1524)
				(type default)
			)
			(layer "F.SilkS")
		)
		(fp_line
			(start -0.889 -1.9304)
			(end 0.889 -1.9304)
			(stroke
				(width 0.1524)
				(type default)
			)
			(layer "F.SilkS")
		)
		(fp_rect
			(start -1.016 2.3114)
			(end 1.016 -2.0066)
			(stroke
				(width 0)
				(type default)
			)
			(fill no)
			(layer "F.CrtYd")
		)
		(fp_poly
			(pts
				(xy -1.016 -2.0066) (xy 1.016 -2.0066) (xy 1.016 2.3114) (xy -1.016 2.3114)
			)
			(stroke
				(width 0)
				(type default)
			)
			(fill no)
			(layer "F.Fab")
		)
		(pad "A" smd rect
			(at 0 -1.143 180)
			(size 0.5588 1.016)
			(layers "F.Cu" "F.Mask" "F.Paste")
			(net "SW_HDD_R32")
		)
		(pad "K" smd rect
			(at 0 1.143 180)
			(size 0.5588 1.016)
			(layers "F.Cu" "F.Mask" "F.Paste")
			(net "SW_HDD_N32")
		)
	)
	(footprint ""
		(layer "F.Cu")
		(at 22.1742 -15.9512 -90)
		(property "Reference" "R633"
			(at 0 0 270)
			(layer "F.SilkS")
			(hide yes)
			(effects
				(font
					(size 1.27 1.27)
				)
			)
		)
		(property "Value" "0R2J-2-GP"
			(at 0.064008 -3.993896 270)
			(unlocked yes)
			(layer "F.Fab")
			(hide yes)
			(effects
				(font
					(size 1.016 1.016)
					(thickness 0.1524)
				)
			)
		)
		(property "Device Type" "R402H16"
			(at 0.064008 -5.517896 270)
			(unlocked yes)
			(layer "F.Fab")
			(hide yes)
			(effects
				(font
					(size 1.016 1.016)
					(thickness 0.1524)
				)
			)
		)
		(duplicate_pad_numbers_are_jumpers no)
		(fp_line
			(start -0.508 -0.9398)
			(end -0.508 0.9398)
			(stroke
				(width 0.1524)
				(type default)
			)
			(layer "F.SilkS")
		)
		(fp_line
			(start 0.508 -0.9398)
			(end -0.508 -0.9398)
			(stroke
				(width 0.1524)
				(type default)
			)
			(layer "F.SilkS")
		)
		(fp_rect
			(start -0.508 0.9398)
			(end 0.508 -0.9398)
			(stroke
				(width 0)
				(type default)
			)
			(fill no)
			(layer "F.CrtYd")
		)
		(fp_rect
			(start -0.508 0.9398)
			(end 0.508 -0.9398)
			(stroke
				(width 0)
				(type default)
			)
			(fill no)
			(layer "F.Fab")
		)
		(pad "1" smd custom
			(at 0 -0.4445 270)
			(size 0.1397 0.1397)
			(layers "F.Cu" "F.Mask" "F.Paste")
			(net "DRIVE_B_24_PWR")
			(options
				(clearance outline)
				(anchor circle)
			)
			(primitives
				(gr_poly
					(pts
						(arc
							(start -0.1778 -0.2794)
							(mid -0.249642 -0.249642)
							(end -0.2794 -0.1778)
						)
						(arc
							(start -0.2794 0.1778)
							(mid -0.249642 0.249642)
							(end -0.1778 0.2794)
						)
						(arc
							(start 0.1778 0.2794)
							(mid 0.249642 0.249642)
							(end 0.2794 0.1778)
						)
						(arc
							(start 0.2794 -0.1778)
							(mid 0.249642 -0.249642)
							(end 0.1778 -0.2794)
						)
					)
					(width 0)
					(fill yes)
				)
			)
		)
		(pad "2" smd custom
			(at 0 0.4445 270)
			(size 0.1397 0.1397)
			(layers "F.Cu" "F.Mask" "F.Paste")
			(net "SW_PWR_R_HDD24")
			(options
				(clearance outline)
				(anchor circle)
			)
			(primitives
				(gr_poly
					(pts
						(arc
							(start -0.1778 -0.2794)
							(mid -0.249642 -0.249642)
							(end -0.2794 -0.1778)
						)
						(arc
							(start -0.2794 0.1778)
							(mid -0.249642 0.249642)
							(end -0.1778 0.2794)
						)
						(arc
							(start 0.1778 0.2794)
							(mid 0.249642 0.249642)
							(end 0.2794 0.1778)
						)
						(arc
							(start 0.2794 -0.1778)
							(mid 0.249642 -0.249642)
							(end 0.1778 -0.2794)
						)
					)
					(width 0)
					(fill yes)
				)
			)
		)
	)
	(footprint ""
		(layer "F.Cu")
		(at 481.339652 -248.750074 -90)
		(property "Reference" "VIA24"
			(at 0 0 270)
			(layer "F.SilkS")
			(hide yes)
			(effects
				(font
					(size 1.27 1.27)
				)
			)
		)
		(property "Value" "100OHM-8L-2D36MM-L16-GP"
			(at -3.4036 -0.4572 270)
			(unlocked yes)
			(layer "F.Fab")
			(hide yes)
			(effects
				(font
					(size 1.016 1.016)
					(thickness 0.1524)
				)
			)
		)
		(property "Device Type" "VIA-PCIE-4P-427097"
			(at -3.4036 -1.9812 270)
			(unlocked yes)
			(layer "F.Fab")
			(hide yes)
			(effects
				(font
					(size 1.016 1.016)
					(thickness 0.1524)
				)
			)
		)
		(duplicate_pad_numbers_are_jumpers no)
		(fp_rect
			(start -2.1336 0.4826)
			(end 2.1336 -0.4826)
			(stroke
				(width 0)
				(type default)
			)
			(fill no)
			(layer "F.CrtYd")
		)
		(fp_rect
			(start -2.1336 0.4826)
			(end 2.1336 -0.4826)
			(stroke
				(width 0)
				(type default)
			)
			(fill no)
			(layer "F.Fab")
		)
		(pad "1" thru_hole circle
			(at -1.651 0 270)
			(size 0.508 0.508)
			(drill 0.254)
			(layers "*.Cu" "*.Mask")
			(remove_unused_layers no)
			(net "GND")
			(clearance 0.2286)
			(thermal_gap 0.2286)
		)
		(pad "2" thru_hole circle
			(at -0.635 0 270)
			(size 0.508 0.508)
			(drill 0.254)
			(layers "*.Cu" "*.Mask")
			(remove_unused_layers no)
			(net "PHY_DRV_B_TO_SCC_B_11_DP")
			(clearance 0.2286)
			(thermal_gap 0.2286)
		)
		(pad "3" thru_hole circle
			(at 0.635 0 270)
			(size 0.508 0.508)
			(drill 0.254)
			(layers "*.Cu" "*.Mask")
			(remove_unused_layers no)
			(net "PHY_DRV_B_TO_SCC_B_11_DN")
			(clearance 0.2286)
			(thermal_gap 0.2286)
		)
		(pad "4" thru_hole circle
			(at 1.651 0 270)
			(size 0.508 0.508)
			(drill 0.254)
			(layers "*.Cu" "*.Mask")
			(remove_unused_layers no)
			(net "GND")
			(clearance 0.2286)
			(thermal_gap 0.2286)
		)
	)
	(footprint ""
		(layer "F.Cu")
		(at 55.245 -148.209)
		(property "Reference" "R368"
			(at 0 0 0)
			(layer "F.SilkS")
			(hide yes)
			(effects
				(font
					(size 1.27 1.27)
				)
			)
		)
		(property "Value" "2R6F-GP"
			(at -0.0508 -4.8514 0)
			(unlocked yes)
			(layer "F.Fab")
			(hide yes)
			(effects
				(font
					(size 1.016 1.016)
					(thickness 0.1524)
				)
			)
		)
		(property "Device Type" "R1206H26"
			(at 0 -6.3754 0)
			(unlocked yes)
			(layer "F.Fab")
			(hide yes)
			(effects
				(font
					(size 1.016 1.016)
					(thickness 0.1524)
				)
			)
		)
		(duplicate_pad_numbers_are_jumpers no)
		(fp_line
			(start -1.016 -2.2352)
			(end 1.016 -2.2352)
			(stroke
				(width 0.1524)
				(type default)
			)
			(layer "F.SilkS")
		)
		(fp_line
			(start -1.016 2.2352)
			(end -1.016 -2.2352)
			(stroke
				(width 0.1524)
				(type default)
			)
			(layer "F.SilkS")
		)
		(fp_line
			(start 1.016 -2.2352)
			(end 1.016 2.2352)
			(stroke
				(width 0.1524)
				(type default)
			)
			(layer "F.SilkS")
		)
		(fp_line
			(start 1.016 2.2352)
			(end -1.016 2.2352)
			(stroke
				(width 0.1524)
				(type default)
			)
			(layer "F.SilkS")
		)
		(fp_rect
			(start -1.0922 2.3114)
			(end 1.0922 -2.3114)
			(stroke
				(width 0)
				(type default)
			)
			(fill no)
			(layer "F.CrtYd")
		)
		(fp_poly
			(pts
				(xy -1.0922 -2.3114) (xy 1.0922 -2.3114) (xy 1.0922 2.3114) (xy -1.0922 2.3114)
			)
			(stroke
				(width 0)
				(type default)
			)
			(fill no)
			(layer "F.Fab")
		)
		(pad "1" smd rect
			(at 0 -1.397)
			(size 1.651 1.27)
			(layers "F.Cu" "F.Mask" "F.Paste")
			(net "P5V_HDD13")
		)
		(pad "2" smd rect
			(at 0 1.397)
			(size 1.651 1.27)
			(layers "F.Cu" "F.Mask" "F.Paste")
			(net "5V_PRE_13")
		)
	)
	(footprint ""
		(layer "F.Cu")
		(at 243.0907 -355.4476 -90)
		(property "Reference" "R1035"
			(at 0 0 270)
			(layer "F.SilkS")
			(hide yes)
			(effects
				(font
					(size 1.27 1.27)
				)
			)
		)
		(property "Value" "10R2F-L-GP"
			(at 0.064008 -3.993896 270)
			(unlocked yes)
			(layer "F.Fab")
			(hide yes)
			(effects
				(font
					(size 1.016 1.016)
					(thickness 0.1524)
				)
			)
		)
		(property "Device Type" "R402H14"
			(at 0.064008 -5.517896 270)
			(unlocked yes)
			(layer "F.Fab")
			(hide yes)
			(effects
				(font
					(size 1.016 1.016)
					(thickness 0.1524)
				)
			)
		)
		(duplicate_pad_numbers_are_jumpers no)
		(fp_line
			(start -0.508 -0.9398)
			(end -0.508 0.9398)
			(stroke
				(width 0.1524)
				(type default)
			)
			(layer "F.SilkS")
		)
		(fp_line
			(start 0.508 -0.9398)
			(end -0.508 -0.9398)
			(stroke
				(width 0.1524)
				(type default)
			)
			(layer "F.SilkS")
		)
		(fp_rect
			(start -0.508 0.9398)
			(end 0.508 -0.9398)
			(stroke
				(width 0)
				(type default)
			)
			(fill no)
			(layer "F.CrtYd")
		)
		(fp_rect
			(start -0.508 0.9398)
			(end 0.508 -0.9398)
			(stroke
				(width 0)
				(type default)
			)
			(fill no)
			(layer "F.Fab")
		)
		(pad "1" smd custom
			(at 0 -0.4445 270)
			(size 0.1397 0.1397)
			(layers "F.Cu" "F.Mask" "F.Paste")
			(net "MB3_CM_SENSE_R1_P")
			(options
				(clearance outline)
				(anchor circle)
			)
			(primitives
				(gr_poly
					(pts
						(arc
							(start -0.1778 -0.2794)
							(mid -0.249642 -0.249642)
							(end -0.2794 -0.1778)
						)
						(arc
							(start -0.2794 0.1778)
							(mid -0.249642 0.249642)
							(end -0.1778 0.2794)
						)
						(arc
							(start 0.1778 0.2794)
							(mid 0.249642 0.249642)
							(end 0.2794 0.1778)
						)
						(arc
							(start 0.2794 -0.1778)
							(mid 0.249642 -0.249642)
							(end 0.1778 -0.2794)
						)
					)
					(width 0)
					(fill yes)
				)
			)
		)
		(pad "2" smd custom
			(at 0 0.4445 270)
			(size 0.1397 0.1397)
			(layers "F.Cu" "F.Mask" "F.Paste")
			(net "MB3_CM_SENSE_P")
			(options
				(clearance outline)
				(anchor circle)
			)
			(primitives
				(gr_poly
					(pts
						(arc
							(start -0.1778 -0.2794)
							(mid -0.249642 -0.249642)
							(end -0.2794 -0.1778)
						)
						(arc
							(start -0.2794 0.1778)
							(mid -0.249642 0.249642)
							(end -0.1778 0.2794)
						)
						(arc
							(start 0.1778 0.2794)
							(mid 0.249642 0.249642)
							(end 0.2794 0.1778)
						)
						(arc
							(start 0.2794 -0.1778)
							(mid 0.249642 -0.249642)
							(end 0.1778 -0.2794)
						)
					)
					(width 0)
					(fill yes)
				)
			)
		)
	)
	(footprint ""
		(layer "F.Cu")
		(at 111.379 -139.065 -90)
		(property "Reference" "C233"
			(at 0 0 270)
			(layer "F.SilkS")
			(hide yes)
			(effects
				(font
					(size 1.27 1.27)
				)
			)
		)
		(property "Value" "SCD033U25V2KX-GP"
			(at 1.1811 -2.7051 270)
			(unlocked yes)
			(layer "F.Fab")
			(hide yes)
			(effects
				(font
					(size 1.016 1.016)
					(thickness 0.1524)
				)
			)
		)
		(property "Device Type" "C402H22"
			(at 1.1811 -4.2291 270)
			(unlocked yes)
			(layer "F.Fab")
			(hide yes)
			(effects
				(font
					(size 1.016 1.016)
					(thickness 0.1524)
				)
			)
		)
		(duplicate_pad_numbers_are_jumpers no)
		(fp_rect
			(start -0.4318 0.9525)
			(end 0.4318 -0.9525)
			(stroke
				(width 0)
				(type default)
			)
			(fill no)
			(layer "F.CrtYd")
		)
		(fp_rect
			(start -0.4318 0.9525)
			(end 0.4318 -0.9525)
			(stroke
				(width 0)
				(type default)
			)
			(fill no)
			(layer "F.Fab")
		)
		(pad "1" smd custom
			(at 0 -0.4445 270)
			(size 0.1524 0.1524)
			(layers "F.Cu" "F.Mask" "F.Paste")
			(net "SW_HDD_P15")
			(options
				(clearance outline)
				(anchor circle)
			)
			(primitives
				(gr_poly
					(pts
						(arc
							(start 0.3048 -0.2032)
							(mid 0.275042 -0.275042)
							(end 0.2032 -0.3048)
						)
						(arc
							(start -0.2032 -0.3048)
							(mid -0.275042 -0.275042)
							(end -0.3048 -0.2032)
						)
						(arc
							(start -0.3048 0.2032)
							(mid -0.275042 0.275042)
							(end -0.2032 0.3048)
						)
						(arc
							(start 0.2032 0.3048)
							(mid 0.275042 0.275042)
							(end 0.3048 0.2032)
						)
					)
					(width 0)
					(fill yes)
				)
			)
		)
		(pad "2" smd custom
			(at 0 0.4445 270)
			(size 0.1524 0.1524)
			(layers "F.Cu" "F.Mask" "F.Paste")
			(net "GND")
			(options
				(clearance outline)
				(anchor circle)
			)
			(primitives
				(gr_poly
					(pts
						(arc
							(start 0.3048 -0.2032)
							(mid 0.275042 -0.275042)
							(end 0.2032 -0.3048)
						)
						(arc
							(start -0.2032 -0.3048)
							(mid -0.275042 -0.275042)
							(end -0.3048 -0.2032)
						)
						(arc
							(start -0.3048 0.2032)
							(mid -0.275042 0.275042)
							(end -0.2032 0.3048)
						)
						(arc
							(start 0.2032 0.3048)
							(mid 0.275042 0.275042)
							(end 0.3048 0.2032)
						)
					)
					(width 0)
					(fill yes)
				)
			)
		)
	)
	(footprint ""
		(layer "F.Cu")
		(at 166.57193 -362.691426 180)
		(property "Reference" "R1013"
			(at 0 0 180)
			(layer "F.SilkS")
			(hide yes)
			(effects
				(font
					(size 1.27 1.27)
				)
			)
		)
		(property "Value" "3K92R2F-GP"
			(at 0.064008 -3.993896 180)
			(unlocked yes)
			(layer "F.Fab")
			(hide yes)
			(effects
				(font
					(size 1.016 1.016)
					(thickness 0.1524)
				)
			)
		)
		(property "Device Type" "R402H16"
			(at 0.064008 -5.517896 180)
			(unlocked yes)
			(layer "F.Fab")
			(hide yes)
			(effects
				(font
					(size 1.016 1.016)
					(thickness 0.1524)
				)
			)
		)
		(duplicate_pad_numbers_are_jumpers no)
		(fp_line
			(start 0.508 -0.9398)
			(end -0.508 -0.9398)
			(stroke
				(width 0.1524)
				(type default)
			)
			(layer "F.SilkS")
		)
		(fp_line
			(start -0.508 -0.9398)
			(end -0.508 0.9398)
			(stroke
				(width 0.1524)
				(type default)
			)
			(layer "F.SilkS")
		)
		(fp_rect
			(start -0.508 0.9398)
			(end 0.508 -0.9398)
			(stroke
				(width 0)
				(type default)
			)
			(fill no)
			(layer "F.CrtYd")
		)
		(fp_rect
			(start -0.508 0.9398)
			(end 0.508 -0.9398)
			(stroke
				(width 0)
				(type default)
			)
			(fill no)
			(layer "F.Fab")
		)
		(pad "1" smd custom
			(at 0 -0.4445 180)
			(size 0.1397 0.1397)
			(layers "F.Cu" "F.Mask" "F.Paste")
			(net "MB0_CM_OV_R")
			(options
				(clearance outline)
				(anchor circle)
			)
			(primitives
				(gr_poly
					(pts
						(arc
							(start -0.1778 -0.2794)
							(mid -0.249642 -0.249642)
							(end -0.2794 -0.1778)
						)
						(arc
							(start -0.2794 0.1778)
							(mid -0.249642 0.249642)
							(end -0.1778 0.2794)
						)
						(arc
							(start 0.1778 0.2794)
							(mid 0.249642 0.249642)
							(end 0.2794 0.1778)
						)
						(arc
							(start 0.2794 -0.1778)
							(mid 0.249642 -0.249642)
							(end 0.1778 -0.2794)
						)
					)
					(width 0)
					(fill yes)
				)
			)
		)
		(pad "2" smd custom
			(at 0 0.4445 180)
			(size 0.1397 0.1397)
			(layers "F.Cu" "F.Mask" "F.Paste")
			(net "AGND_CURRENT_MON")
			(options
				(clearance outline)
				(anchor circle)
			)
			(primitives
				(gr_poly
					(pts
						(arc
							(start -0.1778 -0.2794)
							(mid -0.249642 -0.249642)
							(end -0.2794 -0.1778)
						)
						(arc
							(start -0.2794 0.1778)
							(mid -0.249642 0.249642)
							(end -0.1778 0.2794)
						)
						(arc
							(start 0.1778 0.2794)
							(mid 0.249642 0.249642)
							(end 0.2794 0.1778)
						)
						(arc
							(start 0.2794 -0.1778)
							(mid 0.249642 -0.249642)
							(end 0.1778 -0.2794)
						)
					)
					(width 0)
					(fill yes)
				)
			)
		)
	)
	(footprint ""
		(layer "F.Cu")
		(at 427.863 -13.589 180)
		(property "Reference" "R837"
			(at 0 0 180)
			(layer "F.SilkS")
			(hide yes)
			(effects
				(font
					(size 1.27 1.27)
				)
			)
		)
		(property "Value" "1KR2F-3-GP"
			(at 0.064008 -3.993896 180)
			(unlocked yes)
			(layer "F.Fab")
			(hide yes)
			(effects
				(font
					(size 1.016 1.016)
					(thickness 0.1524)
				)
			)
		)
		(property "Device Type" "R402H16"
			(at 0.064008 -5.517896 180)
			(unlocked yes)
			(layer "F.Fab")
			(hide yes)
			(effects
				(font
					(size 1.016 1.016)
					(thickness 0.1524)
				)
			)
		)
		(duplicate_pad_numbers_are_jumpers no)
		(fp_line
			(start 0.508 -0.9398)
			(end -0.508 -0.9398)
			(stroke
				(width 0.1524)
				(type default)
			)
			(layer "F.SilkS")
		)
		(fp_line
			(start -0.508 -0.9398)
			(end -0.508 0.9398)
			(stroke
				(width 0.1524)
				(type default)
			)
			(layer "F.SilkS")
		)
		(fp_rect
			(start -0.508 0.9398)
			(end 0.508 -0.9398)
			(stroke
				(width 0)
				(type default)
			)
			(fill no)
			(layer "F.CrtYd")
		)
		(fp_rect
			(start -0.508 0.9398)
			(end 0.508 -0.9398)
			(stroke
				(width 0)
				(type default)
			)
			(fill no)
			(layer "F.Fab")
		)
		(pad "1" smd custom
			(at 0 -0.4445 180)
			(size 0.1397 0.1397)
			(layers "F.Cu" "F.Mask" "F.Paste")
			(net "P3V3_STBY_B")
			(options
				(clearance outline)
				(anchor circle)
			)
			(primitives
				(gr_poly
					(pts
						(arc
							(start -0.1778 -0.2794)
							(mid -0.249642 -0.249642)
							(end -0.2794 -0.1778)
						)
						(arc
							(start -0.2794 0.1778)
							(mid -0.249642 0.249642)
							(end -0.1778 0.2794)
						)
						(arc
							(start 0.1778 0.2794)
							(mid 0.249642 0.249642)
							(end 0.2794 0.1778)
						)
						(arc
							(start 0.2794 -0.1778)
							(mid 0.249642 -0.249642)
							(end 0.1778 -0.2794)
						)
					)
					(width 0)
					(fill yes)
				)
			)
		)
		(pad "2" smd custom
			(at 0 0.4445 180)
			(size 0.1397 0.1397)
			(layers "F.Cu" "F.Mask" "F.Paste")
			(net "SW_PWR_R_HDD33")
			(options
				(clearance outline)
				(anchor circle)
			)
			(primitives
				(gr_poly
					(pts
						(arc
							(start -0.1778 -0.2794)
							(mid -0.249642 -0.249642)
							(end -0.2794 -0.1778)
						)
						(arc
							(start -0.2794 0.1778)
							(mid -0.249642 0.249642)
							(end -0.1778 0.2794)
						)
						(arc
							(start 0.1778 0.2794)
							(mid 0.249642 0.249642)
							(end 0.2794 0.1778)
						)
						(arc
							(start 0.2794 -0.1778)
							(mid 0.249642 -0.249642)
							(end 0.1778 -0.2794)
						)
					)
					(width 0)
					(fill yes)
				)
			)
		)
	)
	(footprint ""
		(layer "F.Cu")
		(at 80.01 -247.65 180)
		(property "Reference" "D2"
			(at 0 0 180)
			(layer "F.SilkS")
			(hide yes)
			(effects
				(font
					(size 1.27 1.27)
				)
			)
		)
		(property "Value" "RB551V30-GP"
			(at 0 -6.7818 180)
			(unlocked yes)
			(layer "F.Fab")
			(hide yes)
			(effects
				(font
					(size 1.016 1.016)
					(thickness 0.1524)
				)
			)
		)
		(property "Device Type" "SOD323AKH38"
			(at 0 -8.6868 180)
			(unlocked yes)
			(layer "F.Fab")
			(hide yes)
			(effects
				(font
					(size 1.016 1.016)
					(thickness 0.1524)
				)
			)
		)
		(duplicate_pad_numbers_are_jumpers no)
		(fp_line
			(start 0.889 2.159)
			(end -0.889 2.159)
			(stroke
				(width 0.1524)
				(type default)
			)
			(layer "F.SilkS")
		)
		(fp_line
			(start 0.889 -1.9304)
			(end 0.889 2.159)
			(stroke
				(width 0.1524)
				(type default)
			)
			(layer "F.SilkS")
		)
		(fp_line
			(start 0.762 2.0574)
			(end -0.762 2.0574)
			(stroke
				(width 0.508)
				(type default)
			)
			(layer "F.SilkS")
		)
		(fp_line
			(start -0.889 2.159)
			(end -0.889 -1.9304)
			(stroke
				(width 0.1524)
				(type default)
			)
			(layer "F.SilkS")
		)
		(fp_line
			(start -0.889 -1.9304)
			(end 0.889 -1.9304)
			(stroke
				(width 0.1524)
				(type default)
			)
			(layer "F.SilkS")
		)
		(fp_rect
			(start -1.016 2.3114)
			(end 1.016 -2.0066)
			(stroke
				(width 0)
				(type default)
			)
			(fill no)
			(layer "F.CrtYd")
		)
		(fp_poly
			(pts
				(xy -1.016 -2.0066) (xy 1.016 -2.0066) (xy 1.016 2.3114) (xy -1.016 2.3114)
			)
			(stroke
				(width 0)
				(type default)
			)
			(fill no)
			(layer "F.Fab")
		)
		(pad "A" smd rect
			(at 0 -1.143 180)
			(size 0.5588 1.016)
			(layers "F.Cu" "F.Mask" "F.Paste")
			(net "SW_HDD_R2")
		)
		(pad "K" smd rect
			(at 0 1.143 180)
			(size 0.5588 1.016)
			(layers "F.Cu" "F.Mask" "F.Paste")
			(net "SW_HDD_N2")
		)
	)
	(footprint ""
		(layer "F.Cu")
		(at 319.40246 -244.884194 90)
		(property "Reference" "VIA13"
			(at 0 0 90)
			(layer "F.SilkS")
			(hide yes)
			(effects
				(font
					(size 1.27 1.27)
				)
			)
		)
		(property "Value" "100OHM-8L-2D36MM-L18-GP"
			(at 3.8989 0.5715 90)
			(unlocked yes)
			(layer "F.Fab")
			(hide yes)
			(effects
				(font
					(size 1.016 1.016)
					(thickness 0.1524)
				)
			)
		)
		(property "Device Type" "VIA-PCIE-4P-414097"
			(at 3.8989 -0.9525 90)
			(unlocked yes)
			(layer "F.Fab")
			(hide yes)
			(effects
				(font
					(size 1.016 1.016)
					(thickness 0.1524)
				)
			)
		)
		(duplicate_pad_numbers_are_jumpers no)
		(fp_rect
			(start -2.0701 0.4826)
			(end 2.0701 -0.4826)
			(stroke
				(width 0)
				(type default)
			)
			(fill no)
			(layer "F.CrtYd")
		)
		(fp_rect
			(start -2.0701 0.4826)
			(end 2.0701 -0.4826)
			(stroke
				(width 0)
				(type default)
			)
			(fill no)
			(layer "F.Fab")
		)
		(pad "1" thru_hole circle
			(at -1.5875 0 90)
			(size 0.508 0.508)
			(drill 0.254)
			(layers "*.Cu" "*.Mask")
			(remove_unused_layers no)
			(net "GND")
			(clearance 0.2286)
			(thermal_gap 0.2286)
		)
		(pad "2" thru_hole circle
			(at -0.5715 0 90)
			(size 0.508 0.508)
			(drill 0.254)
			(layers "*.Cu" "*.Mask")
			(remove_unused_layers no)
			(net "PHY_SCC_B_TO_DRV_B_6_DP")
			(clearance 0.2286)
			(thermal_gap 0.2286)
		)
		(pad "3" thru_hole circle
			(at 0.5715 0 90)
			(size 0.508 0.508)
			(drill 0.254)
			(layers "*.Cu" "*.Mask")
			(remove_unused_layers no)
			(net "PHY_SCC_B_TO_DRV_B_6_DN")
			(clearance 0.2286)
			(thermal_gap 0.2286)
		)
		(pad "4" thru_hole circle
			(at 1.5875 0 90)
			(size 0.508 0.508)
			(drill 0.254)
			(layers "*.Cu" "*.Mask")
			(remove_unused_layers no)
			(net "GND")
			(clearance 0.2286)
			(thermal_gap 0.2286)
		)
	)
	(footprint ""
		(layer "F.Cu")
		(at 221.522798 -107.414568)
		(property "Reference" "R16"
			(at 0 0 0)
			(layer "F.SilkS")
			(hide yes)
			(effects
				(font
					(size 1.27 1.27)
				)
			)
		)
		(property "Value" "1KR2F-3-GP"
			(at 0.064008 -3.993896 0)
			(unlocked yes)
			(layer "F.Fab")
			(hide yes)
			(effects
				(font
					(size 1.016 1.016)
					(thickness 0.1524)
				)
			)
		)
		(property "Device Type" "R402H16"
			(at 0.064008 -5.517896 0)
			(unlocked yes)
			(layer "F.Fab")
			(hide yes)
			(effects
				(font
					(size 1.016 1.016)
					(thickness 0.1524)
				)
			)
		)
		(duplicate_pad_numbers_are_jumpers no)
		(fp_line
			(start -0.508 -0.9398)
			(end -0.508 0.9398)
			(stroke
				(width 0.1524)
				(type default)
			)
			(layer "F.SilkS")
		)
		(fp_line
			(start 0.508 -0.9398)
			(end -0.508 -0.9398)
			(stroke
				(width 0.1524)
				(type default)
			)
			(layer "F.SilkS")
		)
		(fp_rect
			(start -0.508 0.9398)
			(end 0.508 -0.9398)
			(stroke
				(width 0)
				(type default)
			)
			(fill no)
			(layer "F.CrtYd")
		)
		(fp_rect
			(start -0.508 0.9398)
			(end 0.508 -0.9398)
			(stroke
				(width 0)
				(type default)
			)
			(fill no)
			(layer "F.Fab")
		)
		(pad "1" smd custom
			(at 0 -0.4445)
			(size 0.1397 0.1397)
			(layers "F.Cu" "F.Mask" "F.Paste")
			(net "P3V3_STBY_B")
			(options
				(clearance outline)
				(anchor circle)
			)
			(primitives
				(gr_poly
					(pts
						(arc
							(start -0.1778 -0.2794)
							(mid -0.249642 -0.249642)
							(end -0.2794 -0.1778)
						)
						(arc
							(start -0.2794 0.1778)
							(mid -0.249642 0.249642)
							(end -0.1778 0.2794)
						)
						(arc
							(start 0.1778 0.2794)
							(mid 0.249642 0.249642)
							(end 0.2794 0.1778)
						)
						(arc
							(start 0.2794 -0.1778)
							(mid 0.249642 -0.249642)
							(end 0.1778 -0.2794)
						)
					)
					(width 0)
					(fill yes)
				)
			)
		)
		(pad "2" smd custom
			(at 0 0.4445)
			(size 0.1397 0.1397)
			(layers "F.Cu" "F.Mask" "F.Paste")
			(net "I2C_BMC_B_EXP_B_SCL")
			(options
				(clearance outline)
				(anchor circle)
			)
			(primitives
				(gr_poly
					(pts
						(arc
							(start -0.1778 -0.2794)
							(mid -0.249642 -0.249642)
							(end -0.2794 -0.1778)
						)
						(arc
							(start -0.2794 0.1778)
							(mid -0.249642 0.249642)
							(end -0.1778 0.2794)
						)
						(arc
							(start 0.1778 0.2794)
							(mid 0.249642 0.249642)
							(end 0.2794 0.1778)
						)
						(arc
							(start 0.2794 -0.1778)
							(mid 0.249642 -0.249642)
							(end 0.1778 -0.2794)
						)
					)
					(width 0)
					(fill yes)
				)
			)
		)
	)
	(footprint ""
		(layer "F.Cu")
		(at 392.938 -267.843 180)
		(property "Reference" "C134"
			(at 0 0 180)
			(layer "F.SilkS")
			(hide yes)
			(effects
				(font
					(size 1.27 1.27)
				)
			)
		)
		(property "Value" "SC1U16V3KX-5GP"
			(at 0 -2.8194 180)
			(unlocked yes)
			(layer "F.Fab")
			(hide yes)
			(effects
				(font
					(size 1.016 1.016)
					(thickness 0.1524)
				)
			)
		)
		(property "Device Type" "C603H36"
			(at 0 -4.3434 180)
			(unlocked yes)
			(layer "F.Fab")
			(hide yes)
			(effects
				(font
					(size 1.016 1.016)
					(thickness 0.1524)
				)
			)
		)
		(duplicate_pad_numbers_are_jumpers no)
		(fp_line
			(start 0.508 0)
			(end -0.508 0)
			(stroke
				(width 0.2032)
				(type default)
			)
			(layer "F.SilkS")
		)
		(fp_rect
			(start -0.5842 1.3335)
			(end 0.5842 -1.3335)
			(stroke
				(width 0)
				(type default)
			)
			(fill no)
			(layer "F.CrtYd")
		)
		(fp_rect
			(start -0.5842 1.3335)
			(end 0.5842 -1.3335)
			(stroke
				(width 0)
				(type default)
			)
			(fill no)
			(layer "F.Fab")
		)
		(pad "1" smd custom
			(at 0 -0.762 180)
			(size 0.2159 0.2159)
			(layers "F.Cu" "F.Mask" "F.Paste")
			(net "P5V_HDD8")
			(options
				(clearance outline)
				(anchor circle)
			)
			(primitives
				(gr_poly
					(pts
						(arc
							(start -0.3302 -0.4318)
							(mid -0.402042 -0.402042)
							(end -0.4318 -0.3302)
						)
						(arc
							(start -0.4318 0.3302)
							(mid -0.402042 0.402042)
							(end -0.3302 0.4318)
						)
						(arc
							(start 0.3302 0.4318)
							(mid 0.402042 0.402042)
							(end 0.4318 0.3302)
						)
						(arc
							(start 0.4318 -0.3302)
							(mid 0.402042 -0.402042)
							(end 0.3302 -0.4318)
						)
					)
					(width 0)
					(fill yes)
				)
			)
		)
		(pad "2" smd custom
			(at 0 0.762 180)
			(size 0.2159 0.2159)
			(layers "F.Cu" "F.Mask" "F.Paste")
			(net "GND")
			(options
				(clearance outline)
				(anchor circle)
			)
			(primitives
				(gr_poly
					(pts
						(arc
							(start -0.3302 -0.4318)
							(mid -0.402042 -0.402042)
							(end -0.4318 -0.3302)
						)
						(arc
							(start -0.4318 0.3302)
							(mid -0.402042 0.402042)
							(end -0.3302 0.4318)
						)
						(arc
							(start 0.3302 0.4318)
							(mid 0.402042 0.402042)
							(end 0.4318 0.3302)
						)
						(arc
							(start 0.4318 -0.3302)
							(mid 0.402042 -0.402042)
							(end 0.3302 -0.4318)
						)
					)
					(width 0)
					(fill yes)
				)
			)
		)
	)
	(footprint ""
		(layer "F.Cu")
		(at 353.184714 -244.660674 -90)
		(property "Reference" "C120"
			(at 0 0 270)
			(layer "F.SilkS")
			(hide yes)
			(effects
				(font
					(size 1.27 1.27)
				)
			)
		)
		(property "Value" "SCD01U16V1KX-GP"
			(at -2.8321 -1.7399 270)
			(unlocked yes)
			(layer "F.Fab")
			(hide yes)
			(effects
				(font
					(size 1.016 1.016)
					(thickness 0.1524)
				)
			)
		)
		(property "Device Type" "C0201H13"
			(at -2.8321 -3.2639 270)
			(unlocked yes)
			(layer "F.Fab")
			(hide yes)
			(effects
				(font
					(size 1.016 1.016)
					(thickness 0.1524)
				)
			)
		)
		(duplicate_pad_numbers_are_jumpers no)
		(fp_rect
			(start -0.2794 0.6477)
			(end 0.2794 -0.6477)
			(stroke
				(width 0)
				(type default)
			)
			(fill no)
			(layer "F.CrtYd")
		)
		(fp_rect
			(start -0.2794 0.6477)
			(end 0.2794 -0.6477)
			(stroke
				(width 0)
				(type default)
			)
			(fill no)
			(layer "F.Fab")
		)
		(pad "1" smd custom
			(at 0 -0.2794 270)
			(size 0.0762 0.0762)
			(layers "F.Cu" "F.Mask" "F.Paste")
			(net "SAS_HDD_RX_P7")
			(options
				(clearance outline)
				(anchor circle)
			)
			(primitives
				(gr_poly
					(pts
						(arc
							(start 0.1524 -0.127)
							(mid 0.137521 -0.162921)
							(end 0.1016 -0.1778)
						)
						(arc
							(start -0.1016 -0.1778)
							(mid -0.137521 -0.162921)
							(end -0.1524 -0.127)
						)
						(arc
							(start -0.1524 0.127)
							(mid -0.137521 0.162921)
							(end -0.1016 0.1778)
						)
						(arc
							(start 0.1016 0.1778)
							(mid 0.137521 0.162921)
							(end 0.1524 0.127)
						)
					)
					(width 0)
					(fill yes)
				)
			)
		)
		(pad "2" smd custom
			(at 0 0.2794 270)
			(size 0.0762 0.0762)
			(layers "F.Cu" "F.Mask" "F.Paste")
			(net "PHY_SCC_B_TO_DRV_B_7_DP")
			(options
				(clearance outline)
				(anchor circle)
			)
			(primitives
				(gr_poly
					(pts
						(arc
							(start 0.1524 -0.127)
							(mid 0.137521 -0.162921)
							(end 0.1016 -0.1778)
						)
						(arc
							(start -0.1016 -0.1778)
							(mid -0.137521 -0.162921)
							(end -0.1524 -0.127)
						)
						(arc
							(start -0.1524 0.127)
							(mid -0.137521 0.162921)
							(end -0.1016 0.1778)
						)
						(arc
							(start 0.1016 0.1778)
							(mid 0.137521 0.162921)
							(end 0.1524 0.127)
						)
					)
					(width 0)
					(fill yes)
				)
			)
		)
	)
	(footprint ""
		(layer "F.Cu")
		(at 113.03 -99.314)
		(property "Reference" "R413"
			(at 0 0 0)
			(layer "F.SilkS")
			(hide yes)
			(effects
				(font
					(size 1.27 1.27)
				)
			)
		)
		(property "Value" "91R3F-1-GP"
			(at -0.0254 -2.5146 0)
			(unlocked yes)
			(layer "F.Fab")
			(hide yes)
			(effects
				(font
					(size 1.016 1.016)
					(thickness 0.1524)
				)
			)
		)
		(property "Device Type" "R603H22"
			(at -0.0254 -4.0386 0)
			(unlocked yes)
			(layer "F.Fab")
			(hide yes)
			(effects
				(font
					(size 1.016 1.016)
					(thickness 0.1524)
				)
			)
		)
		(duplicate_pad_numbers_are_jumpers no)
		(fp_line
			(start -0.4826 0)
			(end -0.2032 0)
			(stroke
				(width 0.2032)
				(type default)
			)
			(layer "F.SilkS")
		)
		(fp_line
			(start 0.2032 0)
			(end 0.4826 0)
			(stroke
				(width 0.2032)
				(type default)
			)
			(layer "F.SilkS")
		)
		(fp_rect
			(start -0.5842 1.3335)
			(end 0.5842 -1.3335)
			(stroke
				(width 0)
				(type default)
			)
			(fill no)
			(layer "F.CrtYd")
		)
		(fp_rect
			(start -0.5842 1.3335)
			(end 0.5842 -1.3335)
			(stroke
				(width 0)
				(type default)
			)
			(fill no)
			(layer "F.Fab")
		)
		(pad "1" smd custom
			(at 0 -0.762)
			(size 0.2159 0.2159)
			(layers "F.Cu" "F.Mask" "F.Paste")
			(net "P5V_B_2")
			(options
				(clearance outline)
				(anchor circle)
			)
			(primitives
				(gr_poly
					(pts
						(arc
							(start -0.3302 -0.4318)
							(mid -0.402042 -0.402042)
							(end -0.4318 -0.3302)
						)
						(arc
							(start -0.4318 0.3302)
							(mid -0.402042 0.402042)
							(end -0.3302 0.4318)
						)
						(arc
							(start 0.3302 0.4318)
							(mid 0.402042 0.402042)
							(end 0.4318 0.3302)
						)
						(arc
							(start 0.4318 -0.3302)
							(mid 0.402042 -0.402042)
							(end 0.3302 -0.4318)
						)
					)
					(width 0)
					(fill yes)
				)
			)
		)
		(pad "2" smd custom
			(at 0 0.762)
			(size 0.2159 0.2159)
			(layers "F.Cu" "F.Mask" "F.Paste")
			(net "DRV_ACT_15")
			(options
				(clearance outline)
				(anchor circle)
			)
			(primitives
				(gr_poly
					(pts
						(arc
							(start -0.3302 -0.4318)
							(mid -0.402042 -0.402042)
							(end -0.4318 -0.3302)
						)
						(arc
							(start -0.4318 0.3302)
							(mid -0.402042 0.402042)
							(end -0.3302 0.4318)
						)
						(arc
							(start 0.3302 0.4318)
							(mid 0.402042 0.402042)
							(end 0.4318 0.3302)
						)
						(arc
							(start 0.4318 -0.3302)
							(mid 0.402042 -0.402042)
							(end 0.3302 -0.4318)
						)
					)
					(width 0)
					(fill yes)
				)
			)
		)
	)
	(footprint ""
		(layer "F.Cu")
		(at 244.37848 -197.86854 -90)
		(property "Reference" "R73"
			(at 0 0 270)
			(layer "F.SilkS")
			(hide yes)
			(effects
				(font
					(size 1.27 1.27)
				)
			)
		)
		(property "Value" "4K7R2F-GP"
			(at 0.064008 -3.993896 270)
			(unlocked yes)
			(layer "F.Fab")
			(hide yes)
			(effects
				(font
					(size 1.016 1.016)
					(thickness 0.1524)
				)
			)
		)
		(property "Device Type" "R402H16"
			(at 0.064008 -5.517896 270)
			(unlocked yes)
			(layer "F.Fab")
			(hide yes)
			(effects
				(font
					(size 1.016 1.016)
					(thickness 0.1524)
				)
			)
		)
		(duplicate_pad_numbers_are_jumpers no)
		(fp_line
			(start -0.508 -0.9398)
			(end -0.508 0.9398)
			(stroke
				(width 0.1524)
				(type default)
			)
			(layer "F.SilkS")
		)
		(fp_line
			(start 0.508 -0.9398)
			(end -0.508 -0.9398)
			(stroke
				(width 0.1524)
				(type default)
			)
			(layer "F.SilkS")
		)
		(fp_rect
			(start -0.508 0.9398)
			(end 0.508 -0.9398)
			(stroke
				(width 0)
				(type default)
			)
			(fill no)
			(layer "F.CrtYd")
		)
		(fp_rect
			(start -0.508 0.9398)
			(end 0.508 -0.9398)
			(stroke
				(width 0)
				(type default)
			)
			(fill no)
			(layer "F.Fab")
		)
		(pad "1" smd custom
			(at 0 -0.4445 270)
			(size 0.1397 0.1397)
			(layers "F.Cu" "F.Mask" "F.Paste")
			(net "P3V3_STBY_B")
			(options
				(clearance outline)
				(anchor circle)
			)
			(primitives
				(gr_poly
					(pts
						(arc
							(start -0.1778 -0.2794)
							(mid -0.249642 -0.249642)
							(end -0.2794 -0.1778)
						)
						(arc
							(start -0.2794 0.1778)
							(mid -0.249642 0.249642)
							(end -0.1778 0.2794)
						)
						(arc
							(start 0.1778 0.2794)
							(mid 0.249642 0.249642)
							(end 0.2794 0.1778)
						)
						(arc
							(start 0.2794 -0.1778)
							(mid 0.249642 -0.249642)
							(end 0.1778 -0.2794)
						)
					)
					(width 0)
					(fill yes)
				)
			)
		)
		(pad "2" smd custom
			(at 0 0.4445 270)
			(size 0.1397 0.1397)
			(layers "F.Cu" "F.Mask" "F.Paste")
			(net "IO_EXP2_A2")
			(options
				(clearance outline)
				(anchor circle)
			)
			(primitives
				(gr_poly
					(pts
						(arc
							(start -0.1778 -0.2794)
							(mid -0.249642 -0.249642)
							(end -0.2794 -0.1778)
						)
						(arc
							(start -0.2794 0.1778)
							(mid -0.249642 0.249642)
							(end -0.1778 0.2794)
						)
						(arc
							(start 0.1778 0.2794)
							(mid 0.249642 0.249642)
							(end 0.2794 0.1778)
						)
						(arc
							(start 0.2794 -0.1778)
							(mid 0.249642 -0.249642)
							(end 0.1778 -0.2794)
						)
					)
					(width 0)
					(fill yes)
				)
			)
		)
	)
	(footprint ""
		(layer "F.Cu")
		(at 432.689 -250.444 90)
		(property "Reference" "R314"
			(at 0 0 90)
			(layer "F.SilkS")
			(hide yes)
			(effects
				(font
					(size 1.27 1.27)
				)
			)
		)
		(property "Value" "200KR2F-L-GP"
			(at 0.064008 -3.993896 90)
			(unlocked yes)
			(layer "F.Fab")
			(hide yes)
			(effects
				(font
					(size 1.016 1.016)
					(thickness 0.1524)
				)
			)
		)
		(property "Device Type" "R402H16"
			(at 0.064008 -5.517896 90)
			(unlocked yes)
			(layer "F.Fab")
			(hide yes)
			(effects
				(font
					(size 1.016 1.016)
					(thickness 0.1524)
				)
			)
		)
		(duplicate_pad_numbers_are_jumpers no)
		(fp_line
			(start 0.508 -0.9398)
			(end -0.508 -0.9398)
			(stroke
				(width 0.1524)
				(type default)
			)
			(layer "F.SilkS")
		)
		(fp_line
			(start -0.508 -0.9398)
			(end -0.508 0.9398)
			(stroke
				(width 0.1524)
				(type default)
			)
			(layer "F.SilkS")
		)
		(fp_rect
			(start -0.508 0.9398)
			(end 0.508 -0.9398)
			(stroke
				(width 0)
				(type default)
			)
			(fill no)
			(layer "F.CrtYd")
		)
		(fp_rect
			(start -0.508 0.9398)
			(end 0.508 -0.9398)
			(stroke
				(width 0)
				(type default)
			)
			(fill no)
			(layer "F.Fab")
		)
		(pad "1" smd custom
			(at 0 -0.4445 90)
			(size 0.1397 0.1397)
			(layers "F.Cu" "F.Mask" "F.Paste")
			(net "SW_HDD_R9")
			(options
				(clearance outline)
				(anchor circle)
			)
			(primitives
				(gr_poly
					(pts
						(arc
							(start -0.1778 -0.2794)
							(mid -0.249642 -0.249642)
							(end -0.2794 -0.1778)
						)
						(arc
							(start -0.2794 0.1778)
							(mid -0.249642 0.249642)
							(end -0.1778 0.2794)
						)
						(arc
							(start 0.1778 0.2794)
							(mid 0.249642 0.249642)
							(end 0.2794 0.1778)
						)
						(arc
							(start 0.2794 -0.1778)
							(mid 0.249642 -0.249642)
							(end 0.1778 -0.2794)
						)
					)
					(width 0)
					(fill yes)
				)
			)
		)
		(pad "2" smd custom
			(at 0 0.4445 90)
			(size 0.1397 0.1397)
			(layers "F.Cu" "F.Mask" "F.Paste")
			(net "SW_HDD_N9")
			(options
				(clearance outline)
				(anchor circle)
			)
			(primitives
				(gr_poly
					(pts
						(arc
							(start -0.1778 -0.2794)
							(mid -0.249642 -0.249642)
							(end -0.2794 -0.1778)
						)
						(arc
							(start -0.2794 0.1778)
							(mid -0.249642 0.249642)
							(end -0.1778 0.2794)
						)
						(arc
							(start 0.1778 0.2794)
							(mid 0.249642 0.249642)
							(end 0.2794 0.1778)
						)
						(arc
							(start 0.2794 -0.1778)
							(mid 0.249642 -0.249642)
							(end 0.1778 -0.2794)
						)
					)
					(width 0)
					(fill yes)
				)
			)
		)
	)
	(footprint ""
		(layer "F.Cu")
		(at 401.828 -143.891 90)
		(property "Reference" "C299"
			(at 0 0 90)
			(layer "F.SilkS")
			(hide yes)
			(effects
				(font
					(size 1.27 1.27)
				)
			)
		)
		(property "Value" "SCD033U25V2KX-GP"
			(at 1.1811 -2.7051 90)
			(unlocked yes)
			(layer "F.Fab")
			(hide yes)
			(effects
				(font
					(size 1.016 1.016)
					(thickness 0.1524)
				)
			)
		)
		(property "Device Type" "C402H22"
			(at 1.1811 -4.2291 90)
			(unlocked yes)
			(layer "F.Fab")
			(hide yes)
			(effects
				(font
					(size 1.016 1.016)
					(thickness 0.1524)
				)
			)
		)
		(duplicate_pad_numbers_are_jumpers no)
		(fp_rect
			(start -0.4318 0.9525)
			(end 0.4318 -0.9525)
			(stroke
				(width 0)
				(type default)
			)
			(fill no)
			(layer "F.CrtYd")
		)
		(fp_rect
			(start -0.4318 0.9525)
			(end 0.4318 -0.9525)
			(stroke
				(width 0)
				(type default)
			)
			(fill no)
			(layer "F.Fab")
		)
		(pad "1" smd custom
			(at 0 -0.4445 90)
			(size 0.1524 0.1524)
			(layers "F.Cu" "F.Mask" "F.Paste")
			(net "P12V_B")
			(options
				(clearance outline)
				(anchor circle)
			)
			(primitives
				(gr_poly
					(pts
						(arc
							(start 0.3048 -0.2032)
							(mid 0.275042 -0.275042)
							(end 0.2032 -0.3048)
						)
						(arc
							(start -0.2032 -0.3048)
							(mid -0.275042 -0.275042)
							(end -0.3048 -0.2032)
						)
						(arc
							(start -0.3048 0.2032)
							(mid -0.275042 0.275042)
							(end -0.2032 0.3048)
						)
						(arc
							(start 0.2032 0.3048)
							(mid 0.275042 0.275042)
							(end 0.3048 0.2032)
						)
					)
					(width 0)
					(fill yes)
				)
			)
		)
		(pad "2" smd custom
			(at 0 0.4445 90)
			(size 0.1524 0.1524)
			(layers "F.Cu" "F.Mask" "F.Paste")
			(net "SW_HDD_N20")
			(options
				(clearance outline)
				(anchor circle)
			)
			(primitives
				(gr_poly
					(pts
						(arc
							(start 0.3048 -0.2032)
							(mid 0.275042 -0.275042)
							(end 0.2032 -0.3048)
						)
						(arc
							(start -0.2032 -0.3048)
							(mid -0.275042 -0.275042)
							(end -0.3048 -0.2032)
						)
						(arc
							(start -0.3048 0.2032)
							(mid -0.275042 0.275042)
							(end -0.2032 0.3048)
						)
						(arc
							(start 0.2032 0.3048)
							(mid 0.275042 0.275042)
							(end 0.3048 0.2032)
						)
					)
					(width 0)
					(fill yes)
				)
			)
		)
	)
	(footprint ""
		(layer "F.Cu")
		(at 46.33595 -217.337386 -90)
		(property "Reference" "R156"
			(at 0 0 270)
			(layer "F.SilkS")
			(hide yes)
			(effects
				(font
					(size 1.27 1.27)
				)
			)
		)
		(property "Value" "4K7R2F-GP"
			(at 0.064008 -3.993896 270)
			(unlocked yes)
			(layer "F.Fab")
			(hide yes)
			(effects
				(font
					(size 1.016 1.016)
					(thickness 0.1524)
				)
			)
		)
		(property "Device Type" "R402H16"
			(at 0.064008 -5.517896 270)
			(unlocked yes)
			(layer "F.Fab")
			(hide yes)
			(effects
				(font
					(size 1.016 1.016)
					(thickness 0.1524)
				)
			)
		)
		(duplicate_pad_numbers_are_jumpers no)
		(fp_line
			(start -0.508 -0.9398)
			(end -0.508 0.9398)
			(stroke
				(width 0.1524)
				(type default)
			)
			(layer "F.SilkS")
		)
		(fp_line
			(start 0.508 -0.9398)
			(end -0.508 -0.9398)
			(stroke
				(width 0.1524)
				(type default)
			)
			(layer "F.SilkS")
		)
		(fp_rect
			(start -0.508 0.9398)
			(end 0.508 -0.9398)
			(stroke
				(width 0)
				(type default)
			)
			(fill no)
			(layer "F.CrtYd")
		)
		(fp_rect
			(start -0.508 0.9398)
			(end 0.508 -0.9398)
			(stroke
				(width 0)
				(type default)
			)
			(fill no)
			(layer "F.Fab")
		)
		(pad "1" smd custom
			(at 0 -0.4445 270)
			(size 0.1397 0.1397)
			(layers "F.Cu" "F.Mask" "F.Paste")
			(net "DRIVE_B_1_FLT_LED")
			(options
				(clearance outline)
				(anchor circle)
			)
			(primitives
				(gr_poly
					(pts
						(arc
							(start -0.1778 -0.2794)
							(mid -0.249642 -0.249642)
							(end -0.2794 -0.1778)
						)
						(arc
							(start -0.2794 0.1778)
							(mid -0.249642 0.249642)
							(end -0.1778 0.2794)
						)
						(arc
							(start 0.1778 0.2794)
							(mid 0.249642 0.249642)
							(end 0.2794 0.1778)
						)
						(arc
							(start 0.2794 -0.1778)
							(mid 0.249642 -0.249642)
							(end 0.1778 -0.2794)
						)
					)
					(width 0)
					(fill yes)
				)
			)
		)
		(pad "2" smd custom
			(at 0 0.4445 270)
			(size 0.1397 0.1397)
			(layers "F.Cu" "F.Mask" "F.Paste")
			(net "GND")
			(options
				(clearance outline)
				(anchor circle)
			)
			(primitives
				(gr_poly
					(pts
						(arc
							(start -0.1778 -0.2794)
							(mid -0.249642 -0.249642)
							(end -0.2794 -0.1778)
						)
						(arc
							(start -0.2794 0.1778)
							(mid -0.249642 0.249642)
							(end -0.1778 0.2794)
						)
						(arc
							(start 0.1778 0.2794)
							(mid 0.249642 0.249642)
							(end 0.2794 0.1778)
						)
						(arc
							(start 0.2794 -0.1778)
							(mid 0.249642 -0.249642)
							(end 0.1778 -0.2794)
						)
					)
					(width 0)
					(fill yes)
				)
			)
		)
	)
	(footprint ""
		(layer "F.Cu")
		(at 407.093928 -217.413586 -90)
		(property "Reference" "R290"
			(at 0 0 270)
			(layer "F.SilkS")
			(hide yes)
			(effects
				(font
					(size 1.27 1.27)
				)
			)
		)
		(property "Value" "4K7R2F-GP"
			(at 0.064008 -3.993896 270)
			(unlocked yes)
			(layer "F.Fab")
			(hide yes)
			(effects
				(font
					(size 1.016 1.016)
					(thickness 0.1524)
				)
			)
		)
		(property "Device Type" "R402H16"
			(at 0.064008 -5.517896 270)
			(unlocked yes)
			(layer "F.Fab")
			(hide yes)
			(effects
				(font
					(size 1.016 1.016)
					(thickness 0.1524)
				)
			)
		)
		(duplicate_pad_numbers_are_jumpers no)
		(fp_line
			(start -0.508 -0.9398)
			(end -0.508 0.9398)
			(stroke
				(width 0.1524)
				(type default)
			)
			(layer "F.SilkS")
		)
		(fp_line
			(start 0.508 -0.9398)
			(end -0.508 -0.9398)
			(stroke
				(width 0.1524)
				(type default)
			)
			(layer "F.SilkS")
		)
		(fp_rect
			(start -0.508 0.9398)
			(end 0.508 -0.9398)
			(stroke
				(width 0)
				(type default)
			)
			(fill no)
			(layer "F.CrtYd")
		)
		(fp_rect
			(start -0.508 0.9398)
			(end 0.508 -0.9398)
			(stroke
				(width 0)
				(type default)
			)
			(fill no)
			(layer "F.Fab")
		)
		(pad "1" smd custom
			(at 0 -0.4445 270)
			(size 0.1397 0.1397)
			(layers "F.Cu" "F.Mask" "F.Paste")
			(net "DRIVE_B_9_FLT_LED")
			(options
				(clearance outline)
				(anchor circle)
			)
			(primitives
				(gr_poly
					(pts
						(arc
							(start -0.1778 -0.2794)
							(mid -0.249642 -0.249642)
							(end -0.2794 -0.1778)
						)
						(arc
							(start -0.2794 0.1778)
							(mid -0.249642 0.249642)
							(end -0.1778 0.2794)
						)
						(arc
							(start 0.1778 0.2794)
							(mid 0.249642 0.249642)
							(end 0.2794 0.1778)
						)
						(arc
							(start 0.2794 -0.1778)
							(mid 0.249642 -0.249642)
							(end 0.1778 -0.2794)
						)
					)
					(width 0)
					(fill yes)
				)
			)
		)
		(pad "2" smd custom
			(at 0 0.4445 270)
			(size 0.1397 0.1397)
			(layers "F.Cu" "F.Mask" "F.Paste")
			(net "GND")
			(options
				(clearance outline)
				(anchor circle)
			)
			(primitives
				(gr_poly
					(pts
						(arc
							(start -0.1778 -0.2794)
							(mid -0.249642 -0.249642)
							(end -0.2794 -0.1778)
						)
						(arc
							(start -0.2794 0.1778)
							(mid -0.249642 0.249642)
							(end -0.1778 0.2794)
						)
						(arc
							(start 0.1778 0.2794)
							(mid 0.249642 0.249642)
							(end 0.2794 0.1778)
						)
						(arc
							(start 0.2794 -0.1778)
							(mid 0.249642 -0.249642)
							(end 0.1778 -0.2794)
						)
					)
					(width 0)
					(fill yes)
				)
			)
		)
	)
	(footprint ""
		(layer "F.Cu")
		(at 458.505814 -378.4854 -90)
		(property "Reference" "R1304"
			(at 0 0 270)
			(layer "F.SilkS")
			(hide yes)
			(effects
				(font
					(size 1.27 1.27)
				)
			)
		)
		(property "Value" "4K7R2F-GP"
			(at 0.064008 -3.993896 270)
			(unlocked yes)
			(layer "F.Fab")
			(hide yes)
			(effects
				(font
					(size 1.016 1.016)
					(thickness 0.1524)
				)
			)
		)
		(property "Device Type" "R402H16"
			(at 0.064008 -5.517896 270)
			(unlocked yes)
			(layer "F.Fab")
			(hide yes)
			(effects
				(font
					(size 1.016 1.016)
					(thickness 0.1524)
				)
			)
		)
		(duplicate_pad_numbers_are_jumpers no)
		(fp_line
			(start -0.508 -0.9398)
			(end -0.508 0.9398)
			(stroke
				(width 0.1524)
				(type default)
			)
			(layer "F.SilkS")
		)
		(fp_line
			(start 0.508 -0.9398)
			(end -0.508 -0.9398)
			(stroke
				(width 0.1524)
				(type default)
			)
			(layer "F.SilkS")
		)
		(fp_rect
			(start -0.508 0.9398)
			(end 0.508 -0.9398)
			(stroke
				(width 0)
				(type default)
			)
			(fill no)
			(layer "F.CrtYd")
		)
		(fp_rect
			(start -0.508 0.9398)
			(end 0.508 -0.9398)
			(stroke
				(width 0)
				(type default)
			)
			(fill no)
			(layer "F.Fab")
		)
		(pad "1" smd custom
			(at 0 -0.4445 270)
			(size 0.1397 0.1397)
			(layers "F.Cu" "F.Mask" "F.Paste")
			(net "FAN_BLUE_LED3")
			(options
				(clearance outline)
				(anchor circle)
			)
			(primitives
				(gr_poly
					(pts
						(arc
							(start -0.1778 -0.2794)
							(mid -0.249642 -0.249642)
							(end -0.2794 -0.1778)
						)
						(arc
							(start -0.2794 0.1778)
							(mid -0.249642 0.249642)
							(end -0.1778 0.2794)
						)
						(arc
							(start 0.1778 0.2794)
							(mid 0.249642 0.249642)
							(end 0.2794 0.1778)
						)
						(arc
							(start 0.2794 -0.1778)
							(mid 0.249642 -0.249642)
							(end 0.1778 -0.2794)
						)
					)
					(width 0)
					(fill yes)
				)
			)
		)
		(pad "2" smd custom
			(at 0 0.4445 270)
			(size 0.1397 0.1397)
			(layers "F.Cu" "F.Mask" "F.Paste")
			(net "FAN_LED3_D")
			(options
				(clearance outline)
				(anchor circle)
			)
			(primitives
				(gr_poly
					(pts
						(arc
							(start -0.1778 -0.2794)
							(mid -0.249642 -0.249642)
							(end -0.2794 -0.1778)
						)
						(arc
							(start -0.2794 0.1778)
							(mid -0.249642 0.249642)
							(end -0.1778 0.2794)
						)
						(arc
							(start 0.1778 0.2794)
							(mid 0.249642 0.249642)
							(end 0.2794 0.1778)
						)
						(arc
							(start 0.2794 -0.1778)
							(mid 0.249642 -0.249642)
							(end 0.1778 -0.2794)
						)
					)
					(width 0)
					(fill yes)
				)
			)
		)
	)
	(footprint ""
		(layer "F.Cu")
		(at 436.089044 -111.731552 90)
		(property "Reference" "C676"
			(at 0 0 90)
			(layer "F.SilkS")
			(hide yes)
			(effects
				(font
					(size 1.27 1.27)
				)
			)
		)
		(property "Value" "SC10U16V5KX-7-GP-U"
			(at -0.0762 -6.1214 90)
			(unlocked yes)
			(layer "F.Fab")
			(hide yes)
			(effects
				(font
					(size 1.016 1.016)
					(thickness 0.1524)
				)
			)
		)
		(property "Device Type" "C805H58"
			(at -0.0762 -8.1534 90)
			(unlocked yes)
			(layer "F.Fab")
			(hide yes)
			(effects
				(font
					(size 1.016 1.016)
					(thickness 0.1524)
				)
			)
		)
		(duplicate_pad_numbers_are_jumpers no)
		(fp_line
			(start 0.635 0)
			(end -0.635 0)
			(stroke
				(width 0.508)
				(type default)
			)
			(layer "F.SilkS")
		)
		(fp_rect
			(start -0.9652 1.778)
			(end 0.9652 -1.778)
			(stroke
				(width 0)
				(type default)
			)
			(fill no)
			(layer "F.CrtYd")
		)
		(fp_poly
			(pts
				(xy -0.9652 -1.778) (xy 0.9652 -1.778) (xy 0.9652 1.778) (xy -0.9652 1.778)
			)
			(stroke
				(width 0)
				(type default)
			)
			(fill no)
			(layer "F.Fab")
		)
		(pad "1" smd rect
			(at 0 -0.9652 90)
			(size 1.397 1.143)
			(layers "F.Cu" "F.Mask" "F.Paste")
			(net "P12V_B_4_VIN_U34")
		)
		(pad "2" smd rect
			(at 0 0.9652 90)
			(size 1.397 1.143)
			(layers "F.Cu" "F.Mask" "F.Paste")
			(net "GND")
		)
	)
	(footprint ""
		(layer "F.Cu")
		(at 165.224968 -99.798378 90)
		(property "Reference" "Q259"
			(at 0 0 90)
			(layer "F.SilkS")
			(hide yes)
			(effects
				(font
					(size 1.27 1.27)
				)
			)
		)
		(property "Value" "SSM3K324R-GP"
			(at 0.127 -8.9662 90)
			(unlocked yes)
			(layer "F.Fab")
			(hide yes)
			(effects
				(font
					(size 1.016 1.016)
					(thickness 0.1524)
				)
			)
		)
		(property "Device Type" "SOT23DGS2D4H35"
			(at 0.127 -10.4902 90)
			(unlocked yes)
			(layer "F.Fab")
			(hide yes)
			(effects
				(font
					(size 1.016 1.016)
					(thickness 0.1524)
				)
			)
		)
		(duplicate_pad_numbers_are_jumpers no)
		(fp_line
			(start 1.651 -1.778)
			(end -1.651 -1.778)
			(stroke
				(width 0.1524)
				(type default)
			)
			(layer "F.SilkS")
		)
		(fp_line
			(start -1.651 -1.778)
			(end -1.651 1.778)
			(stroke
				(width 0.1524)
				(type default)
			)
			(layer "F.SilkS")
		)
		(fp_line
			(start 1.651 1.778)
			(end 1.651 -1.778)
			(stroke
				(width 0.1524)
				(type default)
			)
			(layer "F.SilkS")
		)
		(fp_line
			(start -1.651 1.778)
			(end 1.651 1.778)
			(stroke
				(width 0.1524)
				(type default)
			)
			(layer "F.SilkS")
		)
		(fp_poly
			(pts
				(xy -1.778 1.8796) (xy -1.778 -1.8796) (xy 1.778 -1.8796) (xy 1.778 1.8796)
			)
			(stroke
				(width 0)
				(type default)
			)
			(fill no)
			(layer "F.CrtYd")
		)
		(fp_poly
			(pts
				(xy -1.778 1.8796) (xy -1.778 -1.8796) (xy 1.778 -1.8796) (xy 1.778 1.8796)
			)
			(stroke
				(width 0)
				(type default)
			)
			(fill no)
			(layer "F.Fab")
		)
		(pad "D" smd custom
			(at 0 -0.9525 90)
			(size 0.1905 0.1905)
			(layers "F.Cu" "F.Mask" "F.Paste")
			(net "DRV_ACT_17_N")
			(options
				(clearance outline)
				(anchor circle)
			)
			(primitives
				(gr_poly
					(pts
						(arc
							(start -0.1778 0.5715)
							(mid -0.321484 0.511984)
							(end -0.381 0.3683)
						)
						(arc
							(start -0.381 -0.3683)
							(mid -0.321484 -0.511984)
							(end -0.1778 -0.5715)
						)
						(arc
							(start 0.1778 -0.5715)
							(mid 0.321484 -0.511984)
							(end 0.381 -0.3683)
						)
						(arc
							(start 0.381 0.3683)
							(mid 0.321484 0.511984)
							(end 0.1778 0.5715)
						)
					)
					(width 0)
					(fill yes)
				)
			)
		)
		(pad "G" smd custom
			(at -0.98425 0.9525 90)
			(size 0.1905 0.1905)
			(layers "F.Cu" "F.Mask" "F.Paste")
			(net "DRIVE_B_17_ACT")
			(options
				(clearance outline)
				(anchor circle)
			)
			(primitives
				(gr_poly
					(pts
						(arc
							(start -0.1778 0.5715)
							(mid -0.321484 0.511984)
							(end -0.381 0.3683)
						)
						(arc
							(start -0.381 -0.3683)
							(mid -0.321484 -0.511984)
							(end -0.1778 -0.5715)
						)
						(arc
							(start 0.1778 -0.5715)
							(mid 0.321484 -0.511984)
							(end 0.381 -0.3683)
						)
						(arc
							(start 0.381 0.3683)
							(mid 0.321484 0.511984)
							(end 0.1778 0.5715)
						)
					)
					(width 0)
					(fill yes)
				)
			)
		)
		(pad "S" smd custom
			(at 0.98425 0.9525 90)
			(size 0.1905 0.1905)
			(layers "F.Cu" "F.Mask" "F.Paste")
			(net "GND")
			(options
				(clearance outline)
				(anchor circle)
			)
			(primitives
				(gr_poly
					(pts
						(arc
							(start -0.1778 0.5715)
							(mid -0.321484 0.511984)
							(end -0.381 0.3683)
						)
						(arc
							(start -0.381 -0.3683)
							(mid -0.321484 -0.511984)
							(end -0.1778 -0.5715)
						)
						(arc
							(start 0.1778 -0.5715)
							(mid 0.321484 -0.511984)
							(end 0.381 -0.3683)
						)
						(arc
							(start 0.381 0.3683)
							(mid 0.321484 0.511984)
							(end 0.1778 0.5715)
						)
					)
					(width 0)
					(fill yes)
				)
			)
		)
	)
	(footprint ""
		(layer "F.Cu")
		(at 29.457396 -376.0216 90)
		(property "Reference" "R173"
			(at 0 0 90)
			(layer "F.SilkS")
			(hide yes)
			(effects
				(font
					(size 1.27 1.27)
				)
			)
		)
		(property "Value" "4K7R2F-GP"
			(at 0.064008 -3.993896 90)
			(unlocked yes)
			(layer "F.Fab")
			(hide yes)
			(effects
				(font
					(size 1.016 1.016)
					(thickness 0.1524)
				)
			)
		)
		(property "Device Type" "R402H16"
			(at 0.064008 -5.517896 90)
			(unlocked yes)
			(layer "F.Fab")
			(hide yes)
			(effects
				(font
					(size 1.016 1.016)
					(thickness 0.1524)
				)
			)
		)
		(duplicate_pad_numbers_are_jumpers no)
		(fp_line
			(start 0.508 -0.9398)
			(end -0.508 -0.9398)
			(stroke
				(width 0.1524)
				(type default)
			)
			(layer "F.SilkS")
		)
		(fp_line
			(start -0.508 -0.9398)
			(end -0.508 0.9398)
			(stroke
				(width 0.1524)
				(type default)
			)
			(layer "F.SilkS")
		)
		(fp_rect
			(start -0.508 0.9398)
			(end 0.508 -0.9398)
			(stroke
				(width 0)
				(type default)
			)
			(fill no)
			(layer "F.CrtYd")
		)
		(fp_rect
			(start -0.508 0.9398)
			(end 0.508 -0.9398)
			(stroke
				(width 0)
				(type default)
			)
			(fill no)
			(layer "F.Fab")
		)
		(pad "1" smd custom
			(at 0 -0.4445 90)
			(size 0.1397 0.1397)
			(layers "F.Cu" "F.Mask" "F.Paste")
			(net "FAN_BLUE_LED0")
			(options
				(clearance outline)
				(anchor circle)
			)
			(primitives
				(gr_poly
					(pts
						(arc
							(start -0.1778 -0.2794)
							(mid -0.249642 -0.249642)
							(end -0.2794 -0.1778)
						)
						(arc
							(start -0.2794 0.1778)
							(mid -0.249642 0.249642)
							(end -0.1778 0.2794)
						)
						(arc
							(start 0.1778 0.2794)
							(mid 0.249642 0.249642)
							(end 0.2794 0.1778)
						)
						(arc
							(start 0.2794 -0.1778)
							(mid 0.249642 -0.249642)
							(end 0.1778 -0.2794)
						)
					)
					(width 0)
					(fill yes)
				)
			)
		)
		(pad "2" smd custom
			(at 0 0.4445 90)
			(size 0.1397 0.1397)
			(layers "F.Cu" "F.Mask" "F.Paste")
			(net "P12V_IN")
			(options
				(clearance outline)
				(anchor circle)
			)
			(primitives
				(gr_poly
					(pts
						(arc
							(start -0.1778 -0.2794)
							(mid -0.249642 -0.249642)
							(end -0.2794 -0.1778)
						)
						(arc
							(start -0.2794 0.1778)
							(mid -0.249642 0.249642)
							(end -0.1778 0.2794)
						)
						(arc
							(start 0.1778 0.2794)
							(mid 0.249642 0.249642)
							(end 0.2794 0.1778)
						)
						(arc
							(start 0.2794 -0.1778)
							(mid 0.249642 -0.249642)
							(end 0.1778 -0.2794)
						)
					)
					(width 0)
					(fill yes)
				)
			)
		)
	)
	(footprint ""
		(layer "F.Cu")
		(at 413.866076 -154.70505)
		(property "Reference" "TP126"
			(at 0 0 0)
			(layer "F.SilkS")
			(hide yes)
			(effects
				(font
					(size 1.27 1.27)
				)
			)
		)
		(property "Value" "*"
			(at -0.0508 -1.6764 0)
			(unlocked yes)
			(layer "F.Fab")
			(hide yes)
			(effects
				(font
					(size 1.016 1.016)
					(thickness 0.1524)
				)
			)
		)
		(property "Device Type" "TPAD32"
			(at -0.0508 -3.2004 0)
			(unlocked yes)
			(layer "F.Fab")
			(hide yes)
			(effects
				(font
					(size 1.016 1.016)
					(thickness 0.1524)
				)
			)
		)
		(duplicate_pad_numbers_are_jumpers no)
		(fp_poly
			(pts
				(arc
					(start 0.4064 0)
					(mid -0.4064 0)
					(end 0.4064 0)
				)
			)
			(stroke
				(width 0)
				(type default)
			)
			(fill no)
			(layer "F.CrtYd")
		)
		(fp_poly
			(pts
				(arc
					(start 0.7112 0)
					(mid -0.7112 0)
					(end 0.7112 0)
				)
			)
			(stroke
				(width 0)
				(type default)
			)
			(fill no)
			(layer "F.Fab")
		)
		(pad "1" smd circle
			(at 0 0)
			(size 0.8128 0.8128)
			(layers "F.Cu" "F.Mask" "F.Paste")
			(net "ACT_HDD_21")
		)
	)
	(footprint ""
		(layer "F.Cu")
		(at 23.749 -263.271)
		(property "Reference" "R897"
			(at 0 0 0)
			(layer "F.SilkS")
			(hide yes)
			(effects
				(font
					(size 1.27 1.27)
				)
			)
		)
		(property "Value" "2R6F-GP"
			(at -0.0508 -4.8514 0)
			(unlocked yes)
			(layer "F.Fab")
			(hide yes)
			(effects
				(font
					(size 1.016 1.016)
					(thickness 0.1524)
				)
			)
		)
		(property "Device Type" "R1206H26"
			(at 0 -6.3754 0)
			(unlocked yes)
			(layer "F.Fab")
			(hide yes)
			(effects
				(font
					(size 1.016 1.016)
					(thickness 0.1524)
				)
			)
		)
		(duplicate_pad_numbers_are_jumpers no)
		(fp_line
			(start -1.016 -2.2352)
			(end 1.016 -2.2352)
			(stroke
				(width 0.1524)
				(type default)
			)
			(layer "F.SilkS")
		)
		(fp_line
			(start -1.016 2.2352)
			(end -1.016 -2.2352)
			(stroke
				(width 0.1524)
				(type default)
			)
			(layer "F.SilkS")
		)
		(fp_line
			(start 1.016 -2.2352)
			(end 1.016 2.2352)
			(stroke
				(width 0.1524)
				(type default)
			)
			(layer "F.SilkS")
		)
		(fp_line
			(start 1.016 2.2352)
			(end -1.016 2.2352)
			(stroke
				(width 0.1524)
				(type default)
			)
			(layer "F.SilkS")
		)
		(fp_rect
			(start -1.0922 2.3114)
			(end 1.0922 -2.3114)
			(stroke
				(width 0)
				(type default)
			)
			(fill no)
			(layer "F.CrtYd")
		)
		(fp_poly
			(pts
				(xy -1.0922 -2.3114) (xy 1.0922 -2.3114) (xy 1.0922 2.3114) (xy -1.0922 2.3114)
			)
			(stroke
				(width 0)
				(type default)
			)
			(fill no)
			(layer "F.Fab")
		)
		(pad "1" smd rect
			(at 0 -1.397)
			(size 1.651 1.27)
			(layers "F.Cu" "F.Mask" "F.Paste")
			(net "P5V_HDD0")
		)
		(pad "2" smd rect
			(at 0 1.397)
			(size 1.651 1.27)
			(layers "F.Cu" "F.Mask" "F.Paste")
			(net "5V_PRE_0")
		)
	)
	(footprint ""
		(layer "F.Cu")
		(at 280.67 -330.1238 -90)
		(property "Reference" "U11"
			(at 0 0 270)
			(layer "F.SilkS")
			(hide yes)
			(effects
				(font
					(size 1.27 1.27)
				)
			)
		)
		(property "Value" "TSLV07APWR-GP"
			(at -7.112 -6.0579 270)
			(unlocked yes)
			(layer "F.Fab")
			(hide yes)
			(effects
				(font
					(size 1.016 1.016)
					(thickness 0.1524)
				)
			)
		)
		(property "Device Type" "TSOIC14H48"
			(at -7.112 -7.5819 270)
			(unlocked yes)
			(layer "F.Fab")
			(hide yes)
			(effects
				(font
					(size 1.016 1.016)
					(thickness 0.1524)
				)
			)
		)
		(duplicate_pad_numbers_are_jumpers no)
		(fp_line
			(start -2.794 3.8227)
			(end -2.794 1.7018)
			(stroke
				(width 0.508)
				(type default)
			)
			(layer "F.SilkS")
		)
		(fp_line
			(start -2.9718 1.778)
			(end -2.9718 -1.778)
			(stroke
				(width 0.1524)
				(type default)
			)
			(layer "F.SilkS")
		)
		(fp_line
			(start 2.1336 1.778)
			(end -2.9718 1.778)
			(stroke
				(width 0.1524)
				(type default)
			)
			(layer "F.SilkS")
		)
		(fp_line
			(start -2.8956 0.4572)
			(end -2.921 0.4572)
			(stroke
				(width 0.1524)
				(type default)
			)
			(layer "F.SilkS")
		)
		(fp_line
			(start -2.4384 0)
			(end -2.8956 0.4572)
			(stroke
				(width 0.1524)
				(type default)
			)
			(layer "F.SilkS")
		)
		(fp_line
			(start -2.9337 -0.4699)
			(end -2.9083 -0.4699)
			(stroke
				(width 0.1524)
				(type default)
			)
			(layer "F.SilkS")
		)
		(fp_line
			(start -2.9083 -0.4699)
			(end -2.4384 0)
			(stroke
				(width 0.1524)
				(type default)
			)
			(layer "F.SilkS")
		)
		(fp_line
			(start -2.9718 -1.778)
			(end 2.1336 -1.778)
			(stroke
				(width 0.1524)
				(type default)
			)
			(layer "F.SilkS")
		)
		(fp_line
			(start 2.1336 -1.778)
			(end 2.1336 1.778)
			(stroke
				(width 0.1524)
				(type default)
			)
			(layer "F.SilkS")
		)
		(fp_poly
			(pts
				(xy -2.1336 -1.7653) (xy 2.1336 -1.7653) (xy 2.1336 1.778) (xy -2.1336 1.778)
			)
			(stroke
				(width 0)
				(type default)
			)
			(fill yes)
			(layer "F.SilkS")
		)
		(fp_rect
			(start -2.5019 3.2004)
			(end 2.5019 -3.2004)
			(stroke
				(width 0)
				(type default)
			)
			(fill no)
			(layer "F.CrtYd")
		)
		(fp_poly
			(pts
				(xy -3.048 4.0894) (xy -3.048 -2.5781) (xy -2.5019 -2.5781) (xy -2.5019 3.2004) (xy 2.5019 3.2004)
				(xy 2.5019 -3.2004) (xy -2.5019 -3.2004) (xy -2.5019 -2.5908) (xy -3.048 -2.5908) (xy -3.048 -4.0894)
				(xy 3.048 -4.0894) (xy 3.048 4.0894)
			)
			(stroke
				(width 0)
				(type default)
			)
			(fill no)
			(layer "F.CrtYd")
		)
		(fp_rect
			(start -3.048 4.0894)
			(end 3.048 -4.0894)
			(stroke
				(width 0)
				(type default)
			)
			(fill no)
			(layer "F.Fab")
		)
		(pad "1" smd rect
			(at -1.94945 2.8194 270)
			(size 0.3556 1.524)
			(layers "F.Cu" "F.Mask" "F.Paste")
			(net "PWM_OUT_C")
		)
		(pad "2" smd rect
			(at -1.30048 2.8194 270)
			(size 0.3556 1.524)
			(layers "F.Cu" "F.Mask" "F.Paste")
			(net "PWM_OUT_FAN1")
		)
		(pad "3" smd rect
			(at -0.65024 2.8194 270)
			(size 0.3556 1.524)
			(layers "F.Cu" "F.Mask" "F.Paste")
			(net "PWM_OUT_C")
		)
		(pad "4" smd rect
			(at 0 2.8194 270)
			(size 0.3556 1.524)
			(layers "F.Cu" "F.Mask" "F.Paste")
			(net "PWM_OUT_FAN2")
		)
		(pad "5" smd rect
			(at 0.65024 2.8194 270)
			(size 0.3556 1.524)
			(layers "F.Cu" "F.Mask" "F.Paste")
			(net "PWM_OUT_D")
		)
		(pad "6" smd rect
			(at 1.30048 2.8194 270)
			(size 0.3556 1.524)
			(layers "F.Cu" "F.Mask" "F.Paste")
			(net "PWM_OUT_FAN0")
		)
		(pad "7" smd rect
			(at 1.94945 2.8194 270)
			(size 0.3556 1.524)
			(layers "F.Cu" "F.Mask" "F.Paste")
			(net "GND")
		)
		(pad "8" smd rect
			(at 1.94945 -2.8194 270)
			(size 0.3556 1.524)
			(layers "F.Cu" "F.Mask" "F.Paste")
			(net "PWM_OUT_FAN3")
		)
		(pad "9" smd rect
			(at 1.30048 -2.8194 270)
			(size 0.3556 1.524)
			(layers "F.Cu" "F.Mask" "F.Paste")
			(net "PWM_OUT_D")
		)
		(pad "10" smd rect
			(at 0.65024 -2.8194 270)
			(size 0.3556 1.524)
			(layers "F.Cu" "F.Mask" "F.Paste")
			(net "Net_1057")
		)
		(pad "11" smd rect
			(at 0 -2.8194 270)
			(size 0.3556 1.524)
			(layers "F.Cu" "F.Mask" "F.Paste")
			(net "Net_234")
		)
		(pad "12" smd rect
			(at -0.65024 -2.8194 270)
			(size 0.3556 1.524)
			(layers "F.Cu" "F.Mask" "F.Paste")
			(net "Net_1056")
		)
		(pad "13" smd rect
			(at -1.30048 -2.8194 270)
			(size 0.3556 1.524)
			(layers "F.Cu" "F.Mask" "F.Paste")
			(net "Net_235")
		)
		(pad "14" smd rect
			(at -1.94945 -2.8194 270)
			(size 0.3556 1.524)
			(layers "F.Cu" "F.Mask" "F.Paste")
			(net "P3V3_IN")
		)
	)
	(footprint ""
		(layer "F.Cu")
		(at 458.216 -243.586)
		(property "Reference" "R327"
			(at 0 0 0)
			(layer "F.SilkS")
			(hide yes)
			(effects
				(font
					(size 1.27 1.27)
				)
			)
		)
		(property "Value" "4K7R2F-GP"
			(at 0.064008 -3.993896 0)
			(unlocked yes)
			(layer "F.Fab")
			(hide yes)
			(effects
				(font
					(size 1.016 1.016)
					(thickness 0.1524)
				)
			)
		)
		(property "Device Type" "R402H16"
			(at 0.064008 -5.517896 0)
			(unlocked yes)
			(layer "F.Fab")
			(hide yes)
			(effects
				(font
					(size 1.016 1.016)
					(thickness 0.1524)
				)
			)
		)
		(duplicate_pad_numbers_are_jumpers no)
		(fp_line
			(start -0.508 -0.9398)
			(end -0.508 0.9398)
			(stroke
				(width 0.1524)
				(type default)
			)
			(layer "F.SilkS")
		)
		(fp_line
			(start 0.508 -0.9398)
			(end -0.508 -0.9398)
			(stroke
				(width 0.1524)
				(type default)
			)
			(layer "F.SilkS")
		)
		(fp_rect
			(start -0.508 0.9398)
			(end 0.508 -0.9398)
			(stroke
				(width 0)
				(type default)
			)
			(fill no)
			(layer "F.CrtYd")
		)
		(fp_rect
			(start -0.508 0.9398)
			(end 0.508 -0.9398)
			(stroke
				(width 0)
				(type default)
			)
			(fill no)
			(layer "F.Fab")
		)
		(pad "1" smd custom
			(at 0 -0.4445)
			(size 0.1397 0.1397)
			(layers "F.Cu" "F.Mask" "F.Paste")
			(net "SW_PWR_R_HDD10")
			(options
				(clearance outline)
				(anchor circle)
			)
			(primitives
				(gr_poly
					(pts
						(arc
							(start -0.1778 -0.2794)
							(mid -0.249642 -0.249642)
							(end -0.2794 -0.1778)
						)
						(arc
							(start -0.2794 0.1778)
							(mid -0.249642 0.249642)
							(end -0.1778 0.2794)
						)
						(arc
							(start 0.1778 0.2794)
							(mid 0.249642 0.249642)
							(end 0.2794 0.1778)
						)
						(arc
							(start 0.2794 -0.1778)
							(mid 0.249642 -0.249642)
							(end 0.1778 -0.2794)
						)
					)
					(width 0)
					(fill yes)
				)
			)
		)
		(pad "2" smd custom
			(at 0 0.4445)
			(size 0.1397 0.1397)
			(layers "F.Cu" "F.Mask" "F.Paste")
			(net "GND")
			(options
				(clearance outline)
				(anchor circle)
			)
			(primitives
				(gr_poly
					(pts
						(arc
							(start -0.1778 -0.2794)
							(mid -0.249642 -0.249642)
							(end -0.2794 -0.1778)
						)
						(arc
							(start -0.2794 0.1778)
							(mid -0.249642 0.249642)
							(end -0.1778 0.2794)
						)
						(arc
							(start 0.1778 0.2794)
							(mid 0.249642 0.249642)
							(end 0.2794 0.1778)
						)
						(arc
							(start 0.2794 -0.1778)
							(mid 0.249642 -0.249642)
							(end 0.1778 -0.2794)
						)
					)
					(width 0)
					(fill yes)
				)
			)
		)
	)
	(footprint ""
		(layer "F.Cu")
		(at 110.5154 -30.6324)
		(property "Reference" "R698"
			(at 0 0 0)
			(layer "F.SilkS")
			(hide yes)
			(effects
				(font
					(size 1.27 1.27)
				)
			)
		)
		(property "Value" "4K7R2J-2-GP"
			(at 0.064008 -3.993896 0)
			(unlocked yes)
			(layer "F.Fab")
			(hide yes)
			(effects
				(font
					(size 1.016 1.016)
					(thickness 0.1524)
				)
			)
		)
		(property "Device Type" "R402H16"
			(at 0.064008 -5.517896 0)
			(unlocked yes)
			(layer "F.Fab")
			(hide yes)
			(effects
				(font
					(size 1.016 1.016)
					(thickness 0.1524)
				)
			)
		)
		(duplicate_pad_numbers_are_jumpers no)
		(fp_line
			(start -0.508 -0.9398)
			(end -0.508 0.9398)
			(stroke
				(width 0.1524)
				(type default)
			)
			(layer "F.SilkS")
		)
		(fp_line
			(start 0.508 -0.9398)
			(end -0.508 -0.9398)
			(stroke
				(width 0.1524)
				(type default)
			)
			(layer "F.SilkS")
		)
		(fp_rect
			(start -0.508 0.9398)
			(end 0.508 -0.9398)
			(stroke
				(width 0)
				(type default)
			)
			(fill no)
			(layer "F.CrtYd")
		)
		(fp_rect
			(start -0.508 0.9398)
			(end 0.508 -0.9398)
			(stroke
				(width 0)
				(type default)
			)
			(fill no)
			(layer "F.Fab")
		)
		(pad "1" smd custom
			(at 0 -0.4445)
			(size 0.1397 0.1397)
			(layers "F.Cu" "F.Mask" "F.Paste")
			(net "P12V_B")
			(options
				(clearance outline)
				(anchor circle)
			)
			(primitives
				(gr_poly
					(pts
						(arc
							(start -0.1778 -0.2794)
							(mid -0.249642 -0.249642)
							(end -0.2794 -0.1778)
						)
						(arc
							(start -0.2794 0.1778)
							(mid -0.249642 0.249642)
							(end -0.1778 0.2794)
						)
						(arc
							(start 0.1778 0.2794)
							(mid 0.249642 0.249642)
							(end 0.2794 0.1778)
						)
						(arc
							(start 0.2794 -0.1778)
							(mid 0.249642 -0.249642)
							(end 0.1778 -0.2794)
						)
					)
					(width 0)
					(fill yes)
				)
			)
		)
		(pad "2" smd custom
			(at 0 0.4445)
			(size 0.1397 0.1397)
			(layers "F.Cu" "F.Mask" "F.Paste")
			(net "SW_HDD_P27")
			(options
				(clearance outline)
				(anchor circle)
			)
			(primitives
				(gr_poly
					(pts
						(arc
							(start -0.1778 -0.2794)
							(mid -0.249642 -0.249642)
							(end -0.2794 -0.1778)
						)
						(arc
							(start -0.2794 0.1778)
							(mid -0.249642 0.249642)
							(end -0.1778 0.2794)
						)
						(arc
							(start 0.1778 0.2794)
							(mid 0.249642 0.249642)
							(end 0.2794 0.1778)
						)
						(arc
							(start 0.2794 -0.1778)
							(mid 0.249642 -0.249642)
							(end 0.1778 -0.2794)
						)
					)
					(width 0)
					(fill yes)
				)
			)
		)
	)
	(footprint ""
		(layer "F.Cu")
		(at 163.4998 -356.2096)
		(property "Reference" "R1009"
			(at 0 0 0)
			(layer "F.SilkS")
			(hide yes)
			(effects
				(font
					(size 1.27 1.27)
				)
			)
		)
		(property "Value" "D0003R4026F-GP"
			(at -6.737858 -1.79959 0)
			(unlocked yes)
			(layer "F.Fab")
			(hide yes)
			(effects
				(font
					(size 1.016 1.016)
					(thickness 0.1524)
				)
			)
		)
		(property "Device Type" "RL4026-4PH149"
			(at -6.737858 -3.32359 0)
			(unlocked yes)
			(layer "F.Fab")
			(hide yes)
			(effects
				(font
					(size 1.016 1.016)
					(thickness 0.1524)
				)
			)
		)
		(duplicate_pad_numbers_are_jumpers no)
		(fp_line
			(start -5.6769 2.4765)
			(end -5.6769 4.0259)
			(stroke
				(width 0.3302)
				(type default)
			)
			(layer "F.SilkS")
		)
		(fp_line
			(start -5.6769 4.0259)
			(end -4.1402 4.0259)
			(stroke
				(width 0.3302)
				(type default)
			)
			(layer "F.SilkS")
		)
		(fp_line
			(start -5.588 -3.937)
			(end 5.588 -3.937)
			(stroke
				(width 0.1524)
				(type default)
			)
			(layer "F.SilkS")
		)
		(fp_line
			(start -5.588 3.937)
			(end -5.588 -3.937)
			(stroke
				(width 0.1524)
				(type default)
			)
			(layer "F.SilkS")
		)
		(fp_line
			(start 5.588 -3.937)
			(end 5.588 3.937)
			(stroke
				(width 0.1524)
				(type default)
			)
			(layer "F.SilkS")
		)
		(fp_line
			(start 5.588 3.937)
			(end -5.588 3.937)
			(stroke
				(width 0.1524)
				(type default)
			)
			(layer "F.SilkS")
		)
		(fp_poly
			(pts
				(xy -4.703572 3.998468) (xy -5.289804 4.5847) (xy -4.11734 4.5847)
			)
			(stroke
				(width 0)
				(type default)
			)
			(fill yes)
			(layer "F.SilkS")
		)
		(fp_rect
			(start -5.0546 3.302)
			(end 5.0546 -3.302)
			(stroke
				(width 0)
				(type default)
			)
			(fill no)
			(layer "F.CrtYd")
		)
		(fp_poly
			(pts
				(xy -5.842 4.191) (xy -5.842 -4.191) (xy 5.842 -4.191) (xy 5.842 -0.00635) (xy 5.0546 -0.00635)
				(xy 5.0546 -3.302) (xy -5.0546 -3.302) (xy -5.0546 3.302) (xy 5.0546 3.302) (xy 5.0546 0.00635)
				(xy 5.842 0.00635) (xy 5.842 4.191)
			)
			(stroke
				(width 0)
				(type default)
			)
			(fill no)
			(layer "F.CrtYd")
		)
		(fp_rect
			(start -5.842 4.191)
			(end 5.842 -4.191)
			(stroke
				(width 0)
				(type default)
			)
			(fill no)
			(layer "F.Fab")
		)
		(pad "1" smd rect
			(at -4.115054 0.890016)
			(size 2.4384 5.588)
			(layers "F.Cu" "F.Mask" "F.Paste")
			(net "P12V_CLIP")
		)
		(pad "2" smd rect
			(at 4.115054 0.890016)
			(size 2.4384 5.588)
			(layers "F.Cu" "F.Mask" "F.Paste")
			(net "MB0_P12V_IN_R")
		)
		(pad "3" smd rect
			(at -4.115054 -3.245104)
			(size 2.4384 0.889)
			(layers "F.Cu" "F.Mask" "F.Paste")
			(net "MB0_CM_SENSE_R1_P")
		)
		(pad "4" smd rect
			(at 4.115054 -3.245104)
			(size 2.4384 0.889)
			(layers "F.Cu" "F.Mask" "F.Paste")
			(net "MB0_CM_SENSE_R1_N")
		)
		(zone
			(layer "F.Cu")
			(hatch none 0.5)
			(connect_pads
				(clearance 0)
			)
			(min_thickness 0.25)
			(keepout
				(tracks allowed)
				(vias not_allowed)
				(pads allowed)
				(copperpour not_allowed)
				(footprints allowed)
			)
			(placement
				(enabled no)
				(sheetname "")
			)
			(fill
				(thermal_gap 0.5)
				(thermal_bridge_width 0.5)
				(island_removal_mode 0)
			)
			(polygon
				(pts
					(xy 158.165546 -359.010204) (xy 158.165546 -358.113584) (xy 160.603946 -358.113584) (xy 160.603946 -359.010204)
				)
			)
		)
		(zone
			(layer "F.Cu")
			(hatch none 0.5)
			(connect_pads
				(clearance 0)
			)
			(min_thickness 0.25)
			(keepout
				(tracks not_allowed)
				(vias allowed)
				(pads allowed)
				(copperpour not_allowed)
				(footprints allowed)
			)
			(placement
				(enabled no)
				(sheetname "")
			)
			(fill
				(thermal_gap 0.5)
				(thermal_bridge_width 0.5)
				(island_removal_mode 0)
			)
			(polygon
				(pts
					(xy 158.165546 -358.113584) (xy 160.603946 -358.113584) (xy 160.603946 -359.010204) (xy 158.165546 -359.010204)
				)
			)
		)
		(zone
			(layer "F.Cu")
			(hatch none 0.5)
			(connect_pads
				(clearance 0)
			)
			(min_thickness 0.25)
			(keepout
				(tracks allowed)
				(vias not_allowed)
				(pads allowed)
				(copperpour not_allowed)
				(footprints allowed)
			)
			(placement
				(enabled no)
				(sheetname "")
			)
			(fill
				(thermal_gap 0.5)
				(thermal_bridge_width 0.5)
				(island_removal_mode 0)
			)
			(polygon
				(pts
					(xy 166.395654 -359.010204) (xy 166.395654 -358.113584) (xy 168.834054 -358.113584) (xy 168.834054 -359.010204)
				)
			)
		)
		(zone
			(layer "F.Cu")
			(hatch none 0.5)
			(connect_pads
				(clearance 0)
			)
			(min_thickness 0.25)
			(keepout
				(tracks not_allowed)
				(vias allowed)
				(pads allowed)
				(copperpour not_allowed)
				(footprints allowed)
			)
			(placement
				(enabled no)
				(sheetname "")
			)
			(fill
				(thermal_gap 0.5)
				(thermal_bridge_width 0.5)
				(island_removal_mode 0)
			)
			(polygon
				(pts
					(xy 166.395654 -358.113584) (xy 168.834054 -358.113584) (xy 168.834054 -359.010204) (xy 166.395654 -359.010204)
				)
			)
		)
	)
	(footprint ""
		(layer "F.Cu")
		(at 98.806 -151.003 90)
		(property "Reference" "R396"
			(at 0 0 90)
			(layer "F.SilkS")
			(hide yes)
			(effects
				(font
					(size 1.27 1.27)
				)
			)
		)
		(property "Value" "220R3F-1-GP"
			(at -0.0254 -2.5146 90)
			(unlocked yes)
			(layer "F.Fab")
			(hide yes)
			(effects
				(font
					(size 1.016 1.016)
					(thickness 0.1524)
				)
			)
		)
		(property "Device Type" "R603H22"
			(at -0.0254 -4.0386 90)
			(unlocked yes)
			(layer "F.Fab")
			(hide yes)
			(effects
				(font
					(size 1.016 1.016)
					(thickness 0.1524)
				)
			)
		)
		(duplicate_pad_numbers_are_jumpers no)
		(fp_line
			(start 0.2032 0)
			(end 0.4826 0)
			(stroke
				(width 0.2032)
				(type default)
			)
			(layer "F.SilkS")
		)
		(fp_line
			(start -0.4826 0)
			(end -0.2032 0)
			(stroke
				(width 0.2032)
				(type default)
			)
			(layer "F.SilkS")
		)
		(fp_rect
			(start -0.5842 1.3335)
			(end 0.5842 -1.3335)
			(stroke
				(width 0)
				(type default)
			)
			(fill no)
			(layer "F.CrtYd")
		)
		(fp_rect
			(start -0.5842 1.3335)
			(end 0.5842 -1.3335)
			(stroke
				(width 0)
				(type default)
			)
			(fill no)
			(layer "F.Fab")
		)
		(pad "1" smd custom
			(at 0 -0.762 90)
			(size 0.2159 0.2159)
			(layers "F.Cu" "F.Mask" "F.Paste")
			(net "HDD_PRSNT_14")
			(options
				(clearance outline)
				(anchor circle)
			)
			(primitives
				(gr_poly
					(pts
						(arc
							(start -0.3302 -0.4318)
							(mid -0.402042 -0.402042)
							(end -0.4318 -0.3302)
						)
						(arc
							(start -0.4318 0.3302)
							(mid -0.402042 0.402042)
							(end -0.3302 0.4318)
						)
						(arc
							(start 0.3302 0.4318)
							(mid 0.402042 0.402042)
							(end 0.4318 0.3302)
						)
						(arc
							(start 0.4318 -0.3302)
							(mid 0.402042 -0.402042)
							(end 0.3302 -0.4318)
						)
					)
					(width 0)
					(fill yes)
				)
			)
		)
		(pad "2" smd custom
			(at 0 0.762 90)
			(size 0.2159 0.2159)
			(layers "F.Cu" "F.Mask" "F.Paste")
			(net "DRIVE_B_14_INS")
			(options
				(clearance outline)
				(anchor circle)
			)
			(primitives
				(gr_poly
					(pts
						(arc
							(start -0.3302 -0.4318)
							(mid -0.402042 -0.402042)
							(end -0.4318 -0.3302)
						)
						(arc
							(start -0.4318 0.3302)
							(mid -0.402042 0.402042)
							(end -0.3302 0.4318)
						)
						(arc
							(start 0.3302 0.4318)
							(mid 0.402042 0.402042)
							(end 0.4318 0.3302)
						)
						(arc
							(start 0.4318 -0.3302)
							(mid 0.402042 -0.402042)
							(end 0.3302 -0.4318)
						)
					)
					(width 0)
					(fill yes)
				)
			)
		)
	)
	(footprint ""
		(layer "F.Cu")
		(at 245.578122 -367.131346 90)
		(property "Reference" "R1111"
			(at 0 0 90)
			(layer "F.SilkS")
			(hide yes)
			(effects
				(font
					(size 1.27 1.27)
				)
			)
		)
		(property "Value" "10R2F-L-GP"
			(at 0.064008 -3.993896 90)
			(unlocked yes)
			(layer "F.Fab")
			(hide yes)
			(effects
				(font
					(size 1.016 1.016)
					(thickness 0.1524)
				)
			)
		)
		(property "Device Type" "R402H14"
			(at 0.064008 -5.517896 90)
			(unlocked yes)
			(layer "F.Fab")
			(hide yes)
			(effects
				(font
					(size 1.016 1.016)
					(thickness 0.1524)
				)
			)
		)
		(duplicate_pad_numbers_are_jumpers no)
		(fp_line
			(start 0.508 -0.9398)
			(end -0.508 -0.9398)
			(stroke
				(width 0.1524)
				(type default)
			)
			(layer "F.SilkS")
		)
		(fp_line
			(start -0.508 -0.9398)
			(end -0.508 0.9398)
			(stroke
				(width 0.1524)
				(type default)
			)
			(layer "F.SilkS")
		)
		(fp_rect
			(start -0.508 0.9398)
			(end 0.508 -0.9398)
			(stroke
				(width 0)
				(type default)
			)
			(fill no)
			(layer "F.CrtYd")
		)
		(fp_rect
			(start -0.508 0.9398)
			(end 0.508 -0.9398)
			(stroke
				(width 0)
				(type default)
			)
			(fill no)
			(layer "F.Fab")
		)
		(pad "1" smd custom
			(at 0 -0.4445 90)
			(size 0.1397 0.1397)
			(layers "F.Cu" "F.Mask" "F.Paste")
			(net "MB3_CM_SENSE_R1_N")
			(options
				(clearance outline)
				(anchor circle)
			)
			(primitives
				(gr_poly
					(pts
						(arc
							(start -0.1778 -0.2794)
							(mid -0.249642 -0.249642)
							(end -0.2794 -0.1778)
						)
						(arc
							(start -0.2794 0.1778)
							(mid -0.249642 0.249642)
							(end -0.1778 0.2794)
						)
						(arc
							(start 0.1778 0.2794)
							(mid 0.249642 0.249642)
							(end 0.2794 0.1778)
						)
						(arc
							(start 0.2794 -0.1778)
							(mid 0.249642 -0.249642)
							(end 0.1778 -0.2794)
						)
					)
					(width 0)
					(fill yes)
				)
			)
		)
		(pad "2" smd custom
			(at 0 0.4445 90)
			(size 0.1397 0.1397)
			(layers "F.Cu" "F.Mask" "F.Paste")
			(net "MB3_HS_SENSE_N")
			(options
				(clearance outline)
				(anchor circle)
			)
			(primitives
				(gr_poly
					(pts
						(arc
							(start -0.1778 -0.2794)
							(mid -0.249642 -0.249642)
							(end -0.2794 -0.1778)
						)
						(arc
							(start -0.2794 0.1778)
							(mid -0.249642 0.249642)
							(end -0.1778 0.2794)
						)
						(arc
							(start 0.1778 0.2794)
							(mid 0.249642 0.249642)
							(end 0.2794 0.1778)
						)
						(arc
							(start 0.2794 -0.1778)
							(mid 0.249642 -0.249642)
							(end 0.1778 -0.2794)
						)
					)
					(width 0)
					(fill yes)
				)
			)
		)
	)
	(footprint ""
		(layer "F.Cu")
		(at 475.107 -31.877 -90)
		(property "Reference" "C486"
			(at 0 0 270)
			(layer "F.SilkS")
			(hide yes)
			(effects
				(font
					(size 1.27 1.27)
				)
			)
		)
		(property "Value" "SC10U16V6KX-2GP"
			(at -0.0762 -5.1308 270)
			(unlocked yes)
			(layer "F.Fab")
			(hide yes)
			(effects
				(font
					(size 1.016 1.016)
					(thickness 0.1524)
				)
			)
		)
		(property "Device Type" "C1206H71"
			(at -0.127 -6.6548 270)
			(unlocked yes)
			(layer "F.Fab")
			(hide yes)
			(effects
				(font
					(size 1.016 1.016)
					(thickness 0.1524)
				)
			)
		)
		(duplicate_pad_numbers_are_jumpers no)
		(fp_line
			(start -1.016 2.2352)
			(end -1.016 0.8382)
			(stroke
				(width 0.1524)
				(type default)
			)
			(layer "F.SilkS")
		)
		(fp_line
			(start 1.016 2.2352)
			(end -1.016 2.2352)
			(stroke
				(width 0.1524)
				(type default)
			)
			(layer "F.SilkS")
		)
		(fp_line
			(start 1.016 0.8382)
			(end 1.016 2.2352)
			(stroke
				(width 0.1524)
				(type default)
			)
			(layer "F.SilkS")
		)
		(fp_line
			(start -1.016 -0.8382)
			(end -1.016 -2.2352)
			(stroke
				(width 0.1524)
				(type default)
			)
			(layer "F.SilkS")
		)
		(fp_line
			(start -1.016 -2.2352)
			(end 1.016 -2.2352)
			(stroke
				(width 0.1524)
				(type default)
			)
			(layer "F.SilkS")
		)
		(fp_line
			(start 1.016 -2.2352)
			(end 1.016 -0.8382)
			(stroke
				(width 0.1524)
				(type default)
			)
			(layer "F.SilkS")
		)
		(fp_rect
			(start -1.0922 2.3114)
			(end 1.0922 -2.3114)
			(stroke
				(width 0)
				(type default)
			)
			(fill no)
			(layer "F.CrtYd")
		)
		(fp_poly
			(pts
				(xy 1.0922 -2.3114) (xy 1.0922 2.3114) (xy -1.0922 2.3114) (xy -1.0922 -2.3114)
			)
			(stroke
				(width 0)
				(type default)
			)
			(fill no)
			(layer "F.Fab")
		)
		(pad "1" smd rect
			(at 0 -1.397 270)
			(size 1.651 1.27)
			(layers "F.Cu" "F.Mask" "F.Paste")
			(net "P5V_HDD35")
		)
		(pad "2" smd rect
			(at 0 1.397 270)
			(size 1.651 1.27)
			(layers "F.Cu" "F.Mask" "F.Paste")
			(net "GND")
		)
	)
	(footprint ""
		(layer "F.Cu")
		(at 321.634612 -129.66065 -90)
		(property "Reference" "C263"
			(at 0 0 270)
			(layer "F.SilkS")
			(hide yes)
			(effects
				(font
					(size 1.27 1.27)
				)
			)
		)
		(property "Value" "SCD01U16V1KX-GP"
			(at -2.8321 -1.7399 270)
			(unlocked yes)
			(layer "F.Fab")
			(hide yes)
			(effects
				(font
					(size 1.016 1.016)
					(thickness 0.1524)
				)
			)
		)
		(property "Device Type" "C0201H13"
			(at -2.8321 -3.2639 270)
			(unlocked yes)
			(layer "F.Fab")
			(hide yes)
			(effects
				(font
					(size 1.016 1.016)
					(thickness 0.1524)
				)
			)
		)
		(duplicate_pad_numbers_are_jumpers no)
		(fp_rect
			(start -0.2794 0.6477)
			(end 0.2794 -0.6477)
			(stroke
				(width 0)
				(type default)
			)
			(fill no)
			(layer "F.CrtYd")
		)
		(fp_rect
			(start -0.2794 0.6477)
			(end 0.2794 -0.6477)
			(stroke
				(width 0)
				(type default)
			)
			(fill no)
			(layer "F.Fab")
		)
		(pad "1" smd custom
			(at 0 -0.2794 270)
			(size 0.0762 0.0762)
			(layers "F.Cu" "F.Mask" "F.Paste")
			(net "SAS_HDD_RX_P18")
			(options
				(clearance outline)
				(anchor circle)
			)
			(primitives
				(gr_poly
					(pts
						(arc
							(start 0.1524 -0.127)
							(mid 0.137521 -0.162921)
							(end 0.1016 -0.1778)
						)
						(arc
							(start -0.1016 -0.1778)
							(mid -0.137521 -0.162921)
							(end -0.1524 -0.127)
						)
						(arc
							(start -0.1524 0.127)
							(mid -0.137521 0.162921)
							(end -0.1016 0.1778)
						)
						(arc
							(start 0.1016 0.1778)
							(mid 0.137521 0.162921)
							(end 0.1524 0.127)
						)
					)
					(width 0)
					(fill yes)
				)
			)
		)
		(pad "2" smd custom
			(at 0 0.2794 270)
			(size 0.0762 0.0762)
			(layers "F.Cu" "F.Mask" "F.Paste")
			(net "PHY_SCC_B_TO_DRV_B_18_DP")
			(options
				(clearance outline)
				(anchor circle)
			)
			(primitives
				(gr_poly
					(pts
						(arc
							(start 0.1524 -0.127)
							(mid 0.137521 -0.162921)
							(end 0.1016 -0.1778)
						)
						(arc
							(start -0.1016 -0.1778)
							(mid -0.137521 -0.162921)
							(end -0.1524 -0.127)
						)
						(arc
							(start -0.1524 0.127)
							(mid -0.137521 0.162921)
							(end -0.1016 0.1778)
						)
						(arc
							(start 0.1016 0.1778)
							(mid 0.137521 0.162921)
							(end 0.1524 0.127)
						)
					)
					(width 0)
					(fill yes)
				)
			)
		)
	)
	(footprint ""
		(layer "F.Cu")
		(at 465.943696 -214.860378 90)
		(property "Reference" "Q254"
			(at 0 0 90)
			(layer "F.SilkS")
			(hide yes)
			(effects
				(font
					(size 1.27 1.27)
				)
			)
		)
		(property "Value" "SSM3K324R-GP"
			(at 0.127 -8.9662 90)
			(unlocked yes)
			(layer "F.Fab")
			(hide yes)
			(effects
				(font
					(size 1.016 1.016)
					(thickness 0.1524)
				)
			)
		)
		(property "Device Type" "SOT23DGS2D4H35"
			(at 0.127 -10.4902 90)
			(unlocked yes)
			(layer "F.Fab")
			(hide yes)
			(effects
				(font
					(size 1.016 1.016)
					(thickness 0.1524)
				)
			)
		)
		(duplicate_pad_numbers_are_jumpers no)
		(fp_line
			(start 1.651 -1.778)
			(end -1.651 -1.778)
			(stroke
				(width 0.1524)
				(type default)
			)
			(layer "F.SilkS")
		)
		(fp_line
			(start -1.651 -1.778)
			(end -1.651 1.778)
			(stroke
				(width 0.1524)
				(type default)
			)
			(layer "F.SilkS")
		)
		(fp_line
			(start 1.651 1.778)
			(end 1.651 -1.778)
			(stroke
				(width 0.1524)
				(type default)
			)
			(layer "F.SilkS")
		)
		(fp_line
			(start -1.651 1.778)
			(end 1.651 1.778)
			(stroke
				(width 0.1524)
				(type default)
			)
			(layer "F.SilkS")
		)
		(fp_poly
			(pts
				(xy -1.778 1.8796) (xy -1.778 -1.8796) (xy 1.778 -1.8796) (xy 1.778 1.8796)
			)
			(stroke
				(width 0)
				(type default)
			)
			(fill no)
			(layer "F.CrtYd")
		)
		(fp_poly
			(pts
				(xy -1.778 1.8796) (xy -1.778 -1.8796) (xy 1.778 -1.8796) (xy 1.778 1.8796)
			)
			(stroke
				(width 0)
				(type default)
			)
			(fill no)
			(layer "F.Fab")
		)
		(pad "D" smd custom
			(at 0 -0.9525 90)
			(size 0.1905 0.1905)
			(layers "F.Cu" "F.Mask" "F.Paste")
			(net "DRV_ACT_11_N")
			(options
				(clearance outline)
				(anchor circle)
			)
			(primitives
				(gr_poly
					(pts
						(arc
							(start -0.1778 0.5715)
							(mid -0.321484 0.511984)
							(end -0.381 0.3683)
						)
						(arc
							(start -0.381 -0.3683)
							(mid -0.321484 -0.511984)
							(end -0.1778 -0.5715)
						)
						(arc
							(start 0.1778 -0.5715)
							(mid 0.321484 -0.511984)
							(end 0.381 -0.3683)
						)
						(arc
							(start 0.381 0.3683)
							(mid 0.321484 0.511984)
							(end 0.1778 0.5715)
						)
					)
					(width 0)
					(fill yes)
				)
			)
		)
		(pad "G" smd custom
			(at -0.98425 0.9525 90)
			(size 0.1905 0.1905)
			(layers "F.Cu" "F.Mask" "F.Paste")
			(net "DRIVE_B_11_ACT")
			(options
				(clearance outline)
				(anchor circle)
			)
			(primitives
				(gr_poly
					(pts
						(arc
							(start -0.1778 0.5715)
							(mid -0.321484 0.511984)
							(end -0.381 0.3683)
						)
						(arc
							(start -0.381 -0.3683)
							(mid -0.321484 -0.511984)
							(end -0.1778 -0.5715)
						)
						(arc
							(start 0.1778 -0.5715)
							(mid 0.321484 -0.511984)
							(end 0.381 -0.3683)
						)
						(arc
							(start 0.381 0.3683)
							(mid 0.321484 0.511984)
							(end 0.1778 0.5715)
						)
					)
					(width 0)
					(fill yes)
				)
			)
		)
		(pad "S" smd custom
			(at 0.98425 0.9525 90)
			(size 0.1905 0.1905)
			(layers "F.Cu" "F.Mask" "F.Paste")
			(net "GND")
			(options
				(clearance outline)
				(anchor circle)
			)
			(primitives
				(gr_poly
					(pts
						(arc
							(start -0.1778 0.5715)
							(mid -0.321484 0.511984)
							(end -0.381 0.3683)
						)
						(arc
							(start -0.381 -0.3683)
							(mid -0.321484 -0.511984)
							(end -0.1778 -0.5715)
						)
						(arc
							(start 0.1778 -0.5715)
							(mid 0.321484 -0.511984)
							(end 0.381 -0.3683)
						)
						(arc
							(start 0.381 0.3683)
							(mid 0.321484 0.511984)
							(end 0.1778 0.5715)
						)
					)
					(width 0)
					(fill yes)
				)
			)
		)
	)
	(footprint ""
		(layer "F.Cu")
		(at 392.938 -37.846 180)
		(property "Reference" "C446"
			(at 0 0 180)
			(layer "F.SilkS")
			(hide yes)
			(effects
				(font
					(size 1.27 1.27)
				)
			)
		)
		(property "Value" "SC1U16V3KX-5GP"
			(at 0 -2.8194 180)
			(unlocked yes)
			(layer "F.Fab")
			(hide yes)
			(effects
				(font
					(size 1.016 1.016)
					(thickness 0.1524)
				)
			)
		)
		(property "Device Type" "C603H36"
			(at 0 -4.3434 180)
			(unlocked yes)
			(layer "F.Fab")
			(hide yes)
			(effects
				(font
					(size 1.016 1.016)
					(thickness 0.1524)
				)
			)
		)
		(duplicate_pad_numbers_are_jumpers no)
		(fp_line
			(start 0.508 0)
			(end -0.508 0)
			(stroke
				(width 0.2032)
				(type default)
			)
			(layer "F.SilkS")
		)
		(fp_rect
			(start -0.5842 1.3335)
			(end 0.5842 -1.3335)
			(stroke
				(width 0)
				(type default)
			)
			(fill no)
			(layer "F.CrtYd")
		)
		(fp_rect
			(start -0.5842 1.3335)
			(end 0.5842 -1.3335)
			(stroke
				(width 0)
				(type default)
			)
			(fill no)
			(layer "F.Fab")
		)
		(pad "1" smd custom
			(at 0 -0.762 180)
			(size 0.2159 0.2159)
			(layers "F.Cu" "F.Mask" "F.Paste")
			(net "P5V_HDD32")
			(options
				(clearance outline)
				(anchor circle)
			)
			(primitives
				(gr_poly
					(pts
						(arc
							(start -0.3302 -0.4318)
							(mid -0.402042 -0.402042)
							(end -0.4318 -0.3302)
						)
						(arc
							(start -0.4318 0.3302)
							(mid -0.402042 0.402042)
							(end -0.3302 0.4318)
						)
						(arc
							(start 0.3302 0.4318)
							(mid 0.402042 0.402042)
							(end 0.4318 0.3302)
						)
						(arc
							(start 0.4318 -0.3302)
							(mid 0.402042 -0.402042)
							(end 0.3302 -0.4318)
						)
					)
					(width 0)
					(fill yes)
				)
			)
		)
		(pad "2" smd custom
			(at 0 0.762 180)
			(size 0.2159 0.2159)
			(layers "F.Cu" "F.Mask" "F.Paste")
			(net "GND")
			(options
				(clearance outline)
				(anchor circle)
			)
			(primitives
				(gr_poly
					(pts
						(arc
							(start -0.3302 -0.4318)
							(mid -0.402042 -0.402042)
							(end -0.4318 -0.3302)
						)
						(arc
							(start -0.4318 0.3302)
							(mid -0.402042 0.402042)
							(end -0.3302 0.4318)
						)
						(arc
							(start 0.3302 0.4318)
							(mid 0.402042 0.402042)
							(end 0.4318 0.3302)
						)
						(arc
							(start 0.4318 -0.3302)
							(mid 0.402042 -0.402042)
							(end 0.3302 -0.4318)
						)
					)
					(width 0)
					(fill yes)
				)
			)
		)
	)
	(footprint ""
		(layer "F.Cu")
		(at 244.199918 -175.79975)
		(property "Reference" ""
			(at 0 0 0)
			(layer "F.SilkS")
			(hide yes)
			(effects
				(font
					(size 1.27 1.27)
				)
			)
		)
		(property "Value" "*"
			(at -8.398764 -8.057642 0)
			(unlocked yes)
			(layer "F.Fab")
			(hide yes)
			(effects
				(font
					(size 1.016 1.016)
					(thickness 0.1524)
				)
			)
		)
		(duplicate_pad_numbers_are_jumpers no)
		(fp_poly
			(pts
				(arc
					(start 7.3152 0)
					(mid 0 7.3152)
					(end -7.3152 0)
				)
				(arc
					(start -7.3152 -5.9944)
					(mid 0 -13.3096)
					(end 7.3152 -5.9944)
				)
			)
			(stroke
				(width 0)
				(type default)
			)
			(fill no)
			(layer "B.CrtYd")
		)
		(fp_poly
			(pts
				(arc
					(start 7.3152 0)
					(mid 0 7.3152)
					(end -7.3152 0)
				)
				(arc
					(start -7.3152 -5.9944)
					(mid 0 -13.3096)
					(end 7.3152 -5.9944)
				)
			)
			(stroke
				(width 0)
				(type default)
			)
			(fill no)
			(layer "F.CrtYd")
		)
		(fp_poly
			(pts
				(arc
					(start 7.3152 0)
					(mid 0 7.3152)
					(end -7.3152 0)
				)
				(arc
					(start -7.3152 -5.9944)
					(mid 0 -13.3096)
					(end 7.3152 -5.9944)
				)
			)
			(stroke
				(width 0)
				(type default)
			)
			(fill no)
			(layer "B.Fab")
		)
		(fp_poly
			(pts
				(arc
					(start 7.3152 0)
					(mid 0 7.3152)
					(end -7.3152 0)
				)
				(arc
					(start -7.3152 -5.9944)
					(mid 0 -13.3096)
					(end 7.3152 -5.9944)
				)
			)
			(stroke
				(width 0)
				(type default)
			)
			(fill no)
			(layer "F.Fab")
		)
		(pad "1" thru_hole oval
			(at 0 0)
			(size 14.0208 20.0152)
			(drill 0.0254
				(offset 0 -2.9972)
			)
			(layers "*.Cu" "*.Mask")
			(remove_unused_layers no)
			(net "Net_18")
			(clearance -1.002284)
			(thermal_gap 0.1524)
			(padstack
				(mode front_inner_back)
				(layer "Inner"
					(shape custom)
					(size 2.928012 2.928012)
					(options
						(anchor circle)
					)
					(primitives
						(gr_poly
							(pts
								(arc
									(start 4.571746 -2.084324)
									(mid 0.000333 7.430372)
									(end -4.571492 -2.084324)
								)
								(arc
									(start -4.571492 -2.084324)
									(mid -3.570296 -3.611977)
									(end -2.875026 -5.30098)
								)
								(arc
									(start -2.875026 -5.30098)
									(mid 0.000217 -7.43089)
									(end 2.87528 -5.30098)
								)
								(arc
									(start 2.87528 -5.30098)
									(mid 3.570511 -3.611956)
									(end 4.571746 -2.084324)
								)
							)
							(width 0)
							(fill yes)
						)
					)
					(clearance 0.1524)
				)
				(layer "B.Cu"
					(shape oval)
					(size 14.0208 20.0152)
					(offset 0 -2.9972)
					(clearance -1.002284)
				)
			)
		)
		(zone
			(layers "F.Cu" "B.Cu" "In1.Cu" "In2.Cu" "In3.Cu" "In4.Cu" "In5.Cu" "In6.Cu")
			(hatch none 0.5)
			(connect_pads
				(clearance 0)
			)
			(min_thickness 0.25)
			(keepout
				(tracks not_allowed)
				(vias allowed)
				(pads allowed)
				(copperpour not_allowed)
				(footprints allowed)
			)
			(placement
				(enabled no)
				(sheetname "")
			)
			(fill
				(thermal_gap 0.5)
				(thermal_bridge_width 0.5)
				(island_removal_mode 0)
			)
			(polygon
				(pts
					(arc
						(start 237.189518 -181.79415)
						(mid 244.199918 -188.80455)
						(end 251.210318 -181.79415)
					)
					(arc
						(start 251.210318 -175.79975)
						(mid 244.199918 -168.78935)
						(end 237.189518 -175.79975)
					)
				)
			)
		)
	)
	(footprint ""
		(layer "F.Cu")
		(at 265.625072 -351.431606 90)
		(property "Reference" "R1052"
			(at 0 0 90)
			(layer "F.SilkS")
			(hide yes)
			(effects
				(font
					(size 1.27 1.27)
				)
			)
		)
		(property "Value" "10R5F-1-GP"
			(at 0 -8.9535 90)
			(unlocked yes)
			(layer "F.Fab")
			(hide yes)
			(effects
				(font
					(size 1.27 1.016)
					(thickness 0.1524)
				)
			)
		)
		(property "Device Type" "R805H24"
			(at 0 -10.6299 90)
			(unlocked yes)
			(layer "F.Fab")
			(hide yes)
			(effects
				(font
					(size 1.27 1.016)
					(thickness 0.1524)
				)
			)
		)
		(duplicate_pad_numbers_are_jumpers no)
		(fp_line
			(start 0.889 -1.7018)
			(end -0.889 -1.7018)
			(stroke
				(width 0.1524)
				(type default)
			)
			(layer "F.SilkS")
		)
		(fp_line
			(start 0.889 -1.7018)
			(end 0.889 -0.381)
			(stroke
				(width 0.1524)
				(type default)
			)
			(layer "F.SilkS")
		)
		(fp_line
			(start -0.889 -1.7018)
			(end -0.889 0.2794)
			(stroke
				(width 0.1524)
				(type default)
			)
			(layer "F.SilkS")
		)
		(fp_line
			(start -0.889 0.0762)
			(end -0.889 1.7018)
			(stroke
				(width 0.1524)
				(type default)
			)
			(layer "F.SilkS")
		)
		(fp_line
			(start 0.889 1.7018)
			(end 0.889 -0.508)
			(stroke
				(width 0.1524)
				(type default)
			)
			(layer "F.SilkS")
		)
		(fp_line
			(start -0.889 1.7018)
			(end 0.889 1.7018)
			(stroke
				(width 0.1524)
				(type default)
			)
			(layer "F.SilkS")
		)
		(fp_poly
			(pts
				(xy 0.9652 -1.778) (xy 0.9652 1.778) (xy -0.9652 1.778) (xy -0.9652 -1.778)
			)
			(stroke
				(width 0)
				(type default)
			)
			(fill no)
			(layer "F.CrtYd")
		)
		(fp_rect
			(start -0.9652 1.778)
			(end 0.9652 -1.778)
			(stroke
				(width 0)
				(type default)
			)
			(fill no)
			(layer "F.Fab")
		)
		(pad "1" smd rect
			(at 0 -0.9652 90)
			(size 1.397 1.143)
			(layers "F.Cu" "F.Mask" "F.Paste")
			(net "MB3_12V_CTRL_GATE1")
		)
		(pad "2" smd rect
			(at 0 0.9652 90)
			(size 1.397 1.143)
			(layers "F.Cu" "F.Mask" "F.Paste")
			(net "MB3_CM_GATE_R")
		)
	)
	(footprint ""
		(layer "F.Cu")
		(at 234.86618 -219.03436)
		(property "Reference" "R66"
			(at 0 0 0)
			(layer "F.SilkS")
			(hide yes)
			(effects
				(font
					(size 1.27 1.27)
				)
			)
		)
		(property "Value" "0R2J-2-GP"
			(at 0.064008 -3.993896 0)
			(unlocked yes)
			(layer "F.Fab")
			(hide yes)
			(effects
				(font
					(size 1.016 1.016)
					(thickness 0.1524)
				)
			)
		)
		(property "Device Type" "R402H16"
			(at 0.064008 -5.517896 0)
			(unlocked yes)
			(layer "F.Fab")
			(hide yes)
			(effects
				(font
					(size 1.016 1.016)
					(thickness 0.1524)
				)
			)
		)
		(duplicate_pad_numbers_are_jumpers no)
		(fp_line
			(start -0.508 -0.9398)
			(end -0.508 0.9398)
			(stroke
				(width 0.1524)
				(type default)
			)
			(layer "F.SilkS")
		)
		(fp_line
			(start 0.508 -0.9398)
			(end -0.508 -0.9398)
			(stroke
				(width 0.1524)
				(type default)
			)
			(layer "F.SilkS")
		)
		(fp_rect
			(start -0.508 0.9398)
			(end 0.508 -0.9398)
			(stroke
				(width 0)
				(type default)
			)
			(fill no)
			(layer "F.CrtYd")
		)
		(fp_rect
			(start -0.508 0.9398)
			(end 0.508 -0.9398)
			(stroke
				(width 0)
				(type default)
			)
			(fill no)
			(layer "F.Fab")
		)
		(pad "1" smd custom
			(at 0 -0.4445)
			(size 0.1397 0.1397)
			(layers "F.Cu" "F.Mask" "F.Paste")
			(net "IO_EXP1_SDA")
			(options
				(clearance outline)
				(anchor circle)
			)
			(primitives
				(gr_poly
					(pts
						(arc
							(start -0.1778 -0.2794)
							(mid -0.249642 -0.249642)
							(end -0.2794 -0.1778)
						)
						(arc
							(start -0.2794 0.1778)
							(mid -0.249642 0.249642)
							(end -0.1778 0.2794)
						)
						(arc
							(start 0.1778 0.2794)
							(mid 0.249642 0.249642)
							(end 0.2794 0.1778)
						)
						(arc
							(start 0.2794 -0.1778)
							(mid 0.249642 -0.249642)
							(end 0.1778 -0.2794)
						)
					)
					(width 0)
					(fill yes)
				)
			)
		)
		(pad "2" smd custom
			(at 0 0.4445)
			(size 0.1397 0.1397)
			(layers "F.Cu" "F.Mask" "F.Paste")
			(net "I2C_DRIVE_B_PWR_SDA")
			(options
				(clearance outline)
				(anchor circle)
			)
			(primitives
				(gr_poly
					(pts
						(arc
							(start -0.1778 -0.2794)
							(mid -0.249642 -0.249642)
							(end -0.2794 -0.1778)
						)
						(arc
							(start -0.2794 0.1778)
							(mid -0.249642 0.249642)
							(end -0.1778 0.2794)
						)
						(arc
							(start 0.1778 0.2794)
							(mid 0.249642 0.249642)
							(end 0.2794 0.1778)
						)
						(arc
							(start 0.2794 -0.1778)
							(mid 0.249642 -0.249642)
							(end 0.1778 -0.2794)
						)
					)
					(width 0)
					(fill yes)
				)
			)
		)
	)
	(footprint ""
		(layer "F.Cu")
		(at 481.066602 -132.437124)
		(property "Reference" "VIA48"
			(at 0 0 0)
			(layer "F.SilkS")
			(hide yes)
			(effects
				(font
					(size 1.27 1.27)
				)
			)
		)
		(property "Value" "100OHM-8L-2D36MM-L16-GP"
			(at -3.4036 -0.4572 0)
			(unlocked yes)
			(layer "F.Fab")
			(hide yes)
			(effects
				(font
					(size 1.016 1.016)
					(thickness 0.1524)
				)
			)
		)
		(property "Device Type" "VIA-PCIE-4P-427097"
			(at -3.4036 -1.9812 0)
			(unlocked yes)
			(layer "F.Fab")
			(hide yes)
			(effects
				(font
					(size 1.016 1.016)
					(thickness 0.1524)
				)
			)
		)
		(duplicate_pad_numbers_are_jumpers no)
		(fp_rect
			(start -2.1336 0.4826)
			(end 2.1336 -0.4826)
			(stroke
				(width 0)
				(type default)
			)
			(fill no)
			(layer "F.CrtYd")
		)
		(fp_rect
			(start -2.1336 0.4826)
			(end 2.1336 -0.4826)
			(stroke
				(width 0)
				(type default)
			)
			(fill no)
			(layer "F.Fab")
		)
		(pad "1" thru_hole circle
			(at -1.651 0)
			(size 0.508 0.508)
			(drill 0.254)
			(layers "*.Cu" "*.Mask")
			(remove_unused_layers no)
			(net "GND")
			(clearance 0.2286)
			(thermal_gap 0.2286)
		)
		(pad "2" thru_hole circle
			(at -0.635 0)
			(size 0.508 0.508)
			(drill 0.254)
			(layers "*.Cu" "*.Mask")
			(remove_unused_layers no)
			(net "PHY_DRV_B_TO_SCC_B_23_DP")
			(clearance 0.2286)
			(thermal_gap 0.2286)
		)
		(pad "3" thru_hole circle
			(at 0.635 0)
			(size 0.508 0.508)
			(drill 0.254)
			(layers "*.Cu" "*.Mask")
			(remove_unused_layers no)
			(net "PHY_DRV_B_TO_SCC_B_23_DN")
			(clearance 0.2286)
			(thermal_gap 0.2286)
		)
		(pad "4" thru_hole circle
			(at 1.651 0)
			(size 0.508 0.508)
			(drill 0.254)
			(layers "*.Cu" "*.Mask")
			(remove_unused_layers no)
			(net "GND")
			(clearance 0.2286)
			(thermal_gap 0.2286)
		)
	)
	(footprint ""
		(layer "F.Cu")
		(at 280.444448 -352.367342 -90)
		(property "Reference" "R1077"
			(at 0 0 270)
			(layer "F.SilkS")
			(hide yes)
			(effects
				(font
					(size 1.27 1.27)
				)
			)
		)
		(property "Value" "0R2J-2-GP"
			(at 0.064008 -3.993896 270)
			(unlocked yes)
			(layer "F.Fab")
			(hide yes)
			(effects
				(font
					(size 1.016 1.016)
					(thickness 0.1524)
				)
			)
		)
		(property "Device Type" "R402H16"
			(at 0.064008 -5.517896 270)
			(unlocked yes)
			(layer "F.Fab")
			(hide yes)
			(effects
				(font
					(size 1.016 1.016)
					(thickness 0.1524)
				)
			)
		)
		(duplicate_pad_numbers_are_jumpers no)
		(fp_line
			(start -0.508 -0.9398)
			(end -0.508 0.9398)
			(stroke
				(width 0.1524)
				(type default)
			)
			(layer "F.SilkS")
		)
		(fp_line
			(start 0.508 -0.9398)
			(end -0.508 -0.9398)
			(stroke
				(width 0.1524)
				(type default)
			)
			(layer "F.SilkS")
		)
		(fp_rect
			(start -0.508 0.9398)
			(end 0.508 -0.9398)
			(stroke
				(width 0)
				(type default)
			)
			(fill no)
			(layer "F.CrtYd")
		)
		(fp_rect
			(start -0.508 0.9398)
			(end 0.508 -0.9398)
			(stroke
				(width 0)
				(type default)
			)
			(fill no)
			(layer "F.Fab")
		)
		(pad "1" smd custom
			(at 0 -0.4445 270)
			(size 0.1397 0.1397)
			(layers "F.Cu" "F.Mask" "F.Paste")
			(net "MAX31790_B_PWM_ST0")
			(options
				(clearance outline)
				(anchor circle)
			)
			(primitives
				(gr_poly
					(pts
						(arc
							(start -0.1778 -0.2794)
							(mid -0.249642 -0.249642)
							(end -0.2794 -0.1778)
						)
						(arc
							(start -0.2794 0.1778)
							(mid -0.249642 0.249642)
							(end -0.1778 0.2794)
						)
						(arc
							(start 0.1778 0.2794)
							(mid 0.249642 0.249642)
							(end 0.2794 0.1778)
						)
						(arc
							(start 0.2794 -0.1778)
							(mid 0.249642 -0.249642)
							(end 0.1778 -0.2794)
						)
					)
					(width 0)
					(fill yes)
				)
			)
		)
		(pad "2" smd custom
			(at 0 0.4445 270)
			(size 0.1397 0.1397)
			(layers "F.Cu" "F.Mask" "F.Paste")
			(net "GND")
			(options
				(clearance outline)
				(anchor circle)
			)
			(primitives
				(gr_poly
					(pts
						(arc
							(start -0.1778 -0.2794)
							(mid -0.249642 -0.249642)
							(end -0.2794 -0.1778)
						)
						(arc
							(start -0.2794 0.1778)
							(mid -0.249642 0.249642)
							(end -0.1778 0.2794)
						)
						(arc
							(start 0.1778 0.2794)
							(mid 0.249642 0.249642)
							(end 0.2794 0.1778)
						)
						(arc
							(start 0.2794 -0.1778)
							(mid 0.249642 -0.249642)
							(end 0.1778 -0.2794)
						)
					)
					(width 0)
					(fill yes)
				)
			)
		)
	)
	(footprint ""
		(layer "F.Cu")
		(at 363.855 -151.892 180)
		(property "Reference" "C278"
			(at 0 0 180)
			(layer "F.SilkS")
			(hide yes)
			(effects
				(font
					(size 1.27 1.27)
				)
			)
		)
		(property "Value" "SC10U16V6KX-2GP"
			(at -0.0762 -5.1308 180)
			(unlocked yes)
			(layer "F.Fab")
			(hide yes)
			(effects
				(font
					(size 1.016 1.016)
					(thickness 0.1524)
				)
			)
		)
		(property "Device Type" "C1206H71"
			(at -0.127 -6.6548 180)
			(unlocked yes)
			(layer "F.Fab")
			(hide yes)
			(effects
				(font
					(size 1.016 1.016)
					(thickness 0.1524)
				)
			)
		)
		(duplicate_pad_numbers_are_jumpers no)
		(fp_line
			(start 1.016 2.2352)
			(end -1.016 2.2352)
			(stroke
				(width 0.1524)
				(type default)
			)
			(layer "F.SilkS")
		)
		(fp_line
			(start 1.016 0.8382)
			(end 1.016 2.2352)
			(stroke
				(width 0.1524)
				(type default)
			)
			(layer "F.SilkS")
		)
		(fp_line
			(start 1.016 -2.2352)
			(end 1.016 -0.8382)
			(stroke
				(width 0.1524)
				(type default)
			)
			(layer "F.SilkS")
		)
		(fp_line
			(start -1.016 2.2352)
			(end -1.016 0.8382)
			(stroke
				(width 0.1524)
				(type default)
			)
			(layer "F.SilkS")
		)
		(fp_line
			(start -1.016 -0.8382)
			(end -1.016 -2.2352)
			(stroke
				(width 0.1524)
				(type default)
			)
			(layer "F.SilkS")
		)
		(fp_line
			(start -1.016 -2.2352)
			(end 1.016 -2.2352)
			(stroke
				(width 0.1524)
				(type default)
			)
			(layer "F.SilkS")
		)
		(fp_rect
			(start -1.0922 2.3114)
			(end 1.0922 -2.3114)
			(stroke
				(width 0)
				(type default)
			)
			(fill no)
			(layer "F.CrtYd")
		)
		(fp_poly
			(pts
				(xy 1.0922 -2.3114) (xy 1.0922 2.3114) (xy -1.0922 2.3114) (xy -1.0922 -2.3114)
			)
			(stroke
				(width 0)
				(type default)
			)
			(fill no)
			(layer "F.Fab")
		)
		(pad "1" smd rect
			(at 0 -1.397 180)
			(size 1.651 1.27)
			(layers "F.Cu" "F.Mask" "F.Paste")
			(net "P5V_HDD19")
		)
		(pad "2" smd rect
			(at 0 1.397 180)
			(size 1.651 1.27)
			(layers "F.Cu" "F.Mask" "F.Paste")
			(net "GND")
		)
	)
	(footprint ""
		(layer "F.Cu")
		(at 59.749944 -143.91005 -90)
		(property "Reference" "HDDSAS13"
			(at 0 0 270)
			(layer "F.SilkS")
			(hide yes)
			(effects
				(font
					(size 1.27 1.27)
				)
			)
		)
		(property "Value" "SKT-SAS15P-14P-45-GP"
			(at -20.7645 -8.9789 270)
			(unlocked yes)
			(layer "F.Fab")
			(hide yes)
			(effects
				(font
					(size 1.016 1.016)
					(thickness 0.1524)
				)
			)
		)
		(property "Device Type" "10120818-001C-TRLF"
			(at -20.7645 -10.5029 270)
			(unlocked yes)
			(layer "F.Fab")
			(hide yes)
			(effects
				(font
					(size 1.016 1.016)
					(thickness 0.1524)
				)
			)
		)
		(duplicate_pad_numbers_are_jumpers no)
		(fp_line
			(start 1.651 4.2926)
			(end 1.651 3.0099)
			(stroke
				(width 0.1524)
				(type default)
			)
			(layer "F.SilkS")
		)
		(fp_line
			(start 8.509 4.2926)
			(end 1.651 4.2926)
			(stroke
				(width 0.1524)
				(type default)
			)
			(layer "F.SilkS")
		)
		(fp_line
			(start -23.4188 3.0099)
			(end -23.4188 -3.2512)
			(stroke
				(width 0.1524)
				(type default)
			)
			(layer "F.SilkS")
		)
		(fp_line
			(start 1.651 3.0099)
			(end -23.4188 3.0099)
			(stroke
				(width 0.1524)
				(type default)
			)
			(layer "F.SilkS")
		)
		(fp_line
			(start 8.509 3.0099)
			(end 8.509 4.2926)
			(stroke
				(width 0.1524)
				(type default)
			)
			(layer "F.SilkS")
		)
		(fp_line
			(start 23.4188 3.0099)
			(end 8.509 3.0099)
			(stroke
				(width 0.1524)
				(type default)
			)
			(layer "F.SilkS")
		)
		(fp_line
			(start -23.4188 -3.2512)
			(end 23.4188 -3.2512)
			(stroke
				(width 0.1524)
				(type default)
			)
			(layer "F.SilkS")
		)
		(fp_line
			(start 23.4188 -3.2512)
			(end 23.4188 3.0099)
			(stroke
				(width 0.1524)
				(type default)
			)
			(layer "F.SilkS")
		)
		(fp_line
			(start 15.5067 -3.3401)
			(end 16.2687 -3.3401)
			(stroke
				(width 0.3302)
				(type default)
			)
			(layer "F.SilkS")
		)
		(fp_poly
			(pts
				(xy 15.868904 -3.230372) (xy 16.503904 -3.865372) (xy 15.233904 -3.865372)
			)
			(stroke
				(width 0)
				(type default)
			)
			(fill yes)
			(layer "F.SilkS")
		)
		(fp_poly
			(pts
				(xy -22.8727 -2.7559) (xy 22.8727 -2.7559) (xy 22.8727 2.7559) (xy 8.255 2.7559) (xy 8.255 3.5179)
				(xy 1.905 3.5179) (xy 1.905 2.7559) (xy -22.8727 2.7559)
			)
			(stroke
				(width 0)
				(type default)
			)
			(fill no)
			(layer "F.CrtYd")
		)
		(fp_poly
			(pts
				(xy 1.397 4.5466) (xy 1.397 3.2639) (xy -23.6728 3.2639) (xy -23.6728 -3.5052) (xy 23.6728 -3.5052)
				(xy 23.6728 -0.00635) (xy 22.8727 -0.00635) (xy 22.8727 -2.7559) (xy -22.8727 -2.7559) (xy -22.8727 2.7559)
				(xy 1.905 2.7559) (xy 1.905 3.5179) (xy 8.255 3.5179) (xy 8.255 2.7559) (xy 22.8727 2.7559) (xy 22.8727 0.00635)
				(xy 23.6728 0.00635) (xy 23.6728 3.2639) (xy 8.763 3.2639) (xy 8.763 4.5466)
			)
			(stroke
				(width 0)
				(type default)
			)
			(fill no)
			(layer "F.CrtYd")
		)
		(fp_poly
			(pts
				(xy 1.397 4.5466) (xy 1.397 3.2639) (xy -23.6728 3.2639) (xy -23.6728 -3.5052) (xy 23.6728 -3.5052)
				(xy 23.6728 3.2639) (xy 8.763 3.2639) (xy 8.763 4.5466)
			)
			(stroke
				(width 0)
				(type default)
			)
			(fill no)
			(layer "F.Fab")
		)
		(pad "" np_thru_hole circle
			(at -18.874994 0 270)
			(size 0.254 0.254)
			(drill 1.3462)
			(layers "*.Cu" "*.Mask")
			(clearance 0.9017)
			(thermal_gap 0.9017)
		)
		(pad "" np_thru_hole circle
			(at 18.874994 0 270)
			(size 0.254 0.254)
			(drill 0.9398)
			(layers "*.Cu" "*.Mask")
			(clearance 0.6985)
			(thermal_gap 0.6985)
		)
		(pad "G1" smd rect
			(at 21.874988 0 270)
			(size 2.5908 2.5908)
			(layers "F.Cu" "F.Mask" "F.Paste")
			(net "GND")
		)
		(pad "G2" smd rect
			(at -21.874988 0 270)
			(size 2.5908 2.5908)
			(layers "F.Cu" "F.Mask" "F.Paste")
			(net "GND")
		)
		(pad "P1" smd rect
			(at 1.905 -1.82499 270)
			(size 0.6096 2.3622)
			(layers "F.Cu" "F.Mask" "F.Paste")
			(net "Net_1739")
		)
		(pad "P2" smd rect
			(at 0.635 -1.82499 270)
			(size 0.6096 2.3622)
			(layers "F.Cu" "F.Mask" "F.Paste")
			(net "Net_1740")
		)
		(pad "P3" smd rect
			(at -0.635 -1.82499 270)
			(size 0.6096 2.3622)
			(layers "F.Cu" "F.Mask" "F.Paste")
			(net "Net_1741")
		)
		(pad "P4" smd rect
			(at -1.905 -1.82499 270)
			(size 0.6096 2.3622)
			(layers "F.Cu" "F.Mask" "F.Paste")
			(net "GND")
		)
		(pad "P5" smd rect
			(at -3.175 -1.82499 270)
			(size 0.6096 2.3622)
			(layers "F.Cu" "F.Mask" "F.Paste")
			(net "HDD_PRSNT_13")
		)
		(pad "P6" smd rect
			(at -4.445 -1.82499 270)
			(size 0.6096 2.3622)
			(layers "F.Cu" "F.Mask" "F.Paste")
			(net "GND")
		)
		(pad "P7" smd rect
			(at -5.715 -1.82499 270)
			(size 0.6096 2.3622)
			(layers "F.Cu" "F.Mask" "F.Paste")
			(net "5V_PRE_13")
		)
		(pad "P8" smd rect
			(at -6.985 -1.82499 270)
			(size 0.6096 2.3622)
			(layers "F.Cu" "F.Mask" "F.Paste")
			(net "P5V_HDD13")
		)
		(pad "P9" smd rect
			(at -8.255 -1.82499 270)
			(size 0.6096 2.3622)
			(layers "F.Cu" "F.Mask" "F.Paste")
			(net "P5V_HDD13")
		)
		(pad "P10" smd rect
			(at -9.525 -1.82499 270)
			(size 0.6096 2.3622)
			(layers "F.Cu" "F.Mask" "F.Paste")
			(net "GND")
		)
		(pad "P11" smd rect
			(at -10.795 -1.82499 270)
			(size 0.6096 2.3622)
			(layers "F.Cu" "F.Mask" "F.Paste")
			(net "ACT_HDD_13")
		)
		(pad "P12" smd rect
			(at -12.065 -1.82499 270)
			(size 0.6096 2.3622)
			(layers "F.Cu" "F.Mask" "F.Paste")
			(net "GND")
		)
		(pad "P13" smd rect
			(at -13.335 -1.82499 270)
			(size 0.6096 2.3622)
			(layers "F.Cu" "F.Mask" "F.Paste")
			(net "12V_PRE_13")
		)
		(pad "P14" smd rect
			(at -14.605 -1.82499 270)
			(size 0.6096 2.3622)
			(layers "F.Cu" "F.Mask" "F.Paste")
			(net "P12V_HDD13")
		)
		(pad "P15" smd rect
			(at -15.875 -1.82499 270)
			(size 0.6096 2.3622)
			(layers "F.Cu" "F.Mask" "F.Paste")
			(net "P12V_HDD13")
		)
		(pad "S1" smd rect
			(at 15.875 -1.82499 270)
			(size 0.6096 2.3622)
			(layers "F.Cu" "F.Mask" "F.Paste")
			(net "GND")
		)
		(pad "S2" smd rect
			(at 14.605 -1.82499 270)
			(size 0.6096 2.3622)
			(layers "F.Cu" "F.Mask" "F.Paste")
			(net "SAS_HDD_RX_P13")
		)
		(pad "S3" smd rect
			(at 13.335 -1.82499 270)
			(size 0.6096 2.3622)
			(layers "F.Cu" "F.Mask" "F.Paste")
			(net "SAS_HDD_RX_N13")
		)
		(pad "S4" smd rect
			(at 12.065 -1.82499 270)
			(size 0.6096 2.3622)
			(layers "F.Cu" "F.Mask" "F.Paste")
			(net "GND")
		)
		(pad "S5" smd rect
			(at 10.795 -1.82499 270)
			(size 0.6096 2.3622)
			(layers "F.Cu" "F.Mask" "F.Paste")
			(net "PHY_DRV_B_TO_SCC_B_13_DN")
		)
		(pad "S6" smd rect
			(at 9.525 -1.82499 270)
			(size 0.6096 2.3622)
			(layers "F.Cu" "F.Mask" "F.Paste")
			(net "PHY_DRV_B_TO_SCC_B_13_DP")
		)
		(pad "S7" smd rect
			(at 8.255 -1.82499 270)
			(size 0.6096 2.3622)
			(layers "F.Cu" "F.Mask" "F.Paste")
			(net "GND")
		)
		(pad "S8" smd rect
			(at 7.480046 2.845054 270)
			(size 0.508 2.3622)
			(layers "F.Cu" "F.Mask" "F.Paste")
			(net "GND")
		)
		(pad "S9" smd rect
			(at 6.679946 2.845054 270)
			(size 0.508 2.3622)
			(layers "F.Cu" "F.Mask" "F.Paste")
			(net "Net_436")
		)
		(pad "S10" smd rect
			(at 5.8801 2.845054 270)
			(size 0.508 2.3622)
			(layers "F.Cu" "F.Mask" "F.Paste")
			(net "Net_328")
		)
		(pad "S11" smd rect
			(at 5.08 2.845054 270)
			(size 0.508 2.3622)
			(layers "F.Cu" "F.Mask" "F.Paste")
			(net "GND")
		)
		(pad "S12" smd rect
			(at 4.2799 2.845054 270)
			(size 0.508 2.3622)
			(layers "F.Cu" "F.Mask" "F.Paste")
			(net "Net_364")
		)
		(pad "S13" smd rect
			(at 3.480054 2.845054 270)
			(size 0.508 2.3622)
			(layers "F.Cu" "F.Mask" "F.Paste")
			(net "Net_400")
		)
		(pad "S14" smd rect
			(at 2.679954 2.845054 270)
			(size 0.508 2.3622)
			(layers "F.Cu" "F.Mask" "F.Paste")
			(net "GND")
		)
		(zone
			(layer "F.Cu")
			(hatch none 0.5)
			(connect_pads
				(clearance 0)
			)
			(min_thickness 0.25)
			(keepout
				(tracks not_allowed)
				(vias allowed)
				(pads allowed)
				(copperpour not_allowed)
				(footprints allowed)
			)
			(placement
				(enabled no)
				(sheetname "")
			)
			(fill
				(thermal_gap 0.5)
				(thermal_bridge_width 0.5)
				(island_removal_mode 0)
			)
			(polygon
				(pts
					(xy 63.407544 -160.64865) (xy 56.333644 -160.64865) (xy 56.333644 -167.58285) (xy 57.438544 -167.58285)
					(xy 57.438544 -163.46805) (xy 62.061344 -163.46805) (xy 62.061344 -167.58285) (xy 63.407544 -167.58285)
				)
			)
		)
		(zone
			(layer "F.Cu")
			(hatch none 0.5)
			(connect_pads
				(clearance 0)
			)
			(min_thickness 0.25)
			(keepout
				(tracks allowed)
				(vias not_allowed)
				(pads allowed)
				(copperpour not_allowed)
				(footprints allowed)
			)
			(placement
				(enabled no)
				(sheetname "")
			)
			(fill
				(thermal_gap 0.5)
				(thermal_bridge_width 0.5)
				(island_removal_mode 0)
			)
			(polygon
				(pts
					(xy 63.407544 -160.64865) (xy 56.333644 -160.64865) (xy 56.333644 -167.58285) (xy 57.438544 -167.58285)
					(xy 57.438544 -163.46805) (xy 62.061344 -163.46805) (xy 62.061344 -167.58285) (xy 63.407544 -167.58285)
				)
			)
		)
		(zone
			(layer "F.Cu")
			(hatch none 0.5)
			(connect_pads
				(clearance 0)
			)
			(min_thickness 0.25)
			(keepout
				(tracks allowed)
				(vias not_allowed)
				(pads allowed)
				(copperpour not_allowed)
				(footprints allowed)
			)
			(placement
				(enabled no)
				(sheetname "")
			)
			(fill
				(thermal_gap 0.5)
				(thermal_bridge_width 0.5)
				(island_removal_mode 0)
			)
			(polygon
				(pts
					(xy 63.407544 -127.17145) (xy 56.333644 -127.17145) (xy 56.333644 -120.23725) (xy 57.438544 -120.23725)
					(xy 57.438544 -124.35205) (xy 62.061344 -124.35205) (xy 62.061344 -120.23725) (xy 63.407544 -120.23725)
				)
			)
		)
		(zone
			(layer "F.Cu")
			(hatch none 0.5)
			(connect_pads
				(clearance 0)
			)
			(min_thickness 0.25)
			(keepout
				(tracks not_allowed)
				(vias allowed)
				(pads allowed)
				(copperpour not_allowed)
				(footprints allowed)
			)
			(placement
				(enabled no)
				(sheetname "")
			)
			(fill
				(thermal_gap 0.5)
				(thermal_bridge_width 0.5)
				(island_removal_mode 0)
			)
			(polygon
				(pts
					(xy 63.407544 -127.17145) (xy 56.333644 -127.17145) (xy 56.333644 -120.23725) (xy 57.438544 -120.23725)
					(xy 57.438544 -124.35205) (xy 62.061344 -124.35205) (xy 62.061344 -120.23725) (xy 63.407544 -120.23725)
				)
			)
		)
		(zone
			(layers "F.Cu" "B.Cu" "In1.Cu" "In2.Cu" "In3.Cu" "In4.Cu" "In5.Cu" "In6.Cu")
			(hatch none 0.5)
			(connect_pads
				(clearance 0)
			)
			(min_thickness 0.25)
			(keepout
				(tracks not_allowed)
				(vias allowed)
				(pads allowed)
				(copperpour not_allowed)
				(footprints allowed)
			)
			(placement
				(enabled no)
				(sheetname "")
			)
			(fill
				(thermal_gap 0.5)
				(thermal_bridge_width 0.5)
				(island_removal_mode 0)
			)
			(polygon
				(pts
					(arc
						(start 60.524644 -125.035056)
						(mid 58.975244 -125.035056)
						(end 60.524644 -125.035056)
					)
				)
			)
		)
		(zone
			(layers "F.Cu" "B.Cu" "In1.Cu" "In2.Cu" "In3.Cu" "In4.Cu" "In5.Cu" "In6.Cu")
			(hatch none 0.5)
			(connect_pads
				(clearance 0)
			)
			(min_thickness 0.25)
			(keepout
				(tracks not_allowed)
				(vias allowed)
				(pads allowed)
				(copperpour not_allowed)
				(footprints allowed)
			)
			(placement
				(enabled no)
				(sheetname "")
			)
			(fill
				(thermal_gap 0.5)
				(thermal_bridge_width 0.5)
				(island_removal_mode 0)
			)
			(polygon
				(pts
					(arc
						(start 60.727844 -162.785044)
						(mid 58.772044 -162.785044)
						(end 60.727844 -162.785044)
					)
				)
			)
		)
	)
	(footprint ""
		(layer "F.Cu")
		(at 473.583 -214.249)
		(property "Reference" "R380"
			(at 0 0 0)
			(layer "F.SilkS")
			(hide yes)
			(effects
				(font
					(size 1.27 1.27)
				)
			)
		)
		(property "Value" "91R3F-1-GP"
			(at -0.0254 -2.5146 0)
			(unlocked yes)
			(layer "F.Fab")
			(hide yes)
			(effects
				(font
					(size 1.016 1.016)
					(thickness 0.1524)
				)
			)
		)
		(property "Device Type" "R603H22"
			(at -0.0254 -4.0386 0)
			(unlocked yes)
			(layer "F.Fab")
			(hide yes)
			(effects
				(font
					(size 1.016 1.016)
					(thickness 0.1524)
				)
			)
		)
		(duplicate_pad_numbers_are_jumpers no)
		(fp_line
			(start -0.4826 0)
			(end -0.2032 0)
			(stroke
				(width 0.2032)
				(type default)
			)
			(layer "F.SilkS")
		)
		(fp_line
			(start 0.2032 0)
			(end 0.4826 0)
			(stroke
				(width 0.2032)
				(type default)
			)
			(layer "F.SilkS")
		)
		(fp_rect
			(start -0.5842 1.3335)
			(end 0.5842 -1.3335)
			(stroke
				(width 0)
				(type default)
			)
			(fill no)
			(layer "F.CrtYd")
		)
		(fp_rect
			(start -0.5842 1.3335)
			(end 0.5842 -1.3335)
			(stroke
				(width 0)
				(type default)
			)
			(fill no)
			(layer "F.Fab")
		)
		(pad "1" smd custom
			(at 0 -0.762)
			(size 0.2159 0.2159)
			(layers "F.Cu" "F.Mask" "F.Paste")
			(net "P5V_B_3")
			(options
				(clearance outline)
				(anchor circle)
			)
			(primitives
				(gr_poly
					(pts
						(arc
							(start -0.3302 -0.4318)
							(mid -0.402042 -0.402042)
							(end -0.4318 -0.3302)
						)
						(arc
							(start -0.4318 0.3302)
							(mid -0.402042 0.402042)
							(end -0.3302 0.4318)
						)
						(arc
							(start 0.3302 0.4318)
							(mid 0.402042 0.402042)
							(end 0.4318 0.3302)
						)
						(arc
							(start 0.4318 -0.3302)
							(mid 0.402042 -0.402042)
							(end 0.3302 -0.4318)
						)
					)
					(width 0)
					(fill yes)
				)
			)
		)
		(pad "2" smd custom
			(at 0 0.762)
			(size 0.2159 0.2159)
			(layers "F.Cu" "F.Mask" "F.Paste")
			(net "DRV_ACT_11")
			(options
				(clearance outline)
				(anchor circle)
			)
			(primitives
				(gr_poly
					(pts
						(arc
							(start -0.3302 -0.4318)
							(mid -0.402042 -0.402042)
							(end -0.4318 -0.3302)
						)
						(arc
							(start -0.4318 0.3302)
							(mid -0.402042 0.402042)
							(end -0.3302 0.4318)
						)
						(arc
							(start 0.3302 0.4318)
							(mid 0.402042 0.402042)
							(end 0.4318 0.3302)
						)
						(arc
							(start 0.4318 -0.3302)
							(mid 0.402042 -0.402042)
							(end 0.3302 -0.4318)
						)
					)
					(width 0)
					(fill yes)
				)
			)
		)
	)
	(footprint ""
		(layer "F.Cu")
		(at 180.975 -19.177)
		(property "Reference" "R745"
			(at 0 0 0)
			(layer "F.SilkS")
			(hide yes)
			(effects
				(font
					(size 1.27 1.27)
				)
			)
		)
		(property "Value" "1KR2F-3-GP"
			(at 0.064008 -3.993896 0)
			(unlocked yes)
			(layer "F.Fab")
			(hide yes)
			(effects
				(font
					(size 1.016 1.016)
					(thickness 0.1524)
				)
			)
		)
		(property "Device Type" "R402H16"
			(at 0.064008 -5.517896 0)
			(unlocked yes)
			(layer "F.Fab")
			(hide yes)
			(effects
				(font
					(size 1.016 1.016)
					(thickness 0.1524)
				)
			)
		)
		(duplicate_pad_numbers_are_jumpers no)
		(fp_line
			(start -0.508 -0.9398)
			(end -0.508 0.9398)
			(stroke
				(width 0.1524)
				(type default)
			)
			(layer "F.SilkS")
		)
		(fp_line
			(start 0.508 -0.9398)
			(end -0.508 -0.9398)
			(stroke
				(width 0.1524)
				(type default)
			)
			(layer "F.SilkS")
		)
		(fp_rect
			(start -0.508 0.9398)
			(end 0.508 -0.9398)
			(stroke
				(width 0)
				(type default)
			)
			(fill no)
			(layer "F.CrtYd")
		)
		(fp_rect
			(start -0.508 0.9398)
			(end 0.508 -0.9398)
			(stroke
				(width 0)
				(type default)
			)
			(fill no)
			(layer "F.Fab")
		)
		(pad "1" smd custom
			(at 0 -0.4445)
			(size 0.1397 0.1397)
			(layers "F.Cu" "F.Mask" "F.Paste")
			(net "P3V3_STBY_B")
			(options
				(clearance outline)
				(anchor circle)
			)
			(primitives
				(gr_poly
					(pts
						(arc
							(start -0.1778 -0.2794)
							(mid -0.249642 -0.249642)
							(end -0.2794 -0.1778)
						)
						(arc
							(start -0.2794 0.1778)
							(mid -0.249642 0.249642)
							(end -0.1778 0.2794)
						)
						(arc
							(start 0.1778 0.2794)
							(mid 0.249642 0.249642)
							(end 0.2794 0.1778)
						)
						(arc
							(start 0.2794 -0.1778)
							(mid 0.249642 -0.249642)
							(end 0.1778 -0.2794)
						)
					)
					(width 0)
					(fill yes)
				)
			)
		)
		(pad "2" smd custom
			(at 0 0.4445)
			(size 0.1397 0.1397)
			(layers "F.Cu" "F.Mask" "F.Paste")
			(net "SW_PWR_R_HDD29")
			(options
				(clearance outline)
				(anchor circle)
			)
			(primitives
				(gr_poly
					(pts
						(arc
							(start -0.1778 -0.2794)
							(mid -0.249642 -0.249642)
							(end -0.2794 -0.1778)
						)
						(arc
							(start -0.2794 0.1778)
							(mid -0.249642 0.249642)
							(end -0.1778 0.2794)
						)
						(arc
							(start 0.1778 0.2794)
							(mid 0.249642 0.249642)
							(end 0.2794 0.1778)
						)
						(arc
							(start 0.2794 -0.1778)
							(mid 0.249642 -0.249642)
							(end 0.1778 -0.2794)
						)
					)
					(width 0)
					(fill yes)
				)
			)
		)
	)
	(footprint ""
		(layer "F.Cu")
		(at 179.7812 -130.8608 180)
		(property "Reference" "R471"
			(at 0 0 180)
			(layer "F.SilkS")
			(hide yes)
			(effects
				(font
					(size 1.27 1.27)
				)
			)
		)
		(property "Value" "0R2J-2-GP"
			(at 0.064008 -3.993896 180)
			(unlocked yes)
			(layer "F.Fab")
			(hide yes)
			(effects
				(font
					(size 1.016 1.016)
					(thickness 0.1524)
				)
			)
		)
		(property "Device Type" "R402H16"
			(at 0.064008 -5.517896 180)
			(unlocked yes)
			(layer "F.Fab")
			(hide yes)
			(effects
				(font
					(size 1.016 1.016)
					(thickness 0.1524)
				)
			)
		)
		(duplicate_pad_numbers_are_jumpers no)
		(fp_line
			(start 0.508 -0.9398)
			(end -0.508 -0.9398)
			(stroke
				(width 0.1524)
				(type default)
			)
			(layer "F.SilkS")
		)
		(fp_line
			(start -0.508 -0.9398)
			(end -0.508 0.9398)
			(stroke
				(width 0.1524)
				(type default)
			)
			(layer "F.SilkS")
		)
		(fp_rect
			(start -0.508 0.9398)
			(end 0.508 -0.9398)
			(stroke
				(width 0)
				(type default)
			)
			(fill no)
			(layer "F.CrtYd")
		)
		(fp_rect
			(start -0.508 0.9398)
			(end 0.508 -0.9398)
			(stroke
				(width 0)
				(type default)
			)
			(fill no)
			(layer "F.Fab")
		)
		(pad "1" smd custom
			(at 0 -0.4445 180)
			(size 0.1397 0.1397)
			(layers "F.Cu" "F.Mask" "F.Paste")
			(net "DRIVE_B_17_PWR")
			(options
				(clearance outline)
				(anchor circle)
			)
			(primitives
				(gr_poly
					(pts
						(arc
							(start -0.1778 -0.2794)
							(mid -0.249642 -0.249642)
							(end -0.2794 -0.1778)
						)
						(arc
							(start -0.2794 0.1778)
							(mid -0.249642 0.249642)
							(end -0.1778 0.2794)
						)
						(arc
							(start 0.1778 0.2794)
							(mid 0.249642 0.249642)
							(end 0.2794 0.1778)
						)
						(arc
							(start 0.2794 -0.1778)
							(mid 0.249642 -0.249642)
							(end 0.1778 -0.2794)
						)
					)
					(width 0)
					(fill yes)
				)
			)
		)
		(pad "2" smd custom
			(at 0 0.4445 180)
			(size 0.1397 0.1397)
			(layers "F.Cu" "F.Mask" "F.Paste")
			(net "SW_PWR_R_HDD17")
			(options
				(clearance outline)
				(anchor circle)
			)
			(primitives
				(gr_poly
					(pts
						(arc
							(start -0.1778 -0.2794)
							(mid -0.249642 -0.249642)
							(end -0.2794 -0.1778)
						)
						(arc
							(start -0.2794 0.1778)
							(mid -0.249642 0.249642)
							(end -0.1778 0.2794)
						)
						(arc
							(start 0.1778 0.2794)
							(mid 0.249642 0.249642)
							(end 0.2794 0.1778)
						)
						(arc
							(start 0.2794 -0.1778)
							(mid 0.249642 -0.249642)
							(end 0.1778 -0.2794)
						)
					)
					(width 0)
					(fill yes)
				)
			)
		)
	)
	(footprint ""
		(layer "F.Cu")
		(at 471.805 -139.065 -90)
		(property "Reference" "C337"
			(at 0 0 270)
			(layer "F.SilkS")
			(hide yes)
			(effects
				(font
					(size 1.27 1.27)
				)
			)
		)
		(property "Value" "SCD033U25V2KX-GP"
			(at 1.1811 -2.7051 270)
			(unlocked yes)
			(layer "F.Fab")
			(hide yes)
			(effects
				(font
					(size 1.016 1.016)
					(thickness 0.1524)
				)
			)
		)
		(property "Device Type" "C402H22"
			(at 1.1811 -4.2291 270)
			(unlocked yes)
			(layer "F.Fab")
			(hide yes)
			(effects
				(font
					(size 1.016 1.016)
					(thickness 0.1524)
				)
			)
		)
		(duplicate_pad_numbers_are_jumpers no)
		(fp_rect
			(start -0.4318 0.9525)
			(end 0.4318 -0.9525)
			(stroke
				(width 0)
				(type default)
			)
			(fill no)
			(layer "F.CrtYd")
		)
		(fp_rect
			(start -0.4318 0.9525)
			(end 0.4318 -0.9525)
			(stroke
				(width 0)
				(type default)
			)
			(fill no)
			(layer "F.Fab")
		)
		(pad "1" smd custom
			(at 0 -0.4445 270)
			(size 0.1524 0.1524)
			(layers "F.Cu" "F.Mask" "F.Paste")
			(net "SW_HDD_P23")
			(options
				(clearance outline)
				(anchor circle)
			)
			(primitives
				(gr_poly
					(pts
						(arc
							(start 0.3048 -0.2032)
							(mid 0.275042 -0.275042)
							(end 0.2032 -0.3048)
						)
						(arc
							(start -0.2032 -0.3048)
							(mid -0.275042 -0.275042)
							(end -0.3048 -0.2032)
						)
						(arc
							(start -0.3048 0.2032)
							(mid -0.275042 0.275042)
							(end -0.2032 0.3048)
						)
						(arc
							(start 0.2032 0.3048)
							(mid 0.275042 0.275042)
							(end 0.3048 0.2032)
						)
					)
					(width 0)
					(fill yes)
				)
			)
		)
		(pad "2" smd custom
			(at 0 0.4445 270)
			(size 0.1524 0.1524)
			(layers "F.Cu" "F.Mask" "F.Paste")
			(net "GND")
			(options
				(clearance outline)
				(anchor circle)
			)
			(primitives
				(gr_poly
					(pts
						(arc
							(start 0.3048 -0.2032)
							(mid 0.275042 -0.275042)
							(end 0.2032 -0.3048)
						)
						(arc
							(start -0.2032 -0.3048)
							(mid -0.275042 -0.275042)
							(end -0.3048 -0.2032)
						)
						(arc
							(start -0.3048 0.2032)
							(mid -0.275042 0.275042)
							(end -0.2032 0.3048)
						)
						(arc
							(start 0.2032 0.3048)
							(mid 0.275042 0.275042)
							(end 0.3048 0.2032)
						)
					)
					(width 0)
					(fill yes)
				)
			)
		)
	)
	(footprint ""
		(layer "F.Cu")
		(at 27.437588 -229.5017 -90)
		(property "Reference" "R1102"
			(at 0 0 270)
			(layer "F.SilkS")
			(hide yes)
			(effects
				(font
					(size 1.27 1.27)
				)
			)
		)
		(property "Value" "10KR2F-2-GP"
			(at 0.064008 -3.993896 270)
			(unlocked yes)
			(layer "F.Fab")
			(hide yes)
			(effects
				(font
					(size 1.016 1.016)
					(thickness 0.1524)
				)
			)
		)
		(property "Device Type" "R402H16"
			(at 0.064008 -5.517896 270)
			(unlocked yes)
			(layer "F.Fab")
			(hide yes)
			(effects
				(font
					(size 1.016 1.016)
					(thickness 0.1524)
				)
			)
		)
		(duplicate_pad_numbers_are_jumpers no)
		(fp_line
			(start -0.508 -0.9398)
			(end -0.508 0.9398)
			(stroke
				(width 0.1524)
				(type default)
			)
			(layer "F.SilkS")
		)
		(fp_line
			(start 0.508 -0.9398)
			(end -0.508 -0.9398)
			(stroke
				(width 0.1524)
				(type default)
			)
			(layer "F.SilkS")
		)
		(fp_rect
			(start -0.508 0.9398)
			(end 0.508 -0.9398)
			(stroke
				(width 0)
				(type default)
			)
			(fill no)
			(layer "F.CrtYd")
		)
		(fp_rect
			(start -0.508 0.9398)
			(end 0.508 -0.9398)
			(stroke
				(width 0)
				(type default)
			)
			(fill no)
			(layer "F.Fab")
		)
		(pad "1" smd custom
			(at 0 -0.4445 270)
			(size 0.1397 0.1397)
			(layers "F.Cu" "F.Mask" "F.Paste")
			(net "P5V_B_1")
			(options
				(clearance outline)
				(anchor circle)
			)
			(primitives
				(gr_poly
					(pts
						(arc
							(start -0.1778 -0.2794)
							(mid -0.249642 -0.249642)
							(end -0.2794 -0.1778)
						)
						(arc
							(start -0.2794 0.1778)
							(mid -0.249642 0.249642)
							(end -0.1778 0.2794)
						)
						(arc
							(start 0.1778 0.2794)
							(mid 0.249642 0.249642)
							(end 0.2794 0.1778)
						)
						(arc
							(start 0.2794 -0.1778)
							(mid 0.249642 -0.249642)
							(end 0.1778 -0.2794)
						)
					)
					(width 0)
					(fill yes)
				)
			)
		)
		(pad "2" smd custom
			(at 0 0.4445 270)
			(size 0.1397 0.1397)
			(layers "F.Cu" "F.Mask" "F.Paste")
			(net "P5V_B_1_PGOOD")
			(options
				(clearance outline)
				(anchor circle)
			)
			(primitives
				(gr_poly
					(pts
						(arc
							(start -0.1778 -0.2794)
							(mid -0.249642 -0.249642)
							(end -0.2794 -0.1778)
						)
						(arc
							(start -0.2794 0.1778)
							(mid -0.249642 0.249642)
							(end -0.1778 0.2794)
						)
						(arc
							(start 0.1778 0.2794)
							(mid 0.249642 0.249642)
							(end 0.2794 0.1778)
						)
						(arc
							(start 0.2794 -0.1778)
							(mid 0.249642 -0.249642)
							(end 0.1778 -0.2794)
						)
					)
					(width 0)
					(fill yes)
				)
			)
		)
	)
	(footprint ""
		(layer "F.Cu")
		(at 273.5834 -328.28484 90)
		(property "Reference" "R92"
			(at 0 0 90)
			(layer "F.SilkS")
			(hide yes)
			(effects
				(font
					(size 1.27 1.27)
				)
			)
		)
		(property "Value" "4K7R2F-GP"
			(at 0.064008 -3.993896 90)
			(unlocked yes)
			(layer "F.Fab")
			(hide yes)
			(effects
				(font
					(size 1.016 1.016)
					(thickness 0.1524)
				)
			)
		)
		(property "Device Type" "R402H16"
			(at 0.064008 -5.517896 90)
			(unlocked yes)
			(layer "F.Fab")
			(hide yes)
			(effects
				(font
					(size 1.016 1.016)
					(thickness 0.1524)
				)
			)
		)
		(duplicate_pad_numbers_are_jumpers no)
		(fp_line
			(start 0.508 -0.9398)
			(end -0.508 -0.9398)
			(stroke
				(width 0.1524)
				(type default)
			)
			(layer "F.SilkS")
		)
		(fp_line
			(start -0.508 -0.9398)
			(end -0.508 0.9398)
			(stroke
				(width 0.1524)
				(type default)
			)
			(layer "F.SilkS")
		)
		(fp_rect
			(start -0.508 0.9398)
			(end 0.508 -0.9398)
			(stroke
				(width 0)
				(type default)
			)
			(fill no)
			(layer "F.CrtYd")
		)
		(fp_rect
			(start -0.508 0.9398)
			(end 0.508 -0.9398)
			(stroke
				(width 0)
				(type default)
			)
			(fill no)
			(layer "F.Fab")
		)
		(pad "1" smd custom
			(at 0 -0.4445 90)
			(size 0.1397 0.1397)
			(layers "F.Cu" "F.Mask" "F.Paste")
			(net "P3V3_IN")
			(options
				(clearance outline)
				(anchor circle)
			)
			(primitives
				(gr_poly
					(pts
						(arc
							(start -0.1778 -0.2794)
							(mid -0.249642 -0.249642)
							(end -0.2794 -0.1778)
						)
						(arc
							(start -0.2794 0.1778)
							(mid -0.249642 0.249642)
							(end -0.1778 0.2794)
						)
						(arc
							(start 0.1778 0.2794)
							(mid 0.249642 0.249642)
							(end 0.2794 0.1778)
						)
						(arc
							(start 0.2794 -0.1778)
							(mid 0.249642 -0.249642)
							(end 0.1778 -0.2794)
						)
					)
					(width 0)
					(fill yes)
				)
			)
		)
		(pad "2" smd custom
			(at 0 0.4445 90)
			(size 0.1397 0.1397)
			(layers "F.Cu" "F.Mask" "F.Paste")
			(net "PWM_OUT_FAN0")
			(options
				(clearance outline)
				(anchor circle)
			)
			(primitives
				(gr_poly
					(pts
						(arc
							(start -0.1778 -0.2794)
							(mid -0.249642 -0.249642)
							(end -0.2794 -0.1778)
						)
						(arc
							(start -0.2794 0.1778)
							(mid -0.249642 0.249642)
							(end -0.1778 0.2794)
						)
						(arc
							(start 0.1778 0.2794)
							(mid 0.249642 0.249642)
							(end 0.2794 0.1778)
						)
						(arc
							(start 0.2794 -0.1778)
							(mid 0.249642 -0.249642)
							(end 0.1778 -0.2794)
						)
					)
					(width 0)
					(fill yes)
				)
			)
		)
	)
	(footprint ""
		(layer "F.Cu")
		(at 184.277 -369.189 90)
		(property "Reference" "R994"
			(at 0 0 90)
			(layer "F.SilkS")
			(hide yes)
			(effects
				(font
					(size 1.27 1.27)
				)
			)
		)
		(property "Value" "1K4R2F-1-GP"
			(at 0.064008 -3.993896 90)
			(unlocked yes)
			(layer "F.Fab")
			(hide yes)
			(effects
				(font
					(size 1.016 1.016)
					(thickness 0.1524)
				)
			)
		)
		(property "Device Type" "R402H16"
			(at 0.064008 -5.517896 90)
			(unlocked yes)
			(layer "F.Fab")
			(hide yes)
			(effects
				(font
					(size 1.016 1.016)
					(thickness 0.1524)
				)
			)
		)
		(duplicate_pad_numbers_are_jumpers no)
		(fp_line
			(start 0.508 -0.9398)
			(end -0.508 -0.9398)
			(stroke
				(width 0.1524)
				(type default)
			)
			(layer "F.SilkS")
		)
		(fp_line
			(start -0.508 -0.9398)
			(end -0.508 0.9398)
			(stroke
				(width 0.1524)
				(type default)
			)
			(layer "F.SilkS")
		)
		(fp_rect
			(start -0.508 0.9398)
			(end 0.508 -0.9398)
			(stroke
				(width 0)
				(type default)
			)
			(fill no)
			(layer "F.CrtYd")
		)
		(fp_rect
			(start -0.508 0.9398)
			(end 0.508 -0.9398)
			(stroke
				(width 0)
				(type default)
			)
			(fill no)
			(layer "F.Fab")
		)
		(pad "1" smd custom
			(at 0 -0.4445 90)
			(size 0.1397 0.1397)
			(layers "F.Cu" "F.Mask" "F.Paste")
			(net "12V_HS_ENABLE")
			(options
				(clearance outline)
				(anchor circle)
			)
			(primitives
				(gr_poly
					(pts
						(arc
							(start -0.1778 -0.2794)
							(mid -0.249642 -0.249642)
							(end -0.2794 -0.1778)
						)
						(arc
							(start -0.2794 0.1778)
							(mid -0.249642 0.249642)
							(end -0.1778 0.2794)
						)
						(arc
							(start 0.1778 0.2794)
							(mid 0.249642 0.249642)
							(end 0.2794 0.1778)
						)
						(arc
							(start 0.2794 -0.1778)
							(mid 0.249642 -0.249642)
							(end 0.1778 -0.2794)
						)
					)
					(width 0)
					(fill yes)
				)
			)
		)
		(pad "2" smd custom
			(at 0 0.4445 90)
			(size 0.1397 0.1397)
			(layers "F.Cu" "F.Mask" "F.Paste")
			(net "GND")
			(options
				(clearance outline)
				(anchor circle)
			)
			(primitives
				(gr_poly
					(pts
						(arc
							(start -0.1778 -0.2794)
							(mid -0.249642 -0.249642)
							(end -0.2794 -0.1778)
						)
						(arc
							(start -0.2794 0.1778)
							(mid -0.249642 0.249642)
							(end -0.1778 0.2794)
						)
						(arc
							(start 0.1778 0.2794)
							(mid 0.249642 0.249642)
							(end 0.2794 0.1778)
						)
						(arc
							(start 0.2794 -0.1778)
							(mid 0.249642 -0.249642)
							(end 0.1778 -0.2794)
						)
					)
					(width 0)
					(fill yes)
				)
			)
		)
	)
	(footprint ""
		(layer "F.Cu")
		(at 401.4216 -33.909 90)
		(property "Reference" "Q168"
			(at 0 0 90)
			(layer "F.SilkS")
			(hide yes)
			(effects
				(font
					(size 1.27 1.27)
				)
			)
		)
		(property "Value" "AO4407AL-GP"
			(at -3.707384 -1.5367 90)
			(unlocked yes)
			(layer "F.Fab")
			(hide yes)
			(effects
				(font
					(size 1.016 1.016)
					(thickness 0.1524)
				)
			)
		)
		(property "Device Type" "SOIC8H69"
			(at -3.707384 -3.0607 90)
			(unlocked yes)
			(layer "F.Fab")
			(hide yes)
			(effects
				(font
					(size 1.016 1.016)
					(thickness 0.1524)
				)
			)
		)
		(duplicate_pad_numbers_are_jumpers no)
		(fp_line
			(start 2.1336 -1.4224)
			(end -2.7432 -1.4224)
			(stroke
				(width 0.1524)
				(type default)
			)
			(layer "F.SilkS")
		)
		(fp_line
			(start -2.7432 -1.4224)
			(end -2.7432 1.4224)
			(stroke
				(width 0.1524)
				(type default)
			)
			(layer "F.SilkS")
		)
		(fp_line
			(start -2.7178 -0.508)
			(end -2.1844 -0.0508)
			(stroke
				(width 0.1524)
				(type default)
			)
			(layer "F.SilkS")
		)
		(fp_line
			(start -2.1844 -0.0508)
			(end -2.7178 0.508)
			(stroke
				(width 0.1524)
				(type default)
			)
			(layer "F.SilkS")
		)
		(fp_line
			(start 2.1336 1.4224)
			(end 2.1336 -1.4224)
			(stroke
				(width 0.1524)
				(type default)
			)
			(layer "F.SilkS")
		)
		(fp_line
			(start -2.7432 1.4224)
			(end 2.1336 1.4224)
			(stroke
				(width 0.1524)
				(type default)
			)
			(layer "F.SilkS")
		)
		(fp_line
			(start -2.7432 1.4224)
			(end -2.6416 1.4224)
			(stroke
				(width 0.1524)
				(type default)
			)
			(layer "F.SilkS")
		)
		(fp_line
			(start -2.6289 3.4417)
			(end -2.6289 1.4732)
			(stroke
				(width 0.381)
				(type default)
			)
			(layer "F.SilkS")
		)
		(fp_poly
			(pts
				(xy -2.2098 -1.4224) (xy -2.2098 1.4224) (xy 2.2098 1.4224) (xy 2.2098 -1.4224)
			)
			(stroke
				(width 0)
				(type default)
			)
			(fill yes)
			(layer "F.SilkS")
		)
		(fp_rect
			(start -2.450084 2.999994)
			(end 2.450084 -2.999994)
			(stroke
				(width 0)
				(type default)
			)
			(fill no)
			(layer "F.CrtYd")
		)
		(fp_poly
			(pts
				(xy -2.8194 3.6322) (xy -2.8194 -3.6322) (xy 2.8194 -3.6322) (xy 2.8194 1.18364) (xy 2.450084 1.18364)
				(xy 2.450084 -2.999994) (xy -2.450084 -2.999994) (xy -2.450084 2.999994) (xy 2.450084 2.999994)
				(xy 2.450084 1.18618) (xy 2.8194 1.18618) (xy 2.8194 3.6322)
			)
			(stroke
				(width 0)
				(type default)
			)
			(fill no)
			(layer "F.CrtYd")
		)
		(fp_rect
			(start -2.8194 3.6322)
			(end 2.8194 -3.6322)
			(stroke
				(width 0)
				(type default)
			)
			(fill no)
			(layer "F.Fab")
		)
		(pad "1" smd rect
			(at -1.905 2.54 90)
			(size 0.635 1.651)
			(layers "F.Cu" "F.Mask" "F.Paste")
			(net "P12V_B")
		)
		(pad "2" smd rect
			(at -0.635 2.54 90)
			(size 0.635 1.651)
			(layers "F.Cu" "F.Mask" "F.Paste")
			(net "P12V_B")
		)
		(pad "3" smd rect
			(at 0.635 2.54 90)
			(size 0.635 1.651)
			(layers "F.Cu" "F.Mask" "F.Paste")
			(net "P12V_B")
		)
		(pad "4" smd rect
			(at 1.905 2.54 90)
			(size 0.635 1.651)
			(layers "F.Cu" "F.Mask" "F.Paste")
			(net "SW_HDD_N32")
		)
		(pad "5" smd rect
			(at 1.905 -2.54 90)
			(size 0.635 1.651)
			(layers "F.Cu" "F.Mask" "F.Paste")
			(net "P12V_HDD32")
		)
		(pad "6" smd rect
			(at 0.635 -2.54 90)
			(size 0.635 1.651)
			(layers "F.Cu" "F.Mask" "F.Paste")
			(net "P12V_HDD32")
		)
		(pad "7" smd rect
			(at -0.635 -2.54 90)
			(size 0.635 1.651)
			(layers "F.Cu" "F.Mask" "F.Paste")
			(net "P12V_HDD32")
		)
		(pad "8" smd rect
			(at -1.905 -2.54 90)
			(size 0.635 1.651)
			(layers "F.Cu" "F.Mask" "F.Paste")
			(net "P12V_HDD32")
		)
	)
	(footprint ""
		(layer "F.Cu")
		(at 18.923 -265.684 90)
		(property "Reference" "R899"
			(at 0 0 90)
			(layer "F.SilkS")
			(hide yes)
			(effects
				(font
					(size 1.27 1.27)
				)
			)
		)
		(property "Value" "2R6F-GP"
			(at -0.0508 -4.8514 90)
			(unlocked yes)
			(layer "F.Fab")
			(hide yes)
			(effects
				(font
					(size 1.016 1.016)
					(thickness 0.1524)
				)
			)
		)
		(property "Device Type" "R1206H26"
			(at 0 -6.3754 90)
			(unlocked yes)
			(layer "F.Fab")
			(hide yes)
			(effects
				(font
					(size 1.016 1.016)
					(thickness 0.1524)
				)
			)
		)
		(duplicate_pad_numbers_are_jumpers no)
		(fp_line
			(start 1.016 -2.2352)
			(end 1.016 2.2352)
			(stroke
				(width 0.1524)
				(type default)
			)
			(layer "F.SilkS")
		)
		(fp_line
			(start -1.016 -2.2352)
			(end 1.016 -2.2352)
			(stroke
				(width 0.1524)
				(type default)
			)
			(layer "F.SilkS")
		)
		(fp_line
			(start 1.016 2.2352)
			(end -1.016 2.2352)
			(stroke
				(width 0.1524)
				(type default)
			)
			(layer "F.SilkS")
		)
		(fp_line
			(start -1.016 2.2352)
			(end -1.016 -2.2352)
			(stroke
				(width 0.1524)
				(type default)
			)
			(layer "F.SilkS")
		)
		(fp_rect
			(start -1.0922 2.3114)
			(end 1.0922 -2.3114)
			(stroke
				(width 0)
				(type default)
			)
			(fill no)
			(layer "F.CrtYd")
		)
		(fp_poly
			(pts
				(xy -1.0922 -2.3114) (xy 1.0922 -2.3114) (xy 1.0922 2.3114) (xy -1.0922 2.3114)
			)
			(stroke
				(width 0)
				(type default)
			)
			(fill no)
			(layer "F.Fab")
		)
		(pad "1" smd rect
			(at 0 -1.397 90)
			(size 1.651 1.27)
			(layers "F.Cu" "F.Mask" "F.Paste")
			(net "P12V_HDD0")
		)
		(pad "2" smd rect
			(at 0 1.397 90)
			(size 1.651 1.27)
			(layers "F.Cu" "F.Mask" "F.Paste")
			(net "12V_PRE_0")
		)
	)
	(footprint ""
		(layer "F.Cu")
		(at 16.764 -253.111 90)
		(property "Reference" "R905"
			(at 0 0 90)
			(layer "F.SilkS")
			(hide yes)
			(effects
				(font
					(size 1.27 1.27)
				)
			)
		)
		(property "Value" "4K7R2J-2-GP"
			(at 0.064008 -3.993896 90)
			(unlocked yes)
			(layer "F.Fab")
			(hide yes)
			(effects
				(font
					(size 1.016 1.016)
					(thickness 0.1524)
				)
			)
		)
		(property "Device Type" "R402H16"
			(at 0.064008 -5.517896 90)
			(unlocked yes)
			(layer "F.Fab")
			(hide yes)
			(effects
				(font
					(size 1.016 1.016)
					(thickness 0.1524)
				)
			)
		)
		(duplicate_pad_numbers_are_jumpers no)
		(fp_line
			(start 0.508 -0.9398)
			(end -0.508 -0.9398)
			(stroke
				(width 0.1524)
				(type default)
			)
			(layer "F.SilkS")
		)
		(fp_line
			(start -0.508 -0.9398)
			(end -0.508 0.9398)
			(stroke
				(width 0.1524)
				(type default)
			)
			(layer "F.SilkS")
		)
		(fp_rect
			(start -0.508 0.9398)
			(end 0.508 -0.9398)
			(stroke
				(width 0)
				(type default)
			)
			(fill no)
			(layer "F.CrtYd")
		)
		(fp_rect
			(start -0.508 0.9398)
			(end 0.508 -0.9398)
			(stroke
				(width 0)
				(type default)
			)
			(fill no)
			(layer "F.Fab")
		)
		(pad "1" smd custom
			(at 0 -0.4445 90)
			(size 0.1397 0.1397)
			(layers "F.Cu" "F.Mask" "F.Paste")
			(net "P12V_B")
			(options
				(clearance outline)
				(anchor circle)
			)
			(primitives
				(gr_poly
					(pts
						(arc
							(start -0.1778 -0.2794)
							(mid -0.249642 -0.249642)
							(end -0.2794 -0.1778)
						)
						(arc
							(start -0.2794 0.1778)
							(mid -0.249642 0.249642)
							(end -0.1778 0.2794)
						)
						(arc
							(start 0.1778 0.2794)
							(mid 0.249642 0.249642)
							(end 0.2794 0.1778)
						)
						(arc
							(start 0.2794 -0.1778)
							(mid 0.249642 -0.249642)
							(end 0.1778 -0.2794)
						)
					)
					(width 0)
					(fill yes)
				)
			)
		)
		(pad "2" smd custom
			(at 0 0.4445 90)
			(size 0.1397 0.1397)
			(layers "F.Cu" "F.Mask" "F.Paste")
			(net "SW_HDD_P0")
			(options
				(clearance outline)
				(anchor circle)
			)
			(primitives
				(gr_poly
					(pts
						(arc
							(start -0.1778 -0.2794)
							(mid -0.249642 -0.249642)
							(end -0.2794 -0.1778)
						)
						(arc
							(start -0.2794 0.1778)
							(mid -0.249642 0.249642)
							(end -0.1778 0.2794)
						)
						(arc
							(start 0.1778 0.2794)
							(mid 0.249642 0.249642)
							(end 0.2794 0.1778)
						)
						(arc
							(start 0.2794 -0.1778)
							(mid 0.249642 -0.249642)
							(end 0.1778 -0.2794)
						)
					)
					(width 0)
					(fill yes)
				)
			)
		)
	)
	(footprint ""
		(layer "F.Cu")
		(at 112.450118 -65.39992)
		(property "Reference" "LED16"
			(at 0 0 0)
			(layer "F.SilkS")
			(hide yes)
			(effects
				(font
					(size 1.27 1.27)
				)
			)
		)
		(property "Value" "LED-BY-19-GP"
			(at -2.132076 1.414018 0)
			(unlocked yes)
			(layer "F.Fab")
			(hide yes)
			(effects
				(font
					(size 1.016 1.016)
					(thickness 0.1524)
				)
			)
		)
		(property "Device Type" "LED-1615-4PH26"
			(at -2.132076 -0.109982 0)
			(unlocked yes)
			(layer "F.Fab")
			(hide yes)
			(effects
				(font
					(size 1.016 1.016)
					(thickness 0.1524)
				)
			)
		)
		(duplicate_pad_numbers_are_jumpers no)
		(fp_line
			(start -1.2954 0.254)
			(end -1.2954 1.6002)
			(stroke
				(width 0.508)
				(type default)
			)
			(layer "F.SilkS")
		)
		(fp_line
			(start -1.2954 1.6002)
			(end 1.2954 1.6002)
			(stroke
				(width 0.508)
				(type default)
			)
			(layer "F.SilkS")
		)
		(fp_line
			(start -1.1176 -1.4224)
			(end 1.1176 -1.4224)
			(stroke
				(width 0.1524)
				(type default)
			)
			(layer "F.SilkS")
		)
		(fp_line
			(start -1.1176 1.4224)
			(end -1.1176 -1.4224)
			(stroke
				(width 0.1524)
				(type default)
			)
			(layer "F.SilkS")
		)
		(fp_line
			(start 1.1176 -1.4224)
			(end 1.1176 1.4224)
			(stroke
				(width 0.1524)
				(type default)
			)
			(layer "F.SilkS")
		)
		(fp_line
			(start 1.1176 1.4224)
			(end -1.1176 1.4224)
			(stroke
				(width 0.1524)
				(type default)
			)
			(layer "F.SilkS")
		)
		(fp_line
			(start 1.2954 1.6002)
			(end 1.2954 0.254)
			(stroke
				(width 0.508)
				(type default)
			)
			(layer "F.SilkS")
		)
		(fp_rect
			(start -0.7493 0.8001)
			(end 0.7493 -0.8001)
			(stroke
				(width 0)
				(type default)
			)
			(fill no)
			(layer "F.CrtYd")
		)
		(fp_poly
			(pts
				(xy -1.3716 1.6764) (xy -1.3716 -1.6764) (xy 1.3716 -1.6764) (xy 1.3716 0.0635) (xy 0.7493 0.0635)
				(xy 0.7493 -0.8001) (xy -0.7493 -0.8001) (xy -0.7493 0.8001) (xy 0.7493 0.8001) (xy 0.7493 0.0762)
				(xy 1.3716 0.0762) (xy 1.3716 1.6764)
			)
			(stroke
				(width 0)
				(type default)
			)
			(fill no)
			(layer "F.CrtYd")
		)
		(fp_rect
			(start -1.3716 1.6764)
			(end 1.3716 -1.6764)
			(stroke
				(width 0)
				(type default)
			)
			(fill no)
			(layer "F.Fab")
		)
		(pad "1" smd rect
			(at 0.50038 -0.73025)
			(size 0.7112 0.8636)
			(layers "F.Cu" "F.Mask" "F.Paste")
			(net "DRV_ACT_15")
		)
		(pad "2" smd rect
			(at -0.50038 -0.73025)
			(size 0.7112 0.8636)
			(layers "F.Cu" "F.Mask" "F.Paste")
			(net "FLT_HDD15")
		)
		(pad "3" smd rect
			(at 0.50038 0.73025)
			(size 0.7112 0.8636)
			(layers "F.Cu" "F.Mask" "F.Paste")
			(net "DRV_ACT_15_N")
		)
		(pad "4" smd rect
			(at -0.50038 0.73025)
			(size 0.7112 0.8636)
			(layers "F.Cu" "F.Mask" "F.Paste")
			(net "FLT_HDD15_N")
		)
	)
	(footprint ""
		(layer "F.Cu")
		(at 251.4854 -211.201)
		(property "Reference" "C23"
			(at 0 0 0)
			(layer "F.SilkS")
			(hide yes)
			(effects
				(font
					(size 1.27 1.27)
				)
			)
		)
		(property "Value" "SCD1U16V2KX-3GP"
			(at 1.1811 -2.7051 0)
			(unlocked yes)
			(layer "F.Fab")
			(hide yes)
			(effects
				(font
					(size 1.016 1.016)
					(thickness 0.1524)
				)
			)
		)
		(property "Device Type" "C402H22"
			(at 1.1811 -4.2291 0)
			(unlocked yes)
			(layer "F.Fab")
			(hide yes)
			(effects
				(font
					(size 1.016 1.016)
					(thickness 0.1524)
				)
			)
		)
		(duplicate_pad_numbers_are_jumpers no)
		(fp_rect
			(start -0.4318 0.9525)
			(end 0.4318 -0.9525)
			(stroke
				(width 0)
				(type default)
			)
			(fill no)
			(layer "F.CrtYd")
		)
		(fp_rect
			(start -0.4318 0.9525)
			(end 0.4318 -0.9525)
			(stroke
				(width 0)
				(type default)
			)
			(fill no)
			(layer "F.Fab")
		)
		(pad "1" smd custom
			(at 0 -0.4445)
			(size 0.1524 0.1524)
			(layers "F.Cu" "F.Mask" "F.Paste")
			(net "P3V3_STBY_B")
			(options
				(clearance outline)
				(anchor circle)
			)
			(primitives
				(gr_poly
					(pts
						(arc
							(start 0.3048 -0.2032)
							(mid 0.275042 -0.275042)
							(end 0.2032 -0.3048)
						)
						(arc
							(start -0.2032 -0.3048)
							(mid -0.275042 -0.275042)
							(end -0.3048 -0.2032)
						)
						(arc
							(start -0.3048 0.2032)
							(mid -0.275042 0.275042)
							(end -0.2032 0.3048)
						)
						(arc
							(start 0.2032 0.3048)
							(mid 0.275042 0.275042)
							(end 0.3048 0.2032)
						)
					)
					(width 0)
					(fill yes)
				)
			)
		)
		(pad "2" smd custom
			(at 0 0.4445)
			(size 0.1524 0.1524)
			(layers "F.Cu" "F.Mask" "F.Paste")
			(net "GND")
			(options
				(clearance outline)
				(anchor circle)
			)
			(primitives
				(gr_poly
					(pts
						(arc
							(start 0.3048 -0.2032)
							(mid 0.275042 -0.275042)
							(end 0.2032 -0.3048)
						)
						(arc
							(start -0.2032 -0.3048)
							(mid -0.275042 -0.275042)
							(end -0.3048 -0.2032)
						)
						(arc
							(start -0.3048 0.2032)
							(mid -0.275042 0.275042)
							(end -0.2032 0.3048)
						)
						(arc
							(start 0.2032 0.3048)
							(mid 0.275042 0.275042)
							(end 0.3048 0.2032)
						)
					)
					(width 0)
					(fill yes)
				)
			)
		)
	)
	(footprint ""
		(layer "F.Cu")
		(at 50.4952 -9.9568 180)
		(property "Reference" "C364"
			(at 0 0 180)
			(layer "F.SilkS")
			(hide yes)
			(effects
				(font
					(size 1.27 1.27)
				)
			)
		)
		(property "Value" "SCD033U25V2KX-GP"
			(at 1.1811 -2.7051 180)
			(unlocked yes)
			(layer "F.Fab")
			(hide yes)
			(effects
				(font
					(size 1.016 1.016)
					(thickness 0.1524)
				)
			)
		)
		(property "Device Type" "C402H22"
			(at 1.1811 -4.2291 180)
			(unlocked yes)
			(layer "F.Fab")
			(hide yes)
			(effects
				(font
					(size 1.016 1.016)
					(thickness 0.1524)
				)
			)
		)
		(duplicate_pad_numbers_are_jumpers no)
		(fp_rect
			(start -0.4318 0.9525)
			(end 0.4318 -0.9525)
			(stroke
				(width 0)
				(type default)
			)
			(fill no)
			(layer "F.CrtYd")
		)
		(fp_rect
			(start -0.4318 0.9525)
			(end 0.4318 -0.9525)
			(stroke
				(width 0)
				(type default)
			)
			(fill no)
			(layer "F.Fab")
		)
		(pad "1" smd custom
			(at 0 -0.4445 180)
			(size 0.1524 0.1524)
			(layers "F.Cu" "F.Mask" "F.Paste")
			(net "P12V_B")
			(options
				(clearance outline)
				(anchor circle)
			)
			(primitives
				(gr_poly
					(pts
						(arc
							(start 0.3048 -0.2032)
							(mid 0.275042 -0.275042)
							(end 0.2032 -0.3048)
						)
						(arc
							(start -0.2032 -0.3048)
							(mid -0.275042 -0.275042)
							(end -0.3048 -0.2032)
						)
						(arc
							(start -0.3048 0.2032)
							(mid -0.275042 0.275042)
							(end -0.2032 0.3048)
						)
						(arc
							(start 0.2032 0.3048)
							(mid 0.275042 0.275042)
							(end 0.3048 0.2032)
						)
					)
					(width 0)
					(fill yes)
				)
			)
		)
		(pad "2" smd custom
			(at 0 0.4445 180)
			(size 0.1524 0.1524)
			(layers "F.Cu" "F.Mask" "F.Paste")
			(net "SW_HDD_N25")
			(options
				(clearance outline)
				(anchor circle)
			)
			(primitives
				(gr_poly
					(pts
						(arc
							(start 0.3048 -0.2032)
							(mid 0.275042 -0.275042)
							(end 0.2032 -0.3048)
						)
						(arc
							(start -0.2032 -0.3048)
							(mid -0.275042 -0.275042)
							(end -0.3048 -0.2032)
						)
						(arc
							(start -0.3048 0.2032)
							(mid -0.275042 0.275042)
							(end -0.2032 0.3048)
						)
						(arc
							(start 0.2032 0.3048)
							(mid 0.275042 0.275042)
							(end 0.3048 0.2032)
						)
					)
					(width 0)
					(fill yes)
				)
			)
		)
	)
	(footprint ""
		(layer "F.Cu")
		(at 315.149992 -65.39992)
		(property "Reference" "LED19"
			(at 0 0 0)
			(layer "F.SilkS")
			(hide yes)
			(effects
				(font
					(size 1.27 1.27)
				)
			)
		)
		(property "Value" "LED-BY-19-GP"
			(at -2.132076 1.414018 0)
			(unlocked yes)
			(layer "F.Fab")
			(hide yes)
			(effects
				(font
					(size 1.016 1.016)
					(thickness 0.1524)
				)
			)
		)
		(property "Device Type" "LED-1615-4PH26"
			(at -2.132076 -0.109982 0)
			(unlocked yes)
			(layer "F.Fab")
			(hide yes)
			(effects
				(font
					(size 1.016 1.016)
					(thickness 0.1524)
				)
			)
		)
		(duplicate_pad_numbers_are_jumpers no)
		(fp_line
			(start -1.2954 0.254)
			(end -1.2954 1.6002)
			(stroke
				(width 0.508)
				(type default)
			)
			(layer "F.SilkS")
		)
		(fp_line
			(start -1.2954 1.6002)
			(end 1.2954 1.6002)
			(stroke
				(width 0.508)
				(type default)
			)
			(layer "F.SilkS")
		)
		(fp_line
			(start -1.1176 -1.4224)
			(end 1.1176 -1.4224)
			(stroke
				(width 0.1524)
				(type default)
			)
			(layer "F.SilkS")
		)
		(fp_line
			(start -1.1176 1.4224)
			(end -1.1176 -1.4224)
			(stroke
				(width 0.1524)
				(type default)
			)
			(layer "F.SilkS")
		)
		(fp_line
			(start 1.1176 -1.4224)
			(end 1.1176 1.4224)
			(stroke
				(width 0.1524)
				(type default)
			)
			(layer "F.SilkS")
		)
		(fp_line
			(start 1.1176 1.4224)
			(end -1.1176 1.4224)
			(stroke
				(width 0.1524)
				(type default)
			)
			(layer "F.SilkS")
		)
		(fp_line
			(start 1.2954 1.6002)
			(end 1.2954 0.254)
			(stroke
				(width 0.508)
				(type default)
			)
			(layer "F.SilkS")
		)
		(fp_rect
			(start -0.7493 0.8001)
			(end 0.7493 -0.8001)
			(stroke
				(width 0)
				(type default)
			)
			(fill no)
			(layer "F.CrtYd")
		)
		(fp_poly
			(pts
				(xy -1.3716 1.6764) (xy -1.3716 -1.6764) (xy 1.3716 -1.6764) (xy 1.3716 0.0635) (xy 0.7493 0.0635)
				(xy 0.7493 -0.8001) (xy -0.7493 -0.8001) (xy -0.7493 0.8001) (xy 0.7493 0.8001) (xy 0.7493 0.0762)
				(xy 1.3716 0.0762) (xy 1.3716 1.6764)
			)
			(stroke
				(width 0)
				(type default)
			)
			(fill no)
			(layer "F.CrtYd")
		)
		(fp_rect
			(start -1.3716 1.6764)
			(end 1.3716 -1.6764)
			(stroke
				(width 0)
				(type default)
			)
			(fill no)
			(layer "F.Fab")
		)
		(pad "1" smd rect
			(at 0.50038 -0.73025)
			(size 0.7112 0.8636)
			(layers "F.Cu" "F.Mask" "F.Paste")
			(net "DRV_ACT_18")
		)
		(pad "2" smd rect
			(at -0.50038 -0.73025)
			(size 0.7112 0.8636)
			(layers "F.Cu" "F.Mask" "F.Paste")
			(net "FLT_HDD18")
		)
		(pad "3" smd rect
			(at 0.50038 0.73025)
			(size 0.7112 0.8636)
			(layers "F.Cu" "F.Mask" "F.Paste")
			(net "DRV_ACT_18_N")
		)
		(pad "4" smd rect
			(at -0.50038 0.73025)
			(size 0.7112 0.8636)
			(layers "F.Cu" "F.Mask" "F.Paste")
			(net "FLT_HDD18_N")
		)
	)
	(footprint ""
		(layer "F.Cu")
		(at 37.305996 -371.856 -90)
		(property "Reference" "D37"
			(at 0 0 270)
			(layer "F.SilkS")
			(hide yes)
			(effects
				(font
					(size 1.27 1.27)
				)
			)
		)
		(property "Value" "BAS16H-GP"
			(at 0 -5.5372 270)
			(unlocked yes)
			(layer "F.Fab")
			(hide yes)
			(effects
				(font
					(size 1.016 1.016)
					(thickness 0.1524)
				)
			)
		)
		(property "Device Type" "SOD123AKH48"
			(at 0 -7.0612 270)
			(unlocked yes)
			(layer "F.Fab")
			(hide yes)
			(effects
				(font
					(size 1.016 1.016)
					(thickness 0.1524)
				)
			)
		)
		(duplicate_pad_numbers_are_jumpers no)
		(fp_line
			(start 0.889 2.921)
			(end -0.889 2.921)
			(stroke
				(width 0.508)
				(type default)
			)
			(layer "F.SilkS")
		)
		(fp_line
			(start -1.016 2.667)
			(end 1.016 2.667)
			(stroke
				(width 0.1524)
				(type default)
			)
			(layer "F.SilkS")
		)
		(fp_line
			(start 1.016 2.667)
			(end 1.016 -2.667)
			(stroke
				(width 0.1524)
				(type default)
			)
			(layer "F.SilkS")
		)
		(fp_line
			(start -1.016 -2.667)
			(end -1.016 2.667)
			(stroke
				(width 0.1524)
				(type default)
			)
			(layer "F.SilkS")
		)
		(fp_line
			(start 1.016 -2.667)
			(end -1.016 -2.667)
			(stroke
				(width 0.1524)
				(type default)
			)
			(layer "F.SilkS")
		)
		(fp_rect
			(start -1.143 3.175)
			(end 1.143 -2.794)
			(stroke
				(width 0)
				(type default)
			)
			(fill no)
			(layer "F.CrtYd")
		)
		(fp_poly
			(pts
				(xy -1.143 -2.794) (xy 1.143 -2.794) (xy 1.143 3.175) (xy -1.143 3.175)
			)
			(stroke
				(width 0)
				(type default)
			)
			(fill no)
			(layer "F.Fab")
		)
		(pad "A" smd rect
			(at 0 -1.6891 270)
			(size 0.889 1.397)
			(layers "F.Cu" "F.Mask" "F.Paste")
			(net "FAN_0_TACH0")
		)
		(pad "K" smd rect
			(at 0 1.6891 270)
			(size 0.889 1.397)
			(layers "F.Cu" "F.Mask" "F.Paste")
			(net "P12V_IN")
		)
	)
	(footprint ""
		(layer "F.Cu")
		(at 111.379 -138.049 90)
		(property "Reference" "R422"
			(at 0 0 90)
			(layer "F.SilkS")
			(hide yes)
			(effects
				(font
					(size 1.27 1.27)
				)
			)
		)
		(property "Value" "4K7R2J-2-GP"
			(at 0.064008 -3.993896 90)
			(unlocked yes)
			(layer "F.Fab")
			(hide yes)
			(effects
				(font
					(size 1.016 1.016)
					(thickness 0.1524)
				)
			)
		)
		(property "Device Type" "R402H16"
			(at 0.064008 -5.517896 90)
			(unlocked yes)
			(layer "F.Fab")
			(hide yes)
			(effects
				(font
					(size 1.016 1.016)
					(thickness 0.1524)
				)
			)
		)
		(duplicate_pad_numbers_are_jumpers no)
		(fp_line
			(start 0.508 -0.9398)
			(end -0.508 -0.9398)
			(stroke
				(width 0.1524)
				(type default)
			)
			(layer "F.SilkS")
		)
		(fp_line
			(start -0.508 -0.9398)
			(end -0.508 0.9398)
			(stroke
				(width 0.1524)
				(type default)
			)
			(layer "F.SilkS")
		)
		(fp_rect
			(start -0.508 0.9398)
			(end 0.508 -0.9398)
			(stroke
				(width 0)
				(type default)
			)
			(fill no)
			(layer "F.CrtYd")
		)
		(fp_rect
			(start -0.508 0.9398)
			(end 0.508 -0.9398)
			(stroke
				(width 0)
				(type default)
			)
			(fill no)
			(layer "F.Fab")
		)
		(pad "1" smd custom
			(at 0 -0.4445 90)
			(size 0.1397 0.1397)
			(layers "F.Cu" "F.Mask" "F.Paste")
			(net "P12V_B")
			(options
				(clearance outline)
				(anchor circle)
			)
			(primitives
				(gr_poly
					(pts
						(arc
							(start -0.1778 -0.2794)
							(mid -0.249642 -0.249642)
							(end -0.2794 -0.1778)
						)
						(arc
							(start -0.2794 0.1778)
							(mid -0.249642 0.249642)
							(end -0.1778 0.2794)
						)
						(arc
							(start 0.1778 0.2794)
							(mid 0.249642 0.249642)
							(end 0.2794 0.1778)
						)
						(arc
							(start 0.2794 -0.1778)
							(mid 0.249642 -0.249642)
							(end 0.1778 -0.2794)
						)
					)
					(width 0)
					(fill yes)
				)
			)
		)
		(pad "2" smd custom
			(at 0 0.4445 90)
			(size 0.1397 0.1397)
			(layers "F.Cu" "F.Mask" "F.Paste")
			(net "SW_HDD_P15")
			(options
				(clearance outline)
				(anchor circle)
			)
			(primitives
				(gr_poly
					(pts
						(arc
							(start -0.1778 -0.2794)
							(mid -0.249642 -0.249642)
							(end -0.2794 -0.1778)
						)
						(arc
							(start -0.2794 0.1778)
							(mid -0.249642 0.249642)
							(end -0.1778 0.2794)
						)
						(arc
							(start 0.1778 0.2794)
							(mid 0.249642 0.249642)
							(end 0.2794 0.1778)
						)
						(arc
							(start 0.2794 -0.1778)
							(mid 0.249642 -0.249642)
							(end 0.1778 -0.2794)
						)
					)
					(width 0)
					(fill yes)
				)
			)
		)
	)
	(footprint ""
		(layer "F.Cu")
		(at 426.974 -266.827 180)
		(property "Reference" "C148"
			(at 0 0 180)
			(layer "F.SilkS")
			(hide yes)
			(effects
				(font
					(size 1.27 1.27)
				)
			)
		)
		(property "Value" "SC10U16V6KX-2GP"
			(at -0.0762 -5.1308 180)
			(unlocked yes)
			(layer "F.Fab")
			(hide yes)
			(effects
				(font
					(size 1.016 1.016)
					(thickness 0.1524)
				)
			)
		)
		(property "Device Type" "C1206H71"
			(at -0.127 -6.6548 180)
			(unlocked yes)
			(layer "F.Fab")
			(hide yes)
			(effects
				(font
					(size 1.016 1.016)
					(thickness 0.1524)
				)
			)
		)
		(duplicate_pad_numbers_are_jumpers no)
		(fp_line
			(start 1.016 2.2352)
			(end -1.016 2.2352)
			(stroke
				(width 0.1524)
				(type default)
			)
			(layer "F.SilkS")
		)
		(fp_line
			(start 1.016 0.8382)
			(end 1.016 2.2352)
			(stroke
				(width 0.1524)
				(type default)
			)
			(layer "F.SilkS")
		)
		(fp_line
			(start 1.016 -2.2352)
			(end 1.016 -0.8382)
			(stroke
				(width 0.1524)
				(type default)
			)
			(layer "F.SilkS")
		)
		(fp_line
			(start -1.016 2.2352)
			(end -1.016 0.8382)
			(stroke
				(width 0.1524)
				(type default)
			)
			(layer "F.SilkS")
		)
		(fp_line
			(start -1.016 -0.8382)
			(end -1.016 -2.2352)
			(stroke
				(width 0.1524)
				(type default)
			)
			(layer "F.SilkS")
		)
		(fp_line
			(start -1.016 -2.2352)
			(end 1.016 -2.2352)
			(stroke
				(width 0.1524)
				(type default)
			)
			(layer "F.SilkS")
		)
		(fp_rect
			(start -1.0922 2.3114)
			(end 1.0922 -2.3114)
			(stroke
				(width 0)
				(type default)
			)
			(fill no)
			(layer "F.CrtYd")
		)
		(fp_poly
			(pts
				(xy 1.0922 -2.3114) (xy 1.0922 2.3114) (xy -1.0922 2.3114) (xy -1.0922 -2.3114)
			)
			(stroke
				(width 0)
				(type default)
			)
			(fill no)
			(layer "F.Fab")
		)
		(pad "1" smd rect
			(at 0 -1.397 180)
			(size 1.651 1.27)
			(layers "F.Cu" "F.Mask" "F.Paste")
			(net "P5V_HDD9")
		)
		(pad "2" smd rect
			(at 0 1.397 180)
			(size 1.651 1.27)
			(layers "F.Cu" "F.Mask" "F.Paste")
			(net "GND")
		)
	)
	(footprint ""
		(layer "F.Cu")
		(at 285.651448 -352.748342 180)
		(property "Reference" "U29"
			(at 0 0 180)
			(layer "F.SilkS")
			(hide yes)
			(effects
				(font
					(size 1.27 1.27)
				)
			)
		)
		(property "Value" "MAX31790ATI-T-GP"
			(at 4.1021 -3.7338 180)
			(unlocked yes)
			(layer "F.Fab")
			(hide yes)
			(effects
				(font
					(size 1.016 1.016)
					(thickness 0.1524)
				)
			)
		)
		(property "Device Type" "QFN28-G2D7H32"
			(at 4.1021 -5.2578 180)
			(unlocked yes)
			(layer "F.Fab")
			(hide yes)
			(effects
				(font
					(size 1.016 1.016)
					(thickness 0.1524)
				)
			)
		)
		(duplicate_pad_numbers_are_jumpers no)
		(fp_line
			(start 3.0099 3.0099)
			(end 3.0099 1.7399)
			(stroke
				(width 0.1524)
				(type default)
			)
			(layer "F.SilkS")
		)
		(fp_line
			(start 2.7813 0)
			(end 3.2893 0)
			(stroke
				(width 0.1524)
				(type default)
			)
			(layer "F.SilkS")
		)
		(fp_line
			(start 1.7399 3.0099)
			(end 3.0099 3.0099)
			(stroke
				(width 0.1524)
				(type default)
			)
			(layer "F.SilkS")
		)
		(fp_line
			(start 0.8128 2.7813)
			(end 0.8128 3.5433)
			(stroke
				(width 0.1524)
				(type default)
			)
			(layer "F.SilkS")
		)
		(fp_line
			(start -0.4064 -2.7813)
			(end -0.4064 -3.2893)
			(stroke
				(width 0.1524)
				(type default)
			)
			(layer "F.SilkS")
		)
		(fp_line
			(start -1.1938 2.7813)
			(end -1.1938 3.2893)
			(stroke
				(width 0.1524)
				(type default)
			)
			(layer "F.SilkS")
		)
		(fp_line
			(start -2.7813 -0.4064)
			(end -3.5433 -0.4064)
			(stroke
				(width 0.1524)
				(type default)
			)
			(layer "F.SilkS")
		)
		(fp_line
			(start -3.0099 3.0099)
			(end -1.7399 3.0099)
			(stroke
				(width 0.1524)
				(type default)
			)
			(layer "F.SilkS")
		)
		(fp_line
			(start -3.0099 1.7399)
			(end -3.0099 3.0099)
			(stroke
				(width 0.1524)
				(type default)
			)
			(layer "F.SilkS")
		)
		(fp_line
			(start -3.0099 -1.7399)
			(end -3.0099 -3.0099)
			(stroke
				(width 0.1524)
				(type default)
			)
			(layer "F.SilkS")
		)
		(fp_line
			(start -3.0099 -3.0099)
			(end -1.7399 -3.0099)
			(stroke
				(width 0.1524)
				(type default)
			)
			(layer "F.SilkS")
		)
		(fp_poly
			(pts
				(xy 3.0099 -1.7399) (xy 1.7399 -3.0099) (xy 3.0099 -3.0099)
			)
			(stroke
				(width 0)
				(type default)
			)
			(fill yes)
			(layer "F.SilkS")
		)
		(fp_rect
			(start -1.9939 1.9939)
			(end 1.9939 -1.9939)
			(stroke
				(width 0)
				(type default)
			)
			(fill no)
			(layer "F.CrtYd")
		)
		(fp_poly
			(pts
				(xy -3.0099 3.0099) (xy -3.0099 -3.0099) (xy 3.0099 -3.0099) (xy 3.0099 3.0099) (xy -1.98882 3.0099)
				(xy -1.98882 1.9939) (xy 1.9939 1.9939) (xy 1.9939 -1.9939) (xy -1.9939 -1.9939) (xy -1.9939 3.0099)
			)
			(stroke
				(width 0)
				(type default)
			)
			(fill no)
			(layer "F.CrtYd")
		)
		(fp_rect
			(start -3.0099 3.0099)
			(end 3.0099 -3.0099)
			(stroke
				(width 0)
				(type default)
			)
			(fill no)
			(layer "F.Fab")
		)
		(pad "1" smd rect
			(at 1.199896 -2.032 180)
			(size 0.2032 0.9398)
			(layers "F.Cu" "F.Mask" "F.Paste")
			(net "MAX31790_B_FREQ_ST")
		)
		(pad "2" smd rect
			(at 0.8001 -2.032 180)
			(size 0.2032 0.9398)
			(layers "F.Cu" "F.Mask" "F.Paste")
			(net "MAX31790_B_SPIN_ST")
		)
		(pad "3" smd rect
			(at 0.40005 -2.032 180)
			(size 0.2032 0.9398)
			(layers "F.Cu" "F.Mask" "F.Paste")
			(net "MAX31790_B_ADD1")
		)
		(pad "4" smd rect
			(at 0 -2.032 180)
			(size 0.2032 0.9398)
			(layers "F.Cu" "F.Mask" "F.Paste")
			(net "MAX31790_B_ADD0")
		)
		(pad "5" smd rect
			(at -0.40005 -2.032 180)
			(size 0.2032 0.9398)
			(layers "F.Cu" "F.Mask" "F.Paste")
			(net "MAX31790_B_WD_ST")
		)
		(pad "6" smd rect
			(at -0.8001 -2.032 180)
			(size 0.2032 0.9398)
			(layers "F.Cu" "F.Mask" "F.Paste")
			(net "Net_317")
		)
		(pad "7" smd rect
			(at -1.199896 -2.032 180)
			(size 0.2032 0.9398)
			(layers "F.Cu" "F.Mask" "F.Paste")
			(net "GND")
		)
		(pad "8" smd rect
			(at -2.032 -1.199896 180)
			(size 0.9398 0.2032)
			(layers "F.Cu" "F.Mask" "F.Paste")
			(net "GND")
		)
		(pad "9" smd rect
			(at -2.032 -0.8001 180)
			(size 0.9398 0.2032)
			(layers "F.Cu" "F.Mask" "F.Paste")
			(net "FANTACH_B_R3")
		)
		(pad "10" smd rect
			(at -2.032 -0.40005 180)
			(size 0.9398 0.2032)
			(layers "F.Cu" "F.Mask" "F.Paste")
			(net "Net_320")
		)
		(pad "11" smd rect
			(at -2.032 0 180)
			(size 0.9398 0.2032)
			(layers "F.Cu" "F.Mask" "F.Paste")
			(net "FANTACH_B_F3")
		)
		(pad "12" smd rect
			(at -2.032 0.40005 180)
			(size 0.9398 0.2032)
			(layers "F.Cu" "F.Mask" "F.Paste")
			(net "Net_321")
		)
		(pad "13" smd rect
			(at -2.032 0.8001 180)
			(size 0.9398 0.2032)
			(layers "F.Cu" "F.Mask" "F.Paste")
			(net "FANTACH_B_R2")
		)
		(pad "14" smd rect
			(at -2.032 1.199896 180)
			(size 0.9398 0.2032)
			(layers "F.Cu" "F.Mask" "F.Paste")
			(net "Net_322")
		)
		(pad "15" smd rect
			(at -1.199896 2.032 180)
			(size 0.2032 0.9398)
			(layers "F.Cu" "F.Mask" "F.Paste")
			(net "FANTACH_B_F2")
		)
		(pad "16" smd rect
			(at -0.8001 2.032 180)
			(size 0.2032 0.9398)
			(layers "F.Cu" "F.Mask" "F.Paste")
			(net "Net_319")
		)
		(pad "17" smd rect
			(at -0.40005 2.032 180)
			(size 0.2032 0.9398)
			(layers "F.Cu" "F.Mask" "F.Paste")
			(net "FANTACH_B_R1")
		)
		(pad "18" smd rect
			(at 0 2.032 180)
			(size 0.2032 0.9398)
			(layers "F.Cu" "F.Mask" "F.Paste")
			(net "FANTACH_B_R0")
		)
		(pad "19" smd rect
			(at 0.40005 2.032 180)
			(size 0.2032 0.9398)
			(layers "F.Cu" "F.Mask" "F.Paste")
			(net "FANTACH_B_F1")
		)
		(pad "20" smd rect
			(at 0.8001 2.032 180)
			(size 0.2032 0.9398)
			(layers "F.Cu" "F.Mask" "F.Paste")
			(net "FANTACH_B_F0")
		)
		(pad "21" smd rect
			(at 1.199896 2.032 180)
			(size 0.2032 0.9398)
			(layers "F.Cu" "F.Mask" "F.Paste")
			(net "P3V3_STBY_B")
		)
		(pad "22" smd rect
			(at 2.032 1.199896 180)
			(size 0.9398 0.2032)
			(layers "F.Cu" "F.Mask" "F.Paste")
			(net "MAX31790_B_SDA")
		)
		(pad "23" smd rect
			(at 2.032 0.8001 180)
			(size 0.9398 0.2032)
			(layers "F.Cu" "F.Mask" "F.Paste")
			(net "MAX31790_B_SCL")
		)
		(pad "24" smd rect
			(at 2.032 0.40005 180)
			(size 0.9398 0.2032)
			(layers "F.Cu" "F.Mask" "F.Paste")
			(net "MAX31790_B_FAIL")
		)
		(pad "25" smd rect
			(at 2.032 0 180)
			(size 0.9398 0.2032)
			(layers "F.Cu" "F.Mask" "F.Paste")
			(net "MAX31790_B_PWM_ST0")
		)
		(pad "26" smd rect
			(at 2.032 -0.40005 180)
			(size 0.9398 0.2032)
			(layers "F.Cu" "F.Mask" "F.Paste")
			(net "MAX31790_B_PWM_ST1")
		)
		(pad "27" smd rect
			(at 2.032 -0.8001 180)
			(size 0.9398 0.2032)
			(layers "F.Cu" "F.Mask" "F.Paste")
			(net "MAX31790_B_FULL_SPEED")
		)
		(pad "28" smd rect
			(at 2.032 -1.199896 180)
			(size 0.9398 0.2032)
			(layers "F.Cu" "F.Mask" "F.Paste")
			(net "Net_318")
		)
		(pad "29" smd rect
			(at 0 0 180)
			(size 2.6924 2.6924)
			(layers "F.Cu" "F.Mask" "F.Paste")
			(net "GND")
		)
	)
	(footprint ""
		(layer "F.Cu")
		(at 331.47 -262.001 -90)
		(property "Reference" "R254"
			(at 0 0 270)
			(layer "F.SilkS")
			(hide yes)
			(effects
				(font
					(size 1.27 1.27)
				)
			)
		)
		(property "Value" "2R6F-GP"
			(at -0.0508 -4.8514 270)
			(unlocked yes)
			(layer "F.Fab")
			(hide yes)
			(effects
				(font
					(size 1.016 1.016)
					(thickness 0.1524)
				)
			)
		)
		(property "Device Type" "R1206H26"
			(at 0 -6.3754 270)
			(unlocked yes)
			(layer "F.Fab")
			(hide yes)
			(effects
				(font
					(size 1.016 1.016)
					(thickness 0.1524)
				)
			)
		)
		(duplicate_pad_numbers_are_jumpers no)
		(fp_line
			(start -1.016 2.2352)
			(end -1.016 -2.2352)
			(stroke
				(width 0.1524)
				(type default)
			)
			(layer "F.SilkS")
		)
		(fp_line
			(start 1.016 2.2352)
			(end -1.016 2.2352)
			(stroke
				(width 0.1524)
				(type default)
			)
			(layer "F.SilkS")
		)
		(fp_line
			(start -1.016 -2.2352)
			(end 1.016 -2.2352)
			(stroke
				(width 0.1524)
				(type default)
			)
			(layer "F.SilkS")
		)
		(fp_line
			(start 1.016 -2.2352)
			(end 1.016 2.2352)
			(stroke
				(width 0.1524)
				(type default)
			)
			(layer "F.SilkS")
		)
		(fp_rect
			(start -1.0922 2.3114)
			(end 1.0922 -2.3114)
			(stroke
				(width 0)
				(type default)
			)
			(fill no)
			(layer "F.CrtYd")
		)
		(fp_poly
			(pts
				(xy -1.0922 -2.3114) (xy 1.0922 -2.3114) (xy 1.0922 2.3114) (xy -1.0922 2.3114)
			)
			(stroke
				(width 0)
				(type default)
			)
			(fill no)
			(layer "F.Fab")
		)
		(pad "1" smd rect
			(at 0 -1.397 270)
			(size 1.651 1.27)
			(layers "F.Cu" "F.Mask" "F.Paste")
			(net "P5V_HDD6")
		)
		(pad "2" smd rect
			(at 0 1.397 270)
			(size 1.651 1.27)
			(layers "F.Cu" "F.Mask" "F.Paste")
			(net "5V_PRE_6")
		)
	)
	(footprint ""
		(layer "F.Cu")
		(at 398.145 -10.16 180)
		(property "Reference" "R816"
			(at 0 0 180)
			(layer "F.SilkS")
			(hide yes)
			(effects
				(font
					(size 1.27 1.27)
				)
			)
		)
		(property "Value" "0R2J-2-GP"
			(at 0.064008 -3.993896 180)
			(unlocked yes)
			(layer "F.Fab")
			(hide yes)
			(effects
				(font
					(size 1.016 1.016)
					(thickness 0.1524)
				)
			)
		)
		(property "Device Type" "R402H16"
			(at 0.064008 -5.517896 180)
			(unlocked yes)
			(layer "F.Fab")
			(hide yes)
			(effects
				(font
					(size 1.016 1.016)
					(thickness 0.1524)
				)
			)
		)
		(duplicate_pad_numbers_are_jumpers no)
		(fp_line
			(start 0.508 -0.9398)
			(end -0.508 -0.9398)
			(stroke
				(width 0.1524)
				(type default)
			)
			(layer "F.SilkS")
		)
		(fp_line
			(start -0.508 -0.9398)
			(end -0.508 0.9398)
			(stroke
				(width 0.1524)
				(type default)
			)
			(layer "F.SilkS")
		)
		(fp_rect
			(start -0.508 0.9398)
			(end 0.508 -0.9398)
			(stroke
				(width 0)
				(type default)
			)
			(fill no)
			(layer "F.CrtYd")
		)
		(fp_rect
			(start -0.508 0.9398)
			(end 0.508 -0.9398)
			(stroke
				(width 0)
				(type default)
			)
			(fill no)
			(layer "F.Fab")
		)
		(pad "1" smd custom
			(at 0 -0.4445 180)
			(size 0.1397 0.1397)
			(layers "F.Cu" "F.Mask" "F.Paste")
			(net "DRIVE_B_32_PWR")
			(options
				(clearance outline)
				(anchor circle)
			)
			(primitives
				(gr_poly
					(pts
						(arc
							(start -0.1778 -0.2794)
							(mid -0.249642 -0.249642)
							(end -0.2794 -0.1778)
						)
						(arc
							(start -0.2794 0.1778)
							(mid -0.249642 0.249642)
							(end -0.1778 0.2794)
						)
						(arc
							(start 0.1778 0.2794)
							(mid 0.249642 0.249642)
							(end 0.2794 0.1778)
						)
						(arc
							(start 0.2794 -0.1778)
							(mid 0.249642 -0.249642)
							(end 0.1778 -0.2794)
						)
					)
					(width 0)
					(fill yes)
				)
			)
		)
		(pad "2" smd custom
			(at 0 0.4445 180)
			(size 0.1397 0.1397)
			(layers "F.Cu" "F.Mask" "F.Paste")
			(net "SW_PWR_R_HDD32")
			(options
				(clearance outline)
				(anchor circle)
			)
			(primitives
				(gr_poly
					(pts
						(arc
							(start -0.1778 -0.2794)
							(mid -0.249642 -0.249642)
							(end -0.2794 -0.1778)
						)
						(arc
							(start -0.2794 0.1778)
							(mid -0.249642 0.249642)
							(end -0.1778 0.2794)
						)
						(arc
							(start 0.1778 0.2794)
							(mid 0.249642 0.249642)
							(end 0.2794 0.1778)
						)
						(arc
							(start 0.2794 -0.1778)
							(mid 0.249642 -0.249642)
							(end 0.1778 -0.2794)
						)
					)
					(width 0)
					(fill yes)
				)
			)
		)
	)
	(footprint ""
		(layer "F.Cu")
		(at 260.462522 -369.798346 90)
		(property "Reference" "R1027"
			(at 0 0 90)
			(layer "F.SilkS")
			(hide yes)
			(effects
				(font
					(size 1.27 1.27)
				)
			)
		)
		(property "Value" "0R2J-2-GP"
			(at 0.064008 -3.993896 90)
			(unlocked yes)
			(layer "F.Fab")
			(hide yes)
			(effects
				(font
					(size 1.016 1.016)
					(thickness 0.1524)
				)
			)
		)
		(property "Device Type" "R402H16"
			(at 0.064008 -5.517896 90)
			(unlocked yes)
			(layer "F.Fab")
			(hide yes)
			(effects
				(font
					(size 1.016 1.016)
					(thickness 0.1524)
				)
			)
		)
		(duplicate_pad_numbers_are_jumpers no)
		(fp_line
			(start 0.508 -0.9398)
			(end -0.508 -0.9398)
			(stroke
				(width 0.1524)
				(type default)
			)
			(layer "F.SilkS")
		)
		(fp_line
			(start -0.508 -0.9398)
			(end -0.508 0.9398)
			(stroke
				(width 0.1524)
				(type default)
			)
			(layer "F.SilkS")
		)
		(fp_rect
			(start -0.508 0.9398)
			(end 0.508 -0.9398)
			(stroke
				(width 0)
				(type default)
			)
			(fill no)
			(layer "F.CrtYd")
		)
		(fp_rect
			(start -0.508 0.9398)
			(end 0.508 -0.9398)
			(stroke
				(width 0)
				(type default)
			)
			(fill no)
			(layer "F.Fab")
		)
		(pad "1" smd custom
			(at 0 -0.4445 90)
			(size 0.1397 0.1397)
			(layers "F.Cu" "F.Mask" "F.Paste")
			(net "MB3_SCL_R")
			(options
				(clearance outline)
				(anchor circle)
			)
			(primitives
				(gr_poly
					(pts
						(arc
							(start -0.1778 -0.2794)
							(mid -0.249642 -0.249642)
							(end -0.2794 -0.1778)
						)
						(arc
							(start -0.2794 0.1778)
							(mid -0.249642 0.249642)
							(end -0.1778 0.2794)
						)
						(arc
							(start 0.1778 0.2794)
							(mid 0.249642 0.249642)
							(end 0.2794 0.1778)
						)
						(arc
							(start 0.2794 -0.1778)
							(mid 0.249642 -0.249642)
							(end 0.1778 -0.2794)
						)
					)
					(width 0)
					(fill yes)
				)
			)
		)
		(pad "2" smd custom
			(at 0 0.4445 90)
			(size 0.1397 0.1397)
			(layers "F.Cu" "F.Mask" "F.Paste")
			(net "I2C_DPB_B_SCL_BUF")
			(options
				(clearance outline)
				(anchor circle)
			)
			(primitives
				(gr_poly
					(pts
						(arc
							(start -0.1778 -0.2794)
							(mid -0.249642 -0.249642)
							(end -0.2794 -0.1778)
						)
						(arc
							(start -0.2794 0.1778)
							(mid -0.249642 0.249642)
							(end -0.1778 0.2794)
						)
						(arc
							(start 0.1778 0.2794)
							(mid 0.249642 0.249642)
							(end 0.2794 0.1778)
						)
						(arc
							(start 0.2794 -0.1778)
							(mid 0.249642 -0.249642)
							(end 0.1778 -0.2794)
						)
					)
					(width 0)
					(fill yes)
				)
			)
		)
	)
	(footprint ""
		(layer "F.Cu")
		(at 332.105 -243.586)
		(property "Reference" "R263"
			(at 0 0 0)
			(layer "F.SilkS")
			(hide yes)
			(effects
				(font
					(size 1.27 1.27)
				)
			)
		)
		(property "Value" "4K7R2F-GP"
			(at 0.064008 -3.993896 0)
			(unlocked yes)
			(layer "F.Fab")
			(hide yes)
			(effects
				(font
					(size 1.016 1.016)
					(thickness 0.1524)
				)
			)
		)
		(property "Device Type" "R402H16"
			(at 0.064008 -5.517896 0)
			(unlocked yes)
			(layer "F.Fab")
			(hide yes)
			(effects
				(font
					(size 1.016 1.016)
					(thickness 0.1524)
				)
			)
		)
		(duplicate_pad_numbers_are_jumpers no)
		(fp_line
			(start -0.508 -0.9398)
			(end -0.508 0.9398)
			(stroke
				(width 0.1524)
				(type default)
			)
			(layer "F.SilkS")
		)
		(fp_line
			(start 0.508 -0.9398)
			(end -0.508 -0.9398)
			(stroke
				(width 0.1524)
				(type default)
			)
			(layer "F.SilkS")
		)
		(fp_rect
			(start -0.508 0.9398)
			(end 0.508 -0.9398)
			(stroke
				(width 0)
				(type default)
			)
			(fill no)
			(layer "F.CrtYd")
		)
		(fp_rect
			(start -0.508 0.9398)
			(end 0.508 -0.9398)
			(stroke
				(width 0)
				(type default)
			)
			(fill no)
			(layer "F.Fab")
		)
		(pad "1" smd custom
			(at 0 -0.4445)
			(size 0.1397 0.1397)
			(layers "F.Cu" "F.Mask" "F.Paste")
			(net "SW_PWR_R_HDD6")
			(options
				(clearance outline)
				(anchor circle)
			)
			(primitives
				(gr_poly
					(pts
						(arc
							(start -0.1778 -0.2794)
							(mid -0.249642 -0.249642)
							(end -0.2794 -0.1778)
						)
						(arc
							(start -0.2794 0.1778)
							(mid -0.249642 0.249642)
							(end -0.1778 0.2794)
						)
						(arc
							(start 0.1778 0.2794)
							(mid 0.249642 0.249642)
							(end 0.2794 0.1778)
						)
						(arc
							(start 0.2794 -0.1778)
							(mid 0.249642 -0.249642)
							(end 0.1778 -0.2794)
						)
					)
					(width 0)
					(fill yes)
				)
			)
		)
		(pad "2" smd custom
			(at 0 0.4445)
			(size 0.1397 0.1397)
			(layers "F.Cu" "F.Mask" "F.Paste")
			(net "GND")
			(options
				(clearance outline)
				(anchor circle)
			)
			(primitives
				(gr_poly
					(pts
						(arc
							(start -0.1778 -0.2794)
							(mid -0.249642 -0.249642)
							(end -0.2794 -0.1778)
						)
						(arc
							(start -0.2794 0.1778)
							(mid -0.249642 0.249642)
							(end -0.1778 0.2794)
						)
						(arc
							(start 0.1778 0.2794)
							(mid 0.249642 0.249642)
							(end 0.2794 0.1778)
						)
						(arc
							(start 0.2794 -0.1778)
							(mid 0.249642 -0.249642)
							(end 0.1778 -0.2794)
						)
					)
					(width 0)
					(fill yes)
				)
			)
		)
	)
	(footprint ""
		(layer "F.Cu")
		(at 383.8956 -31.6484 180)
		(property "Reference" "R806"
			(at 0 0 180)
			(layer "F.SilkS")
			(hide yes)
			(effects
				(font
					(size 1.27 1.27)
				)
			)
		)
		(property "Value" "10KR2F-2-GP"
			(at 0.064008 -3.993896 180)
			(unlocked yes)
			(layer "F.Fab")
			(hide yes)
			(effects
				(font
					(size 1.016 1.016)
					(thickness 0.1524)
				)
			)
		)
		(property "Device Type" "R402H16"
			(at 0.064008 -5.517896 180)
			(unlocked yes)
			(layer "F.Fab")
			(hide yes)
			(effects
				(font
					(size 1.016 1.016)
					(thickness 0.1524)
				)
			)
		)
		(duplicate_pad_numbers_are_jumpers no)
		(fp_line
			(start 0.508 -0.9398)
			(end -0.508 -0.9398)
			(stroke
				(width 0.1524)
				(type default)
			)
			(layer "F.SilkS")
		)
		(fp_line
			(start -0.508 -0.9398)
			(end -0.508 0.9398)
			(stroke
				(width 0.1524)
				(type default)
			)
			(layer "F.SilkS")
		)
		(fp_rect
			(start -0.508 0.9398)
			(end 0.508 -0.9398)
			(stroke
				(width 0)
				(type default)
			)
			(fill no)
			(layer "F.CrtYd")
		)
		(fp_rect
			(start -0.508 0.9398)
			(end 0.508 -0.9398)
			(stroke
				(width 0)
				(type default)
			)
			(fill no)
			(layer "F.Fab")
		)
		(pad "1" smd custom
			(at 0 -0.4445 180)
			(size 0.1397 0.1397)
			(layers "F.Cu" "F.Mask" "F.Paste")
			(net "P3V3_STBY_B")
			(options
				(clearance outline)
				(anchor circle)
			)
			(primitives
				(gr_poly
					(pts
						(arc
							(start -0.1778 -0.2794)
							(mid -0.249642 -0.249642)
							(end -0.2794 -0.1778)
						)
						(arc
							(start -0.2794 0.1778)
							(mid -0.249642 0.249642)
							(end -0.1778 0.2794)
						)
						(arc
							(start 0.1778 0.2794)
							(mid 0.249642 0.249642)
							(end 0.2794 0.1778)
						)
						(arc
							(start 0.2794 -0.1778)
							(mid 0.249642 -0.249642)
							(end 0.1778 -0.2794)
						)
					)
					(width 0)
					(fill yes)
				)
			)
		)
		(pad "2" smd custom
			(at 0 0.4445 180)
			(size 0.1397 0.1397)
			(layers "F.Cu" "F.Mask" "F.Paste")
			(net "HDD_PRSNT_32")
			(options
				(clearance outline)
				(anchor circle)
			)
			(primitives
				(gr_poly
					(pts
						(arc
							(start -0.1778 -0.2794)
							(mid -0.249642 -0.249642)
							(end -0.2794 -0.1778)
						)
						(arc
							(start -0.2794 0.1778)
							(mid -0.249642 0.249642)
							(end -0.1778 0.2794)
						)
						(arc
							(start 0.1778 0.2794)
							(mid 0.249642 0.249642)
							(end 0.2794 0.1778)
						)
						(arc
							(start 0.2794 -0.1778)
							(mid 0.249642 -0.249642)
							(end 0.1778 -0.2794)
						)
					)
					(width 0)
					(fill yes)
				)
			)
		)
	)
	(footprint ""
		(layer "F.Cu")
		(at 109.347 -35.687 -90)
		(property "Reference" "C385"
			(at 0 0 270)
			(layer "F.SilkS")
			(hide yes)
			(effects
				(font
					(size 1.27 1.27)
				)
			)
		)
		(property "Value" "SC4D7U25V5KX-1-GP"
			(at -0.0762 -6.1214 270)
			(unlocked yes)
			(layer "F.Fab")
			(hide yes)
			(effects
				(font
					(size 1.016 1.016)
					(thickness 0.1524)
				)
			)
		)
		(property "Device Type" "C805H58"
			(at -0.0762 -8.1534 270)
			(unlocked yes)
			(layer "F.Fab")
			(hide yes)
			(effects
				(font
					(size 1.016 1.016)
					(thickness 0.1524)
				)
			)
		)
		(duplicate_pad_numbers_are_jumpers no)
		(fp_line
			(start 0.635 0)
			(end -0.635 0)
			(stroke
				(width 0.508)
				(type default)
			)
			(layer "F.SilkS")
		)
		(fp_rect
			(start -0.9652 1.778)
			(end 0.9652 -1.778)
			(stroke
				(width 0)
				(type default)
			)
			(fill no)
			(layer "F.CrtYd")
		)
		(fp_poly
			(pts
				(xy -0.9652 -1.778) (xy 0.9652 -1.778) (xy 0.9652 1.778) (xy -0.9652 1.778)
			)
			(stroke
				(width 0)
				(type default)
			)
			(fill no)
			(layer "F.Fab")
		)
		(pad "1" smd rect
			(at 0 -0.9652 270)
			(size 1.397 1.143)
			(layers "F.Cu" "F.Mask" "F.Paste")
			(net "P12V_HDD27")
		)
		(pad "2" smd rect
			(at 0 0.9652 270)
			(size 1.397 1.143)
			(layers "F.Cu" "F.Mask" "F.Paste")
			(net "GND")
		)
	)
	(footprint ""
		(layer "F.Cu")
		(at 384.734562 -130.21945 -90)
		(property "Reference" "C288"
			(at 0 0 270)
			(layer "F.SilkS")
			(hide yes)
			(effects
				(font
					(size 1.27 1.27)
				)
			)
		)
		(property "Value" "SCD01U16V1KX-GP"
			(at -2.8321 -1.7399 270)
			(unlocked yes)
			(layer "F.Fab")
			(hide yes)
			(effects
				(font
					(size 1.016 1.016)
					(thickness 0.1524)
				)
			)
		)
		(property "Device Type" "C0201H13"
			(at -2.8321 -3.2639 270)
			(unlocked yes)
			(layer "F.Fab")
			(hide yes)
			(effects
				(font
					(size 1.016 1.016)
					(thickness 0.1524)
				)
			)
		)
		(duplicate_pad_numbers_are_jumpers no)
		(fp_rect
			(start -0.2794 0.6477)
			(end 0.2794 -0.6477)
			(stroke
				(width 0)
				(type default)
			)
			(fill no)
			(layer "F.CrtYd")
		)
		(fp_rect
			(start -0.2794 0.6477)
			(end 0.2794 -0.6477)
			(stroke
				(width 0)
				(type default)
			)
			(fill no)
			(layer "F.Fab")
		)
		(pad "1" smd custom
			(at 0 -0.2794 270)
			(size 0.0762 0.0762)
			(layers "F.Cu" "F.Mask" "F.Paste")
			(net "SAS_HDD_RX_N20")
			(options
				(clearance outline)
				(anchor circle)
			)
			(primitives
				(gr_poly
					(pts
						(arc
							(start 0.1524 -0.127)
							(mid 0.137521 -0.162921)
							(end 0.1016 -0.1778)
						)
						(arc
							(start -0.1016 -0.1778)
							(mid -0.137521 -0.162921)
							(end -0.1524 -0.127)
						)
						(arc
							(start -0.1524 0.127)
							(mid -0.137521 0.162921)
							(end -0.1016 0.1778)
						)
						(arc
							(start 0.1016 0.1778)
							(mid 0.137521 0.162921)
							(end 0.1524 0.127)
						)
					)
					(width 0)
					(fill yes)
				)
			)
		)
		(pad "2" smd custom
			(at 0 0.2794 270)
			(size 0.0762 0.0762)
			(layers "F.Cu" "F.Mask" "F.Paste")
			(net "PHY_SCC_B_TO_DRV_B_20_DN")
			(options
				(clearance outline)
				(anchor circle)
			)
			(primitives
				(gr_poly
					(pts
						(arc
							(start 0.1524 -0.127)
							(mid 0.137521 -0.162921)
							(end 0.1016 -0.1778)
						)
						(arc
							(start -0.1016 -0.1778)
							(mid -0.137521 -0.162921)
							(end -0.1524 -0.127)
						)
						(arc
							(start -0.1524 0.127)
							(mid -0.137521 0.162921)
							(end -0.1016 0.1778)
						)
						(arc
							(start 0.1016 0.1778)
							(mid 0.137521 0.162921)
							(end 0.1524 0.127)
						)
					)
					(width 0)
					(fill yes)
				)
			)
		)
	)
	(footprint ""
		(layer "F.Cu")
		(at 129.921 -147.066 90)
		(property "Reference" "C232"
			(at 0 0 90)
			(layer "F.SilkS")
			(hide yes)
			(effects
				(font
					(size 1.27 1.27)
				)
			)
		)
		(property "Value" "SCD01U50V2KX-1GP"
			(at 1.1811 -2.7051 90)
			(unlocked yes)
			(layer "F.Fab")
			(hide yes)
			(effects
				(font
					(size 1.016 1.016)
					(thickness 0.1524)
				)
			)
		)
		(property "Device Type" "C402H22"
			(at 1.1811 -4.2291 90)
			(unlocked yes)
			(layer "F.Fab")
			(hide yes)
			(effects
				(font
					(size 1.016 1.016)
					(thickness 0.1524)
				)
			)
		)
		(duplicate_pad_numbers_are_jumpers no)
		(fp_rect
			(start -0.4318 0.9525)
			(end 0.4318 -0.9525)
			(stroke
				(width 0)
				(type default)
			)
			(fill no)
			(layer "F.CrtYd")
		)
		(fp_rect
			(start -0.4318 0.9525)
			(end 0.4318 -0.9525)
			(stroke
				(width 0)
				(type default)
			)
			(fill no)
			(layer "F.Fab")
		)
		(pad "1" smd custom
			(at 0 -0.4445 90)
			(size 0.1524 0.1524)
			(layers "F.Cu" "F.Mask" "F.Paste")
			(net "HDD_PRSNT_15")
			(options
				(clearance outline)
				(anchor circle)
			)
			(primitives
				(gr_poly
					(pts
						(arc
							(start 0.3048 -0.2032)
							(mid 0.275042 -0.275042)
							(end 0.2032 -0.3048)
						)
						(arc
							(start -0.2032 -0.3048)
							(mid -0.275042 -0.275042)
							(end -0.3048 -0.2032)
						)
						(arc
							(start -0.3048 0.2032)
							(mid -0.275042 0.275042)
							(end -0.2032 0.3048)
						)
						(arc
							(start 0.2032 0.3048)
							(mid 0.275042 0.275042)
							(end 0.3048 0.2032)
						)
					)
					(width 0)
					(fill yes)
				)
			)
		)
		(pad "2" smd custom
			(at 0 0.4445 90)
			(size 0.1524 0.1524)
			(layers "F.Cu" "F.Mask" "F.Paste")
			(net "GND")
			(options
				(clearance outline)
				(anchor circle)
			)
			(primitives
				(gr_poly
					(pts
						(arc
							(start 0.3048 -0.2032)
							(mid 0.275042 -0.275042)
							(end 0.2032 -0.3048)
						)
						(arc
							(start -0.2032 -0.3048)
							(mid -0.275042 -0.275042)
							(end -0.3048 -0.2032)
						)
						(arc
							(start -0.3048 0.2032)
							(mid -0.275042 0.275042)
							(end -0.2032 0.3048)
						)
						(arc
							(start 0.2032 0.3048)
							(mid 0.275042 0.275042)
							(end 0.3048 0.2032)
						)
					)
					(width 0)
					(fill yes)
				)
			)
		)
	)
	(footprint ""
		(layer "F.Cu")
		(at 178.099974 -377.219972 180)
		(property "Reference" "FLED2"
			(at 0 0 180)
			(layer "F.SilkS")
			(hide yes)
			(effects
				(font
					(size 1.27 1.27)
				)
			)
		)
		(property "Value" "LED-BY-14-GP"
			(at -4.7752 -2.1844 180)
			(unlocked yes)
			(layer "F.Fab")
			(hide yes)
			(effects
				(font
					(size 1.016 1.016)
					(thickness 0.1524)
				)
			)
		)
		(property "Device Type" "LED-100-3PH206"
			(at -4.7752 -3.7084 180)
			(unlocked yes)
			(layer "F.Fab")
			(hide yes)
			(effects
				(font
					(size 1.016 1.016)
					(thickness 0.1524)
				)
			)
		)
		(duplicate_pad_numbers_are_jumpers no)
		(fp_line
			(start 3.7592 8.0264)
			(end -3.7592 8.0264)
			(stroke
				(width 0.1524)
				(type default)
			)
			(layer "F.SilkS")
		)
		(fp_line
			(start 3.7592 -1.524)
			(end 3.7592 8.0264)
			(stroke
				(width 0.1524)
				(type default)
			)
			(layer "F.SilkS")
		)
		(fp_line
			(start 1.87833 3.63474)
			(end 0.58293 2.33934)
			(stroke
				(width 0.1524)
				(type default)
			)
			(layer "F.SilkS")
		)
		(fp_line
			(start 1.87833 2.33934)
			(end 2.81813 2.33934)
			(stroke
				(width 0.1524)
				(type default)
			)
			(layer "F.SilkS")
		)
		(fp_line
			(start 1.87833 1.04394)
			(end 1.87833 3.63474)
			(stroke
				(width 0.1524)
				(type default)
			)
			(layer "F.SilkS")
		)
		(fp_line
			(start 0.58293 3.05054)
			(end 0.58293 1.42494)
			(stroke
				(width 0.1524)
				(type default)
			)
			(layer "F.SilkS")
		)
		(fp_line
			(start 0.58293 2.33934)
			(end 1.87833 1.04394)
			(stroke
				(width 0.1524)
				(type default)
			)
			(layer "F.SilkS")
		)
		(fp_line
			(start -0.45847 3.05054)
			(end -0.45847 1.42494)
			(stroke
				(width 0.1524)
				(type default)
			)
			(layer "F.SilkS")
		)
		(fp_line
			(start -0.45847 2.33934)
			(end 0.58293 2.33934)
			(stroke
				(width 0.1524)
				(type default)
			)
			(layer "F.SilkS")
		)
		(fp_line
			(start -0.45847 2.33934)
			(end -1.75387 1.04394)
			(stroke
				(width 0.1524)
				(type default)
			)
			(layer "F.SilkS")
		)
		(fp_line
			(start -1.75387 3.63474)
			(end -0.45847 2.33934)
			(stroke
				(width 0.1524)
				(type default)
			)
			(layer "F.SilkS")
		)
		(fp_line
			(start -1.75387 2.33934)
			(end -3.45567 2.33934)
			(stroke
				(width 0.1524)
				(type default)
			)
			(layer "F.SilkS")
		)
		(fp_line
			(start -1.75387 1.04394)
			(end -1.75387 3.63474)
			(stroke
				(width 0.1524)
				(type default)
			)
			(layer "F.SilkS")
		)
		(fp_line
			(start -3.7592 8.0264)
			(end -3.7592 -1.524)
			(stroke
				(width 0.1524)
				(type default)
			)
			(layer "F.SilkS")
		)
		(fp_line
			(start -3.7592 -1.524)
			(end 3.7592 -1.524)
			(stroke
				(width 0.1524)
				(type default)
			)
			(layer "F.SilkS")
		)
		(fp_circle
			(center 2.54 0)
			(end 1.5494 0)
			(stroke
				(width 0.3048)
				(type default)
			)
			(fill no)
			(layer "F.SilkS")
		)
		(fp_circle
			(center 0 0)
			(end -0.9906 0)
			(stroke
				(width 0.3048)
				(type default)
			)
			(fill no)
			(layer "F.SilkS")
		)
		(fp_circle
			(center -2.54 0)
			(end -3.5306 0)
			(stroke
				(width 0.3048)
				(type default)
			)
			(fill no)
			(layer "F.SilkS")
		)
		(fp_rect
			(start -3.5052 7.7724)
			(end 3.5052 -1.27)
			(stroke
				(width 0)
				(type default)
			)
			(fill no)
			(layer "F.CrtYd")
		)
		(fp_poly
			(pts
				(xy -4.0132 8.2804) (xy -4.0132 -1.778) (xy -3.5052 -1.778) (xy -3.5052 7.7724) (xy 3.5052 7.7724)
				(xy 3.5052 -1.27) (xy -3.50012 -1.27) (xy -3.50012 -1.778) (xy 4.0132 -1.778) (xy 4.0132 8.2804)
			)
			(stroke
				(width 0)
				(type default)
			)
			(fill no)
			(layer "F.CrtYd")
		)
		(fp_rect
			(start -4.0132 8.2804)
			(end 4.0132 -1.778)
			(stroke
				(width 0)
				(type default)
			)
			(fill no)
			(layer "F.Fab")
		)
		(pad "1" thru_hole circle
			(at -2.54 0 180)
			(size 1.27 1.27)
			(drill 0.889)
			(layers "*.Cu" "*.Mask")
			(remove_unused_layers no)
			(net "FAN_LED_BLUE1")
			(clearance 0.1651)
			(thermal_gap 0.1651)
		)
		(pad "2" thru_hole circle
			(at 0 0 180)
			(size 1.27 1.27)
			(drill 0.889)
			(layers "*.Cu" "*.Mask")
			(remove_unused_layers no)
			(net "GND")
			(clearance 0.1651)
			(thermal_gap 0.1651)
		)
		(pad "3" thru_hole circle
			(at 2.54 0 180)
			(size 1.27 1.27)
			(drill 0.889)
			(layers "*.Cu" "*.Mask")
			(remove_unused_layers no)
			(net "FAN_LED_YELLOW_1")
			(clearance 0.1651)
			(thermal_gap 0.1651)
		)
	)
	(footprint ""
		(layer "F.Cu")
		(at 321.634612 -15.219426 -90)
		(property "Reference" "C418"
			(at 0 0 270)
			(layer "F.SilkS")
			(hide yes)
			(effects
				(font
					(size 1.27 1.27)
				)
			)
		)
		(property "Value" "SCD01U16V1KX-GP"
			(at -2.8321 -1.7399 270)
			(unlocked yes)
			(layer "F.Fab")
			(hide yes)
			(effects
				(font
					(size 1.016 1.016)
					(thickness 0.1524)
				)
			)
		)
		(property "Device Type" "C0201H13"
			(at -2.8321 -3.2639 270)
			(unlocked yes)
			(layer "F.Fab")
			(hide yes)
			(effects
				(font
					(size 1.016 1.016)
					(thickness 0.1524)
				)
			)
		)
		(duplicate_pad_numbers_are_jumpers no)
		(fp_rect
			(start -0.2794 0.6477)
			(end 0.2794 -0.6477)
			(stroke
				(width 0)
				(type default)
			)
			(fill no)
			(layer "F.CrtYd")
		)
		(fp_rect
			(start -0.2794 0.6477)
			(end 0.2794 -0.6477)
			(stroke
				(width 0)
				(type default)
			)
			(fill no)
			(layer "F.Fab")
		)
		(pad "1" smd custom
			(at 0 -0.2794 270)
			(size 0.0762 0.0762)
			(layers "F.Cu" "F.Mask" "F.Paste")
			(net "SAS_HDD_RX_N30")
			(options
				(clearance outline)
				(anchor circle)
			)
			(primitives
				(gr_poly
					(pts
						(arc
							(start 0.1524 -0.127)
							(mid 0.137521 -0.162921)
							(end 0.1016 -0.1778)
						)
						(arc
							(start -0.1016 -0.1778)
							(mid -0.137521 -0.162921)
							(end -0.1524 -0.127)
						)
						(arc
							(start -0.1524 0.127)
							(mid -0.137521 0.162921)
							(end -0.1016 0.1778)
						)
						(arc
							(start 0.1016 0.1778)
							(mid 0.137521 0.162921)
							(end 0.1524 0.127)
						)
					)
					(width 0)
					(fill yes)
				)
			)
		)
		(pad "2" smd custom
			(at 0 0.2794 270)
			(size 0.0762 0.0762)
			(layers "F.Cu" "F.Mask" "F.Paste")
			(net "PHY_SCC_B_TO_DRV_B_30_DN")
			(options
				(clearance outline)
				(anchor circle)
			)
			(primitives
				(gr_poly
					(pts
						(arc
							(start 0.1524 -0.127)
							(mid 0.137521 -0.162921)
							(end 0.1016 -0.1778)
						)
						(arc
							(start -0.1016 -0.1778)
							(mid -0.137521 -0.162921)
							(end -0.1524 -0.127)
						)
						(arc
							(start -0.1524 0.127)
							(mid -0.137521 0.162921)
							(end -0.1016 0.1778)
						)
						(arc
							(start 0.1016 0.1778)
							(mid 0.137521 0.162921)
							(end 0.1524 0.127)
						)
					)
					(width 0)
					(fill yes)
				)
			)
		)
	)
	(footprint ""
		(layer "F.Cu")
		(at 261.117334 -211.051902 90)
		(property "Reference" "R1295"
			(at 0 0 90)
			(layer "F.SilkS")
			(hide yes)
			(effects
				(font
					(size 1.27 1.27)
				)
			)
		)
		(property "Value" "1KR2J-1-GP"
			(at 0.064008 -3.993896 90)
			(unlocked yes)
			(layer "F.Fab")
			(hide yes)
			(effects
				(font
					(size 1.016 1.016)
					(thickness 0.1524)
				)
			)
		)
		(property "Device Type" "R402H16"
			(at 0.064008 -5.517896 90)
			(unlocked yes)
			(layer "F.Fab")
			(hide yes)
			(effects
				(font
					(size 1.016 1.016)
					(thickness 0.1524)
				)
			)
		)
		(duplicate_pad_numbers_are_jumpers no)
		(fp_line
			(start 0.508 -0.9398)
			(end -0.508 -0.9398)
			(stroke
				(width 0.1524)
				(type default)
			)
			(layer "F.SilkS")
		)
		(fp_line
			(start -0.508 -0.9398)
			(end -0.508 0.9398)
			(stroke
				(width 0.1524)
				(type default)
			)
			(layer "F.SilkS")
		)
		(fp_rect
			(start -0.508 0.9398)
			(end 0.508 -0.9398)
			(stroke
				(width 0)
				(type default)
			)
			(fill no)
			(layer "F.CrtYd")
		)
		(fp_rect
			(start -0.508 0.9398)
			(end 0.508 -0.9398)
			(stroke
				(width 0)
				(type default)
			)
			(fill no)
			(layer "F.Fab")
		)
		(pad "1" smd custom
			(at 0 -0.4445 90)
			(size 0.1397 0.1397)
			(layers "F.Cu" "F.Mask" "F.Paste")
			(net "P3V3_STBY_B")
			(options
				(clearance outline)
				(anchor circle)
			)
			(primitives
				(gr_poly
					(pts
						(arc
							(start -0.1778 -0.2794)
							(mid -0.249642 -0.249642)
							(end -0.2794 -0.1778)
						)
						(arc
							(start -0.2794 0.1778)
							(mid -0.249642 0.249642)
							(end -0.1778 0.2794)
						)
						(arc
							(start 0.1778 0.2794)
							(mid 0.249642 0.249642)
							(end 0.2794 0.1778)
						)
						(arc
							(start 0.2794 -0.1778)
							(mid 0.249642 -0.249642)
							(end 0.1778 -0.2794)
						)
					)
					(width 0)
					(fill yes)
				)
			)
		)
		(pad "2" smd custom
			(at 0 0.4445 90)
			(size 0.1397 0.1397)
			(layers "F.Cu" "F.Mask" "F.Paste")
			(net "I2C_DRIVE_B_PWR_SDA")
			(options
				(clearance outline)
				(anchor circle)
			)
			(primitives
				(gr_poly
					(pts
						(arc
							(start -0.1778 -0.2794)
							(mid -0.249642 -0.249642)
							(end -0.2794 -0.1778)
						)
						(arc
							(start -0.2794 0.1778)
							(mid -0.249642 0.249642)
							(end -0.1778 0.2794)
						)
						(arc
							(start 0.1778 0.2794)
							(mid 0.249642 0.249642)
							(end 0.2794 0.1778)
						)
						(arc
							(start 0.2794 -0.1778)
							(mid 0.249642 -0.249642)
							(end 0.1778 -0.2794)
						)
					)
					(width 0)
					(fill yes)
				)
			)
		)
	)
	(footprint ""
		(layer "F.Cu")
		(at 180.975 -369.189 -90)
		(property "Reference" "R992"
			(at 0 0 270)
			(layer "F.SilkS")
			(hide yes)
			(effects
				(font
					(size 1.27 1.27)
				)
			)
		)
		(property "Value" "0R2J-2-GP"
			(at 0.064008 -3.993896 270)
			(unlocked yes)
			(layer "F.Fab")
			(hide yes)
			(effects
				(font
					(size 1.016 1.016)
					(thickness 0.1524)
				)
			)
		)
		(property "Device Type" "R402H16"
			(at 0.064008 -5.517896 270)
			(unlocked yes)
			(layer "F.Fab")
			(hide yes)
			(effects
				(font
					(size 1.016 1.016)
					(thickness 0.1524)
				)
			)
		)
		(duplicate_pad_numbers_are_jumpers no)
		(fp_line
			(start -0.508 -0.9398)
			(end -0.508 0.9398)
			(stroke
				(width 0.1524)
				(type default)
			)
			(layer "F.SilkS")
		)
		(fp_line
			(start 0.508 -0.9398)
			(end -0.508 -0.9398)
			(stroke
				(width 0.1524)
				(type default)
			)
			(layer "F.SilkS")
		)
		(fp_rect
			(start -0.508 0.9398)
			(end 0.508 -0.9398)
			(stroke
				(width 0)
				(type default)
			)
			(fill no)
			(layer "F.CrtYd")
		)
		(fp_rect
			(start -0.508 0.9398)
			(end 0.508 -0.9398)
			(stroke
				(width 0)
				(type default)
			)
			(fill no)
			(layer "F.Fab")
		)
		(pad "1" smd custom
			(at 0 -0.4445 270)
			(size 0.1397 0.1397)
			(layers "F.Cu" "F.Mask" "F.Paste")
			(net "12V_HS_ENABLE")
			(options
				(clearance outline)
				(anchor circle)
			)
			(primitives
				(gr_poly
					(pts
						(arc
							(start -0.1778 -0.2794)
							(mid -0.249642 -0.249642)
							(end -0.2794 -0.1778)
						)
						(arc
							(start -0.2794 0.1778)
							(mid -0.249642 0.249642)
							(end -0.1778 0.2794)
						)
						(arc
							(start 0.1778 0.2794)
							(mid 0.249642 0.249642)
							(end 0.2794 0.1778)
						)
						(arc
							(start 0.2794 -0.1778)
							(mid 0.249642 -0.249642)
							(end 0.1778 -0.2794)
						)
					)
					(width 0)
					(fill yes)
				)
			)
		)
		(pad "2" smd custom
			(at 0 0.4445 270)
			(size 0.1397 0.1397)
			(layers "F.Cu" "F.Mask" "F.Paste")
			(net "MB0_HS_ENABLE")
			(options
				(clearance outline)
				(anchor circle)
			)
			(primitives
				(gr_poly
					(pts
						(arc
							(start -0.1778 -0.2794)
							(mid -0.249642 -0.249642)
							(end -0.2794 -0.1778)
						)
						(arc
							(start -0.2794 0.1778)
							(mid -0.249642 0.249642)
							(end -0.1778 0.2794)
						)
						(arc
							(start 0.1778 0.2794)
							(mid 0.249642 0.249642)
							(end 0.2794 0.1778)
						)
						(arc
							(start 0.2794 -0.1778)
							(mid 0.249642 -0.249642)
							(end 0.1778 -0.2794)
						)
					)
					(width 0)
					(fill yes)
				)
			)
		)
	)
	(footprint ""
		(layer "F.Cu")
		(at 469.9 -260.858)
		(property "Reference" "Q44"
			(at 0 0 0)
			(layer "F.SilkS")
			(hide yes)
			(effects
				(font
					(size 1.27 1.27)
				)
			)
		)
		(property "Value" "AO4407AL-GP"
			(at -3.707384 -1.5367 0)
			(unlocked yes)
			(layer "F.Fab")
			(hide yes)
			(effects
				(font
					(size 1.016 1.016)
					(thickness 0.1524)
				)
			)
		)
		(property "Device Type" "SOIC8H69"
			(at -3.707384 -3.0607 0)
			(unlocked yes)
			(layer "F.Fab")
			(hide yes)
			(effects
				(font
					(size 1.016 1.016)
					(thickness 0.1524)
				)
			)
		)
		(duplicate_pad_numbers_are_jumpers no)
		(fp_line
			(start -2.7432 -1.4224)
			(end -2.7432 1.4224)
			(stroke
				(width 0.1524)
				(type default)
			)
			(layer "F.SilkS")
		)
		(fp_line
			(start -2.7432 1.4224)
			(end -2.6416 1.4224)
			(stroke
				(width 0.1524)
				(type default)
			)
			(layer "F.SilkS")
		)
		(fp_line
			(start -2.7432 1.4224)
			(end 2.1336 1.4224)
			(stroke
				(width 0.1524)
				(type default)
			)
			(layer "F.SilkS")
		)
		(fp_line
			(start -2.7178 -0.508)
			(end -2.1844 -0.0508)
			(stroke
				(width 0.1524)
				(type default)
			)
			(layer "F.SilkS")
		)
		(fp_line
			(start -2.6289 3.4417)
			(end -2.6289 1.4732)
			(stroke
				(width 0.381)
				(type default)
			)
			(layer "F.SilkS")
		)
		(fp_line
			(start -2.1844 -0.0508)
			(end -2.7178 0.508)
			(stroke
				(width 0.1524)
				(type default)
			)
			(layer "F.SilkS")
		)
		(fp_line
			(start 2.1336 -1.4224)
			(end -2.7432 -1.4224)
			(stroke
				(width 0.1524)
				(type default)
			)
			(layer "F.SilkS")
		)
		(fp_line
			(start 2.1336 1.4224)
			(end 2.1336 -1.4224)
			(stroke
				(width 0.1524)
				(type default)
			)
			(layer "F.SilkS")
		)
		(fp_poly
			(pts
				(xy -2.2098 -1.4224) (xy -2.2098 1.4224) (xy 2.2098 1.4224) (xy 2.2098 -1.4224)
			)
			(stroke
				(width 0)
				(type default)
			)
			(fill yes)
			(layer "F.SilkS")
		)
		(fp_rect
			(start -2.450084 2.999994)
			(end 2.450084 -2.999994)
			(stroke
				(width 0)
				(type default)
			)
			(fill no)
			(layer "F.CrtYd")
		)
		(fp_poly
			(pts
				(xy -2.8194 3.6322) (xy -2.8194 -3.6322) (xy 2.8194 -3.6322) (xy 2.8194 1.18364) (xy 2.450084 1.18364)
				(xy 2.450084 -2.999994) (xy -2.450084 -2.999994) (xy -2.450084 2.999994) (xy 2.450084 2.999994)
				(xy 2.450084 1.18618) (xy 2.8194 1.18618) (xy 2.8194 3.6322)
			)
			(stroke
				(width 0)
				(type default)
			)
			(fill no)
			(layer "F.CrtYd")
		)
		(fp_rect
			(start -2.8194 3.6322)
			(end 2.8194 -3.6322)
			(stroke
				(width 0)
				(type default)
			)
			(fill no)
			(layer "F.Fab")
		)
		(pad "1" smd rect
			(at -1.905 2.54)
			(size 0.635 1.651)
			(layers "F.Cu" "F.Mask" "F.Paste")
			(net "P12V_B")
		)
		(pad "2" smd rect
			(at -0.635 2.54)
			(size 0.635 1.651)
			(layers "F.Cu" "F.Mask" "F.Paste")
			(net "P12V_B")
		)
		(pad "3" smd rect
			(at 0.635 2.54)
			(size 0.635 1.651)
			(layers "F.Cu" "F.Mask" "F.Paste")
			(net "P12V_B")
		)
		(pad "4" smd rect
			(at 1.905 2.54)
			(size 0.635 1.651)
			(layers "F.Cu" "F.Mask" "F.Paste")
			(net "SW_HDD_N11")
		)
		(pad "5" smd rect
			(at 1.905 -2.54)
			(size 0.635 1.651)
			(layers "F.Cu" "F.Mask" "F.Paste")
			(net "P12V_HDD11")
		)
		(pad "6" smd rect
			(at 0.635 -2.54)
			(size 0.635 1.651)
			(layers "F.Cu" "F.Mask" "F.Paste")
			(net "P12V_HDD11")
		)
		(pad "7" smd rect
			(at -0.635 -2.54)
			(size 0.635 1.651)
			(layers "F.Cu" "F.Mask" "F.Paste")
			(net "P12V_HDD11")
		)
		(pad "8" smd rect
			(at -1.905 -2.54)
			(size 0.635 1.651)
			(layers "F.Cu" "F.Mask" "F.Paste")
			(net "P12V_HDD11")
		)
	)
	(footprint ""
		(layer "F.Cu")
		(at 431.927 -248.793 90)
		(property "Reference" "D9"
			(at 0 0 90)
			(layer "F.SilkS")
			(hide yes)
			(effects
				(font
					(size 1.27 1.27)
				)
			)
		)
		(property "Value" "RB551V30-GP"
			(at 0 -6.7818 90)
			(unlocked yes)
			(layer "F.Fab")
			(hide yes)
			(effects
				(font
					(size 1.016 1.016)
					(thickness 0.1524)
				)
			)
		)
		(property "Device Type" "SOD323AKH38"
			(at 0 -8.6868 90)
			(unlocked yes)
			(layer "F.Fab")
			(hide yes)
			(effects
				(font
					(size 1.016 1.016)
					(thickness 0.1524)
				)
			)
		)
		(duplicate_pad_numbers_are_jumpers no)
		(fp_line
			(start 0.889 -1.9304)
			(end 0.889 2.159)
			(stroke
				(width 0.1524)
				(type default)
			)
			(layer "F.SilkS")
		)
		(fp_line
			(start -0.889 -1.9304)
			(end 0.889 -1.9304)
			(stroke
				(width 0.1524)
				(type default)
			)
			(layer "F.SilkS")
		)
		(fp_line
			(start 0.762 2.0574)
			(end -0.762 2.0574)
			(stroke
				(width 0.508)
				(type default)
			)
			(layer "F.SilkS")
		)
		(fp_line
			(start 0.889 2.159)
			(end -0.889 2.159)
			(stroke
				(width 0.1524)
				(type default)
			)
			(layer "F.SilkS")
		)
		(fp_line
			(start -0.889 2.159)
			(end -0.889 -1.9304)
			(stroke
				(width 0.1524)
				(type default)
			)
			(layer "F.SilkS")
		)
		(fp_rect
			(start -1.016 2.3114)
			(end 1.016 -2.0066)
			(stroke
				(width 0)
				(type default)
			)
			(fill no)
			(layer "F.CrtYd")
		)
		(fp_poly
			(pts
				(xy -1.016 -2.0066) (xy 1.016 -2.0066) (xy 1.016 2.3114) (xy -1.016 2.3114)
			)
			(stroke
				(width 0)
				(type default)
			)
			(fill no)
			(layer "F.Fab")
		)
		(pad "A" smd rect
			(at 0 -1.143 90)
			(size 0.5588 1.016)
			(layers "F.Cu" "F.Mask" "F.Paste")
			(net "SW_HDD_R9")
		)
		(pad "K" smd rect
			(at 0 1.143 90)
			(size 0.5588 1.016)
			(layers "F.Cu" "F.Mask" "F.Paste")
			(net "SW_HDD_N9")
		)
	)
	(footprint ""
		(layer "F.Cu")
		(at 22.9362 -133.4262 -90)
		(property "Reference" "R356"
			(at 0 0 270)
			(layer "F.SilkS")
			(hide yes)
			(effects
				(font
					(size 1.27 1.27)
				)
			)
		)
		(property "Value" "1KR2F-3-GP"
			(at 0.064008 -3.993896 270)
			(unlocked yes)
			(layer "F.Fab")
			(hide yes)
			(effects
				(font
					(size 1.016 1.016)
					(thickness 0.1524)
				)
			)
		)
		(property "Device Type" "R402H16"
			(at 0.064008 -5.517896 270)
			(unlocked yes)
			(layer "F.Fab")
			(hide yes)
			(effects
				(font
					(size 1.016 1.016)
					(thickness 0.1524)
				)
			)
		)
		(duplicate_pad_numbers_are_jumpers no)
		(fp_line
			(start -0.508 -0.9398)
			(end -0.508 0.9398)
			(stroke
				(width 0.1524)
				(type default)
			)
			(layer "F.SilkS")
		)
		(fp_line
			(start 0.508 -0.9398)
			(end -0.508 -0.9398)
			(stroke
				(width 0.1524)
				(type default)
			)
			(layer "F.SilkS")
		)
		(fp_rect
			(start -0.508 0.9398)
			(end 0.508 -0.9398)
			(stroke
				(width 0)
				(type default)
			)
			(fill no)
			(layer "F.CrtYd")
		)
		(fp_rect
			(start -0.508 0.9398)
			(end 0.508 -0.9398)
			(stroke
				(width 0)
				(type default)
			)
			(fill no)
			(layer "F.Fab")
		)
		(pad "1" smd custom
			(at 0 -0.4445 270)
			(size 0.1397 0.1397)
			(layers "F.Cu" "F.Mask" "F.Paste")
			(net "P3V3_STBY_B")
			(options
				(clearance outline)
				(anchor circle)
			)
			(primitives
				(gr_poly
					(pts
						(arc
							(start -0.1778 -0.2794)
							(mid -0.249642 -0.249642)
							(end -0.2794 -0.1778)
						)
						(arc
							(start -0.2794 0.1778)
							(mid -0.249642 0.249642)
							(end -0.1778 0.2794)
						)
						(arc
							(start 0.1778 0.2794)
							(mid 0.249642 0.249642)
							(end 0.2794 0.1778)
						)
						(arc
							(start 0.2794 -0.1778)
							(mid 0.249642 -0.249642)
							(end 0.1778 -0.2794)
						)
					)
					(width 0)
					(fill yes)
				)
			)
		)
		(pad "2" smd custom
			(at 0 0.4445 270)
			(size 0.1397 0.1397)
			(layers "F.Cu" "F.Mask" "F.Paste")
			(net "SW_PWR_R_HDD12")
			(options
				(clearance outline)
				(anchor circle)
			)
			(primitives
				(gr_poly
					(pts
						(arc
							(start -0.1778 -0.2794)
							(mid -0.249642 -0.249642)
							(end -0.2794 -0.1778)
						)
						(arc
							(start -0.2794 0.1778)
							(mid -0.249642 0.249642)
							(end -0.1778 0.2794)
						)
						(arc
							(start 0.1778 0.2794)
							(mid 0.249642 0.249642)
							(end 0.2794 0.1778)
						)
						(arc
							(start 0.2794 -0.1778)
							(mid 0.249642 -0.249642)
							(end 0.1778 -0.2794)
						)
					)
					(width 0)
					(fill yes)
				)
			)
		)
	)
	(footprint ""
		(layer "F.Cu")
		(at 48.26 -139.065 -90)
		(property "Reference" "C207"
			(at 0 0 270)
			(layer "F.SilkS")
			(hide yes)
			(effects
				(font
					(size 1.27 1.27)
				)
			)
		)
		(property "Value" "SCD033U25V2KX-GP"
			(at 1.1811 -2.7051 270)
			(unlocked yes)
			(layer "F.Fab")
			(hide yes)
			(effects
				(font
					(size 1.016 1.016)
					(thickness 0.1524)
				)
			)
		)
		(property "Device Type" "C402H22"
			(at 1.1811 -4.2291 270)
			(unlocked yes)
			(layer "F.Fab")
			(hide yes)
			(effects
				(font
					(size 1.016 1.016)
					(thickness 0.1524)
				)
			)
		)
		(duplicate_pad_numbers_are_jumpers no)
		(fp_rect
			(start -0.4318 0.9525)
			(end 0.4318 -0.9525)
			(stroke
				(width 0)
				(type default)
			)
			(fill no)
			(layer "F.CrtYd")
		)
		(fp_rect
			(start -0.4318 0.9525)
			(end 0.4318 -0.9525)
			(stroke
				(width 0)
				(type default)
			)
			(fill no)
			(layer "F.Fab")
		)
		(pad "1" smd custom
			(at 0 -0.4445 270)
			(size 0.1524 0.1524)
			(layers "F.Cu" "F.Mask" "F.Paste")
			(net "SW_HDD_P13")
			(options
				(clearance outline)
				(anchor circle)
			)
			(primitives
				(gr_poly
					(pts
						(arc
							(start 0.3048 -0.2032)
							(mid 0.275042 -0.275042)
							(end 0.2032 -0.3048)
						)
						(arc
							(start -0.2032 -0.3048)
							(mid -0.275042 -0.275042)
							(end -0.3048 -0.2032)
						)
						(arc
							(start -0.3048 0.2032)
							(mid -0.275042 0.275042)
							(end -0.2032 0.3048)
						)
						(arc
							(start 0.2032 0.3048)
							(mid 0.275042 0.275042)
							(end 0.3048 0.2032)
						)
					)
					(width 0)
					(fill yes)
				)
			)
		)
		(pad "2" smd custom
			(at 0 0.4445 270)
			(size 0.1524 0.1524)
			(layers "F.Cu" "F.Mask" "F.Paste")
			(net "GND")
			(options
				(clearance outline)
				(anchor circle)
			)
			(primitives
				(gr_poly
					(pts
						(arc
							(start 0.3048 -0.2032)
							(mid 0.275042 -0.275042)
							(end 0.2032 -0.3048)
						)
						(arc
							(start -0.2032 -0.3048)
							(mid -0.275042 -0.275042)
							(end -0.3048 -0.2032)
						)
						(arc
							(start -0.3048 0.2032)
							(mid -0.275042 0.275042)
							(end -0.2032 0.3048)
						)
						(arc
							(start 0.2032 0.3048)
							(mid 0.275042 0.275042)
							(end 0.3048 0.2032)
						)
					)
					(width 0)
					(fill yes)
				)
			)
		)
	)
	(footprint ""
		(layer "F.Cu")
		(at 184.277 -368.046 -90)
		(property "Reference" "R989"
			(at 0 0 270)
			(layer "F.SilkS")
			(hide yes)
			(effects
				(font
					(size 1.27 1.27)
				)
			)
		)
		(property "Value" "10KR2F-2-GP"
			(at 0.064008 -3.993896 270)
			(unlocked yes)
			(layer "F.Fab")
			(hide yes)
			(effects
				(font
					(size 1.016 1.016)
					(thickness 0.1524)
				)
			)
		)
		(property "Device Type" "R402H16"
			(at 0.064008 -5.517896 270)
			(unlocked yes)
			(layer "F.Fab")
			(hide yes)
			(effects
				(font
					(size 1.016 1.016)
					(thickness 0.1524)
				)
			)
		)
		(duplicate_pad_numbers_are_jumpers no)
		(fp_line
			(start -0.508 -0.9398)
			(end -0.508 0.9398)
			(stroke
				(width 0.1524)
				(type default)
			)
			(layer "F.SilkS")
		)
		(fp_line
			(start 0.508 -0.9398)
			(end -0.508 -0.9398)
			(stroke
				(width 0.1524)
				(type default)
			)
			(layer "F.SilkS")
		)
		(fp_rect
			(start -0.508 0.9398)
			(end 0.508 -0.9398)
			(stroke
				(width 0)
				(type default)
			)
			(fill no)
			(layer "F.CrtYd")
		)
		(fp_rect
			(start -0.508 0.9398)
			(end 0.508 -0.9398)
			(stroke
				(width 0)
				(type default)
			)
			(fill no)
			(layer "F.Fab")
		)
		(pad "1" smd custom
			(at 0 -0.4445 270)
			(size 0.1397 0.1397)
			(layers "F.Cu" "F.Mask" "F.Paste")
			(net "P12V_CLIP")
			(options
				(clearance outline)
				(anchor circle)
			)
			(primitives
				(gr_poly
					(pts
						(arc
							(start -0.1778 -0.2794)
							(mid -0.249642 -0.249642)
							(end -0.2794 -0.1778)
						)
						(arc
							(start -0.2794 0.1778)
							(mid -0.249642 0.249642)
							(end -0.1778 0.2794)
						)
						(arc
							(start 0.1778 0.2794)
							(mid 0.249642 0.249642)
							(end 0.2794 0.1778)
						)
						(arc
							(start 0.2794 -0.1778)
							(mid 0.249642 -0.249642)
							(end 0.1778 -0.2794)
						)
					)
					(width 0)
					(fill yes)
				)
			)
		)
		(pad "2" smd custom
			(at 0 0.4445 270)
			(size 0.1397 0.1397)
			(layers "F.Cu" "F.Mask" "F.Paste")
			(net "12V_HS_ENABLE")
			(options
				(clearance outline)
				(anchor circle)
			)
			(primitives
				(gr_poly
					(pts
						(arc
							(start -0.1778 -0.2794)
							(mid -0.249642 -0.249642)
							(end -0.2794 -0.1778)
						)
						(arc
							(start -0.2794 0.1778)
							(mid -0.249642 0.249642)
							(end -0.1778 0.2794)
						)
						(arc
							(start 0.1778 0.2794)
							(mid 0.249642 0.249642)
							(end 0.2794 0.1778)
						)
						(arc
							(start 0.2794 -0.1778)
							(mid 0.249642 -0.249642)
							(end 0.1778 -0.2794)
						)
					)
					(width 0)
					(fill yes)
				)
			)
		)
	)
	(footprint ""
		(layer "F.Cu")
		(at 34.285682 -129.99085 90)
		(property "Reference" "VIA25"
			(at 0 0 90)
			(layer "F.SilkS")
			(hide yes)
			(effects
				(font
					(size 1.27 1.27)
				)
			)
		)
		(property "Value" "100OHM-8L-2D36MM-L18-GP"
			(at 3.8989 0.5715 90)
			(unlocked yes)
			(layer "F.Fab")
			(hide yes)
			(effects
				(font
					(size 1.016 1.016)
					(thickness 0.1524)
				)
			)
		)
		(property "Device Type" "VIA-PCIE-4P-414097"
			(at 3.8989 -0.9525 90)
			(unlocked yes)
			(layer "F.Fab")
			(hide yes)
			(effects
				(font
					(size 1.016 1.016)
					(thickness 0.1524)
				)
			)
		)
		(duplicate_pad_numbers_are_jumpers no)
		(fp_rect
			(start -2.0701 0.4826)
			(end 2.0701 -0.4826)
			(stroke
				(width 0)
				(type default)
			)
			(fill no)
			(layer "F.CrtYd")
		)
		(fp_rect
			(start -2.0701 0.4826)
			(end 2.0701 -0.4826)
			(stroke
				(width 0)
				(type default)
			)
			(fill no)
			(layer "F.Fab")
		)
		(pad "1" thru_hole circle
			(at -1.5875 0 90)
			(size 0.508 0.508)
			(drill 0.254)
			(layers "*.Cu" "*.Mask")
			(remove_unused_layers no)
			(net "GND")
			(clearance 0.2286)
			(thermal_gap 0.2286)
		)
		(pad "2" thru_hole circle
			(at -0.5715 0 90)
			(size 0.508 0.508)
			(drill 0.254)
			(layers "*.Cu" "*.Mask")
			(remove_unused_layers no)
			(net "PHY_SCC_B_TO_DRV_B_12_DP")
			(clearance 0.2286)
			(thermal_gap 0.2286)
		)
		(pad "3" thru_hole circle
			(at 0.5715 0 90)
			(size 0.508 0.508)
			(drill 0.254)
			(layers "*.Cu" "*.Mask")
			(remove_unused_layers no)
			(net "PHY_SCC_B_TO_DRV_B_12_DN")
			(clearance 0.2286)
			(thermal_gap 0.2286)
		)
		(pad "4" thru_hole circle
			(at 1.5875 0 90)
			(size 0.508 0.508)
			(drill 0.254)
			(layers "*.Cu" "*.Mask")
			(remove_unused_layers no)
			(net "GND")
			(clearance 0.2286)
			(thermal_gap 0.2286)
		)
	)
	(footprint ""
		(layer "F.Cu")
		(at 248.30278 -211.690712)
		(property "Reference" "R109"
			(at 0 0 0)
			(layer "F.SilkS")
			(hide yes)
			(effects
				(font
					(size 1.27 1.27)
				)
			)
		)
		(property "Value" "0R2J-2-GP"
			(at 0.064008 -3.993896 0)
			(unlocked yes)
			(layer "F.Fab")
			(hide yes)
			(effects
				(font
					(size 1.016 1.016)
					(thickness 0.1524)
				)
			)
		)
		(property "Device Type" "R402H16"
			(at 0.064008 -5.517896 0)
			(unlocked yes)
			(layer "F.Fab")
			(hide yes)
			(effects
				(font
					(size 1.016 1.016)
					(thickness 0.1524)
				)
			)
		)
		(duplicate_pad_numbers_are_jumpers no)
		(fp_line
			(start -0.508 -0.9398)
			(end -0.508 0.9398)
			(stroke
				(width 0.1524)
				(type default)
			)
			(layer "F.SilkS")
		)
		(fp_line
			(start 0.508 -0.9398)
			(end -0.508 -0.9398)
			(stroke
				(width 0.1524)
				(type default)
			)
			(layer "F.SilkS")
		)
		(fp_rect
			(start -0.508 0.9398)
			(end 0.508 -0.9398)
			(stroke
				(width 0)
				(type default)
			)
			(fill no)
			(layer "F.CrtYd")
		)
		(fp_rect
			(start -0.508 0.9398)
			(end 0.508 -0.9398)
			(stroke
				(width 0)
				(type default)
			)
			(fill no)
			(layer "F.Fab")
		)
		(pad "1" smd custom
			(at 0 -0.4445)
			(size 0.1397 0.1397)
			(layers "F.Cu" "F.Mask" "F.Paste")
			(net "EEPROM_SCL")
			(options
				(clearance outline)
				(anchor circle)
			)
			(primitives
				(gr_poly
					(pts
						(arc
							(start -0.1778 -0.2794)
							(mid -0.249642 -0.249642)
							(end -0.2794 -0.1778)
						)
						(arc
							(start -0.2794 0.1778)
							(mid -0.249642 0.249642)
							(end -0.1778 0.2794)
						)
						(arc
							(start 0.1778 0.2794)
							(mid 0.249642 0.249642)
							(end 0.2794 0.1778)
						)
						(arc
							(start 0.2794 -0.1778)
							(mid 0.249642 -0.249642)
							(end 0.1778 -0.2794)
						)
					)
					(width 0)
					(fill yes)
				)
			)
		)
		(pad "2" smd custom
			(at 0 0.4445)
			(size 0.1397 0.1397)
			(layers "F.Cu" "F.Mask" "F.Paste")
			(net "I2C_DPB_B_SCL_BUF")
			(options
				(clearance outline)
				(anchor circle)
			)
			(primitives
				(gr_poly
					(pts
						(arc
							(start -0.1778 -0.2794)
							(mid -0.249642 -0.249642)
							(end -0.2794 -0.1778)
						)
						(arc
							(start -0.2794 0.1778)
							(mid -0.249642 0.249642)
							(end -0.1778 0.2794)
						)
						(arc
							(start 0.1778 0.2794)
							(mid 0.249642 0.249642)
							(end 0.2794 0.1778)
						)
						(arc
							(start 0.2794 -0.1778)
							(mid 0.249642 -0.249642)
							(end 0.1778 -0.2794)
						)
					)
					(width 0)
					(fill yes)
				)
			)
		)
	)
	(footprint ""
		(layer "F.Cu")
		(at 158.708852 -133.75005 -90)
		(property "Reference" "VIA34"
			(at 0 0 270)
			(layer "F.SilkS")
			(hide yes)
			(effects
				(font
					(size 1.27 1.27)
				)
			)
		)
		(property "Value" "100OHM-8L-2D36MM-L16-GP"
			(at -3.4036 -0.4572 270)
			(unlocked yes)
			(layer "F.Fab")
			(hide yes)
			(effects
				(font
					(size 1.016 1.016)
					(thickness 0.1524)
				)
			)
		)
		(property "Device Type" "VIA-PCIE-4P-427097"
			(at -3.4036 -1.9812 270)
			(unlocked yes)
			(layer "F.Fab")
			(hide yes)
			(effects
				(font
					(size 1.016 1.016)
					(thickness 0.1524)
				)
			)
		)
		(duplicate_pad_numbers_are_jumpers no)
		(fp_rect
			(start -2.1336 0.4826)
			(end 2.1336 -0.4826)
			(stroke
				(width 0)
				(type default)
			)
			(fill no)
			(layer "F.CrtYd")
		)
		(fp_rect
			(start -2.1336 0.4826)
			(end 2.1336 -0.4826)
			(stroke
				(width 0)
				(type default)
			)
			(fill no)
			(layer "F.Fab")
		)
		(pad "1" thru_hole circle
			(at -1.651 0 270)
			(size 0.508 0.508)
			(drill 0.254)
			(layers "*.Cu" "*.Mask")
			(remove_unused_layers no)
			(net "GND")
			(clearance 0.2286)
			(thermal_gap 0.2286)
		)
		(pad "2" thru_hole circle
			(at -0.635 0 270)
			(size 0.508 0.508)
			(drill 0.254)
			(layers "*.Cu" "*.Mask")
			(remove_unused_layers no)
			(net "PHY_DRV_B_TO_SCC_B_16_DP")
			(clearance 0.2286)
			(thermal_gap 0.2286)
		)
		(pad "3" thru_hole circle
			(at 0.635 0 270)
			(size 0.508 0.508)
			(drill 0.254)
			(layers "*.Cu" "*.Mask")
			(remove_unused_layers no)
			(net "PHY_DRV_B_TO_SCC_B_16_DN")
			(clearance 0.2286)
			(thermal_gap 0.2286)
		)
		(pad "4" thru_hole circle
			(at 1.651 0 270)
			(size 0.508 0.508)
			(drill 0.254)
			(layers "*.Cu" "*.Mask")
			(remove_unused_layers no)
			(net "GND")
			(clearance 0.2286)
			(thermal_gap 0.2286)
		)
	)
	(footprint ""
		(layer "F.Cu")
		(at 455.93 -275.336 180)
		(property "Reference" "C166"
			(at 0 0 180)
			(layer "F.SilkS")
			(hide yes)
			(effects
				(font
					(size 1.27 1.27)
				)
			)
		)
		(property "Value" "SC1U25V3KX-GP"
			(at 0 -2.8194 180)
			(unlocked yes)
			(layer "F.Fab")
			(hide yes)
			(effects
				(font
					(size 1.016 1.016)
					(thickness 0.1524)
				)
			)
		)
		(property "Device Type" "C603H36"
			(at 0 -4.3434 180)
			(unlocked yes)
			(layer "F.Fab")
			(hide yes)
			(effects
				(font
					(size 1.016 1.016)
					(thickness 0.1524)
				)
			)
		)
		(duplicate_pad_numbers_are_jumpers no)
		(fp_line
			(start 0.508 0)
			(end -0.508 0)
			(stroke
				(width 0.2032)
				(type default)
			)
			(layer "F.SilkS")
		)
		(fp_rect
			(start -0.5842 1.3335)
			(end 0.5842 -1.3335)
			(stroke
				(width 0)
				(type default)
			)
			(fill no)
			(layer "F.CrtYd")
		)
		(fp_rect
			(start -0.5842 1.3335)
			(end 0.5842 -1.3335)
			(stroke
				(width 0)
				(type default)
			)
			(fill no)
			(layer "F.Fab")
		)
		(pad "1" smd custom
			(at 0 -0.762 180)
			(size 0.2159 0.2159)
			(layers "F.Cu" "F.Mask" "F.Paste")
			(net "P12V_HDD10")
			(options
				(clearance outline)
				(anchor circle)
			)
			(primitives
				(gr_poly
					(pts
						(arc
							(start -0.3302 -0.4318)
							(mid -0.402042 -0.402042)
							(end -0.4318 -0.3302)
						)
						(arc
							(start -0.4318 0.3302)
							(mid -0.402042 0.402042)
							(end -0.3302 0.4318)
						)
						(arc
							(start 0.3302 0.4318)
							(mid 0.402042 0.402042)
							(end 0.4318 0.3302)
						)
						(arc
							(start 0.4318 -0.3302)
							(mid 0.402042 -0.402042)
							(end 0.3302 -0.4318)
						)
					)
					(width 0)
					(fill yes)
				)
			)
		)
		(pad "2" smd custom
			(at 0 0.762 180)
			(size 0.2159 0.2159)
			(layers "F.Cu" "F.Mask" "F.Paste")
			(net "GND")
			(options
				(clearance outline)
				(anchor circle)
			)
			(primitives
				(gr_poly
					(pts
						(arc
							(start -0.3302 -0.4318)
							(mid -0.402042 -0.402042)
							(end -0.4318 -0.3302)
						)
						(arc
							(start -0.4318 0.3302)
							(mid -0.402042 0.402042)
							(end -0.3302 0.4318)
						)
						(arc
							(start 0.3302 0.4318)
							(mid 0.402042 0.402042)
							(end 0.4318 0.3302)
						)
						(arc
							(start 0.4318 -0.3302)
							(mid 0.402042 -0.402042)
							(end 0.3302 -0.4318)
						)
					)
					(width 0)
					(fill yes)
				)
			)
		)
	)
	(footprint ""
		(layer "F.Cu")
		(at 167.7162 -372.872 90)
		(property "Reference" "R998"
			(at 0 0 90)
			(layer "F.SilkS")
			(hide yes)
			(effects
				(font
					(size 1.27 1.27)
				)
			)
		)
		(property "Value" "10R2F-L-GP"
			(at 0.064008 -3.993896 90)
			(unlocked yes)
			(layer "F.Fab")
			(hide yes)
			(effects
				(font
					(size 1.016 1.016)
					(thickness 0.1524)
				)
			)
		)
		(property "Device Type" "R402H14"
			(at 0.064008 -5.517896 90)
			(unlocked yes)
			(layer "F.Fab")
			(hide yes)
			(effects
				(font
					(size 1.016 1.016)
					(thickness 0.1524)
				)
			)
		)
		(duplicate_pad_numbers_are_jumpers no)
		(fp_line
			(start 0.508 -0.9398)
			(end -0.508 -0.9398)
			(stroke
				(width 0.1524)
				(type default)
			)
			(layer "F.SilkS")
		)
		(fp_line
			(start -0.508 -0.9398)
			(end -0.508 0.9398)
			(stroke
				(width 0.1524)
				(type default)
			)
			(layer "F.SilkS")
		)
		(fp_rect
			(start -0.508 0.9398)
			(end 0.508 -0.9398)
			(stroke
				(width 0)
				(type default)
			)
			(fill no)
			(layer "F.CrtYd")
		)
		(fp_rect
			(start -0.508 0.9398)
			(end 0.508 -0.9398)
			(stroke
				(width 0)
				(type default)
			)
			(fill no)
			(layer "F.Fab")
		)
		(pad "1" smd custom
			(at 0 -0.4445 90)
			(size 0.1397 0.1397)
			(layers "F.Cu" "F.Mask" "F.Paste")
			(net "MB0_CM_SENSE_R2_P")
			(options
				(clearance outline)
				(anchor circle)
			)
			(primitives
				(gr_poly
					(pts
						(arc
							(start -0.1778 -0.2794)
							(mid -0.249642 -0.249642)
							(end -0.2794 -0.1778)
						)
						(arc
							(start -0.2794 0.1778)
							(mid -0.249642 0.249642)
							(end -0.1778 0.2794)
						)
						(arc
							(start 0.1778 0.2794)
							(mid 0.249642 0.249642)
							(end 0.2794 0.1778)
						)
						(arc
							(start 0.2794 -0.1778)
							(mid 0.249642 -0.249642)
							(end 0.1778 -0.2794)
						)
					)
					(width 0)
					(fill yes)
				)
			)
		)
		(pad "2" smd custom
			(at 0 0.4445 90)
			(size 0.1397 0.1397)
			(layers "F.Cu" "F.Mask" "F.Paste")
			(net "MB0_CM_SENSE_P")
			(options
				(clearance outline)
				(anchor circle)
			)
			(primitives
				(gr_poly
					(pts
						(arc
							(start -0.1778 -0.2794)
							(mid -0.249642 -0.249642)
							(end -0.2794 -0.1778)
						)
						(arc
							(start -0.2794 0.1778)
							(mid -0.249642 0.249642)
							(end -0.1778 0.2794)
						)
						(arc
							(start 0.1778 0.2794)
							(mid 0.249642 0.249642)
							(end 0.2794 0.1778)
						)
						(arc
							(start 0.2794 -0.1778)
							(mid 0.249642 -0.249642)
							(end 0.1778 -0.2794)
						)
					)
					(width 0)
					(fill yes)
				)
			)
		)
	)
	(footprint ""
		(layer "F.Cu")
		(at 433.324 -142.875 -90)
		(property "Reference" "R568"
			(at 0 0 270)
			(layer "F.SilkS")
			(hide yes)
			(effects
				(font
					(size 1.27 1.27)
				)
			)
		)
		(property "Value" "300KR2F-GP"
			(at 0.064008 -3.993896 270)
			(unlocked yes)
			(layer "F.Fab")
			(hide yes)
			(effects
				(font
					(size 1.016 1.016)
					(thickness 0.1524)
				)
			)
		)
		(property "Device Type" "R402H16"
			(at 0.064008 -5.517896 270)
			(unlocked yes)
			(layer "F.Fab")
			(hide yes)
			(effects
				(font
					(size 1.016 1.016)
					(thickness 0.1524)
				)
			)
		)
		(duplicate_pad_numbers_are_jumpers no)
		(fp_line
			(start -0.508 -0.9398)
			(end -0.508 0.9398)
			(stroke
				(width 0.1524)
				(type default)
			)
			(layer "F.SilkS")
		)
		(fp_line
			(start 0.508 -0.9398)
			(end -0.508 -0.9398)
			(stroke
				(width 0.1524)
				(type default)
			)
			(layer "F.SilkS")
		)
		(fp_rect
			(start -0.508 0.9398)
			(end 0.508 -0.9398)
			(stroke
				(width 0)
				(type default)
			)
			(fill no)
			(layer "F.CrtYd")
		)
		(fp_rect
			(start -0.508 0.9398)
			(end 0.508 -0.9398)
			(stroke
				(width 0)
				(type default)
			)
			(fill no)
			(layer "F.Fab")
		)
		(pad "1" smd custom
			(at 0 -0.4445 270)
			(size 0.1397 0.1397)
			(layers "F.Cu" "F.Mask" "F.Paste")
			(net "SW_HDD_N21")
			(options
				(clearance outline)
				(anchor circle)
			)
			(primitives
				(gr_poly
					(pts
						(arc
							(start -0.1778 -0.2794)
							(mid -0.249642 -0.249642)
							(end -0.2794 -0.1778)
						)
						(arc
							(start -0.2794 0.1778)
							(mid -0.249642 0.249642)
							(end -0.1778 0.2794)
						)
						(arc
							(start 0.1778 0.2794)
							(mid 0.249642 0.249642)
							(end 0.2794 0.1778)
						)
						(arc
							(start 0.2794 -0.1778)
							(mid 0.249642 -0.249642)
							(end 0.1778 -0.2794)
						)
					)
					(width 0)
					(fill yes)
				)
			)
		)
		(pad "2" smd custom
			(at 0 0.4445 270)
			(size 0.1397 0.1397)
			(layers "F.Cu" "F.Mask" "F.Paste")
			(net "P12V_B")
			(options
				(clearance outline)
				(anchor circle)
			)
			(primitives
				(gr_poly
					(pts
						(arc
							(start -0.1778 -0.2794)
							(mid -0.249642 -0.249642)
							(end -0.2794 -0.1778)
						)
						(arc
							(start -0.2794 0.1778)
							(mid -0.249642 0.249642)
							(end -0.1778 0.2794)
						)
						(arc
							(start 0.1778 0.2794)
							(mid 0.249642 0.249642)
							(end 0.2794 0.1778)
						)
						(arc
							(start 0.2794 -0.1778)
							(mid 0.249642 -0.249642)
							(end 0.1778 -0.2794)
						)
					)
					(width 0)
					(fill yes)
				)
			)
		)
	)
	(footprint ""
		(layer "F.Cu")
		(at 241.462306 -139.380214)
		(property "Reference" "R463"
			(at 0 0 0)
			(layer "F.SilkS")
			(hide yes)
			(effects
				(font
					(size 1.27 1.27)
				)
			)
		)
		(property "Value" "0R2J-2-GP"
			(at 0.064008 -3.993896 0)
			(unlocked yes)
			(layer "F.Fab")
			(hide yes)
			(effects
				(font
					(size 1.016 1.016)
					(thickness 0.1524)
				)
			)
		)
		(property "Device Type" "R402H16"
			(at 0.064008 -5.517896 0)
			(unlocked yes)
			(layer "F.Fab")
			(hide yes)
			(effects
				(font
					(size 1.016 1.016)
					(thickness 0.1524)
				)
			)
		)
		(duplicate_pad_numbers_are_jumpers no)
		(fp_line
			(start -0.508 -0.9398)
			(end -0.508 0.9398)
			(stroke
				(width 0.1524)
				(type default)
			)
			(layer "F.SilkS")
		)
		(fp_line
			(start 0.508 -0.9398)
			(end -0.508 -0.9398)
			(stroke
				(width 0.1524)
				(type default)
			)
			(layer "F.SilkS")
		)
		(fp_rect
			(start -0.508 0.9398)
			(end 0.508 -0.9398)
			(stroke
				(width 0)
				(type default)
			)
			(fill no)
			(layer "F.CrtYd")
		)
		(fp_rect
			(start -0.508 0.9398)
			(end 0.508 -0.9398)
			(stroke
				(width 0)
				(type default)
			)
			(fill no)
			(layer "F.Fab")
		)
		(pad "1" smd custom
			(at 0 -0.4445)
			(size 0.1397 0.1397)
			(layers "F.Cu" "F.Mask" "F.Paste")
			(net "I2C_SCC_B_SCL_BUF")
			(options
				(clearance outline)
				(anchor circle)
			)
			(primitives
				(gr_poly
					(pts
						(arc
							(start -0.1778 -0.2794)
							(mid -0.249642 -0.249642)
							(end -0.2794 -0.1778)
						)
						(arc
							(start -0.2794 0.1778)
							(mid -0.249642 0.249642)
							(end -0.1778 0.2794)
						)
						(arc
							(start 0.1778 0.2794)
							(mid 0.249642 0.249642)
							(end 0.2794 0.1778)
						)
						(arc
							(start 0.2794 -0.1778)
							(mid 0.249642 -0.249642)
							(end 0.1778 -0.2794)
						)
					)
					(width 0)
					(fill yes)
				)
			)
		)
		(pad "2" smd custom
			(at 0 0.4445)
			(size 0.1397 0.1397)
			(layers "F.Cu" "F.Mask" "F.Paste")
			(net "I2C_SCC_B_SCL")
			(options
				(clearance outline)
				(anchor circle)
			)
			(primitives
				(gr_poly
					(pts
						(arc
							(start -0.1778 -0.2794)
							(mid -0.249642 -0.249642)
							(end -0.2794 -0.1778)
						)
						(arc
							(start -0.2794 0.1778)
							(mid -0.249642 0.249642)
							(end -0.1778 0.2794)
						)
						(arc
							(start 0.1778 0.2794)
							(mid 0.249642 0.249642)
							(end 0.2794 0.1778)
						)
						(arc
							(start 0.2794 -0.1778)
							(mid 0.249642 -0.249642)
							(end 0.1778 -0.2794)
						)
					)
					(width 0)
					(fill yes)
				)
			)
		)
	)
	(footprint ""
		(layer "F.Cu")
		(at 388.649972 -258.910074 -90)
		(property "Reference" "HDDSAS8"
			(at 0 0 270)
			(layer "F.SilkS")
			(hide yes)
			(effects
				(font
					(size 1.27 1.27)
				)
			)
		)
		(property "Value" "SKT-SAS15P-14P-45-GP"
			(at -20.7645 -8.9789 270)
			(unlocked yes)
			(layer "F.Fab")
			(hide yes)
			(effects
				(font
					(size 1.016 1.016)
					(thickness 0.1524)
				)
			)
		)
		(property "Device Type" "10120818-001C-TRLF"
			(at -20.7645 -10.5029 270)
			(unlocked yes)
			(layer "F.Fab")
			(hide yes)
			(effects
				(font
					(size 1.016 1.016)
					(thickness 0.1524)
				)
			)
		)
		(duplicate_pad_numbers_are_jumpers no)
		(fp_line
			(start 1.651 4.2926)
			(end 1.651 3.0099)
			(stroke
				(width 0.1524)
				(type default)
			)
			(layer "F.SilkS")
		)
		(fp_line
			(start 8.509 4.2926)
			(end 1.651 4.2926)
			(stroke
				(width 0.1524)
				(type default)
			)
			(layer "F.SilkS")
		)
		(fp_line
			(start -23.4188 3.0099)
			(end -23.4188 -3.2512)
			(stroke
				(width 0.1524)
				(type default)
			)
			(layer "F.SilkS")
		)
		(fp_line
			(start 1.651 3.0099)
			(end -23.4188 3.0099)
			(stroke
				(width 0.1524)
				(type default)
			)
			(layer "F.SilkS")
		)
		(fp_line
			(start 8.509 3.0099)
			(end 8.509 4.2926)
			(stroke
				(width 0.1524)
				(type default)
			)
			(layer "F.SilkS")
		)
		(fp_line
			(start 23.4188 3.0099)
			(end 8.509 3.0099)
			(stroke
				(width 0.1524)
				(type default)
			)
			(layer "F.SilkS")
		)
		(fp_line
			(start -23.4188 -3.2512)
			(end 23.4188 -3.2512)
			(stroke
				(width 0.1524)
				(type default)
			)
			(layer "F.SilkS")
		)
		(fp_line
			(start 23.4188 -3.2512)
			(end 23.4188 3.0099)
			(stroke
				(width 0.1524)
				(type default)
			)
			(layer "F.SilkS")
		)
		(fp_line
			(start 15.5067 -3.3401)
			(end 16.2687 -3.3401)
			(stroke
				(width 0.3302)
				(type default)
			)
			(layer "F.SilkS")
		)
		(fp_poly
			(pts
				(xy 15.868904 -3.230372) (xy 16.503904 -3.865372) (xy 15.233904 -3.865372)
			)
			(stroke
				(width 0)
				(type default)
			)
			(fill yes)
			(layer "F.SilkS")
		)
		(fp_poly
			(pts
				(xy -22.8727 -2.7559) (xy 22.8727 -2.7559) (xy 22.8727 2.7559) (xy 8.255 2.7559) (xy 8.255 3.5179)
				(xy 1.905 3.5179) (xy 1.905 2.7559) (xy -22.8727 2.7559)
			)
			(stroke
				(width 0)
				(type default)
			)
			(fill no)
			(layer "F.CrtYd")
		)
		(fp_poly
			(pts
				(xy 1.397 4.5466) (xy 1.397 3.2639) (xy -23.6728 3.2639) (xy -23.6728 -3.5052) (xy 23.6728 -3.5052)
				(xy 23.6728 -0.00635) (xy 22.8727 -0.00635) (xy 22.8727 -2.7559) (xy -22.8727 -2.7559) (xy -22.8727 2.7559)
				(xy 1.905 2.7559) (xy 1.905 3.5179) (xy 8.255 3.5179) (xy 8.255 2.7559) (xy 22.8727 2.7559) (xy 22.8727 0.00635)
				(xy 23.6728 0.00635) (xy 23.6728 3.2639) (xy 8.763 3.2639) (xy 8.763 4.5466)
			)
			(stroke
				(width 0)
				(type default)
			)
			(fill no)
			(layer "F.CrtYd")
		)
		(fp_poly
			(pts
				(xy 1.397 4.5466) (xy 1.397 3.2639) (xy -23.6728 3.2639) (xy -23.6728 -3.5052) (xy 23.6728 -3.5052)
				(xy 23.6728 3.2639) (xy 8.763 3.2639) (xy 8.763 4.5466)
			)
			(stroke
				(width 0)
				(type default)
			)
			(fill no)
			(layer "F.Fab")
		)
		(pad "" np_thru_hole circle
			(at -18.874994 0 270)
			(size 0.254 0.254)
			(drill 1.3462)
			(layers "*.Cu" "*.Mask")
			(clearance 0.9017)
			(thermal_gap 0.9017)
		)
		(pad "" np_thru_hole circle
			(at 18.874994 0 270)
			(size 0.254 0.254)
			(drill 0.9398)
			(layers "*.Cu" "*.Mask")
			(clearance 0.6985)
			(thermal_gap 0.6985)
		)
		(pad "G1" smd rect
			(at 21.874988 0 270)
			(size 2.5908 2.5908)
			(layers "F.Cu" "F.Mask" "F.Paste")
			(net "GND")
		)
		(pad "G2" smd rect
			(at -21.874988 0 270)
			(size 2.5908 2.5908)
			(layers "F.Cu" "F.Mask" "F.Paste")
			(net "GND")
		)
		(pad "P1" smd rect
			(at 1.905 -1.82499 270)
			(size 0.6096 2.3622)
			(layers "F.Cu" "F.Mask" "F.Paste")
			(net "Net_1589")
		)
		(pad "P2" smd rect
			(at 0.635 -1.82499 270)
			(size 0.6096 2.3622)
			(layers "F.Cu" "F.Mask" "F.Paste")
			(net "Net_1590")
		)
		(pad "P3" smd rect
			(at -0.635 -1.82499 270)
			(size 0.6096 2.3622)
			(layers "F.Cu" "F.Mask" "F.Paste")
			(net "Net_1591")
		)
		(pad "P4" smd rect
			(at -1.905 -1.82499 270)
			(size 0.6096 2.3622)
			(layers "F.Cu" "F.Mask" "F.Paste")
			(net "GND")
		)
		(pad "P5" smd rect
			(at -3.175 -1.82499 270)
			(size 0.6096 2.3622)
			(layers "F.Cu" "F.Mask" "F.Paste")
			(net "HDD_PRSNT_8")
		)
		(pad "P6" smd rect
			(at -4.445 -1.82499 270)
			(size 0.6096 2.3622)
			(layers "F.Cu" "F.Mask" "F.Paste")
			(net "GND")
		)
		(pad "P7" smd rect
			(at -5.715 -1.82499 270)
			(size 0.6096 2.3622)
			(layers "F.Cu" "F.Mask" "F.Paste")
			(net "5V_PRE_8")
		)
		(pad "P8" smd rect
			(at -6.985 -1.82499 270)
			(size 0.6096 2.3622)
			(layers "F.Cu" "F.Mask" "F.Paste")
			(net "P5V_HDD8")
		)
		(pad "P9" smd rect
			(at -8.255 -1.82499 270)
			(size 0.6096 2.3622)
			(layers "F.Cu" "F.Mask" "F.Paste")
			(net "P5V_HDD8")
		)
		(pad "P10" smd rect
			(at -9.525 -1.82499 270)
			(size 0.6096 2.3622)
			(layers "F.Cu" "F.Mask" "F.Paste")
			(net "GND")
		)
		(pad "P11" smd rect
			(at -10.795 -1.82499 270)
			(size 0.6096 2.3622)
			(layers "F.Cu" "F.Mask" "F.Paste")
			(net "ACT_HDD_8")
		)
		(pad "P12" smd rect
			(at -12.065 -1.82499 270)
			(size 0.6096 2.3622)
			(layers "F.Cu" "F.Mask" "F.Paste")
			(net "GND")
		)
		(pad "P13" smd rect
			(at -13.335 -1.82499 270)
			(size 0.6096 2.3622)
			(layers "F.Cu" "F.Mask" "F.Paste")
			(net "12V_PRE_8")
		)
		(pad "P14" smd rect
			(at -14.605 -1.82499 270)
			(size 0.6096 2.3622)
			(layers "F.Cu" "F.Mask" "F.Paste")
			(net "P12V_HDD8")
		)
		(pad "P15" smd rect
			(at -15.875 -1.82499 270)
			(size 0.6096 2.3622)
			(layers "F.Cu" "F.Mask" "F.Paste")
			(net "P12V_HDD8")
		)
		(pad "S1" smd rect
			(at 15.875 -1.82499 270)
			(size 0.6096 2.3622)
			(layers "F.Cu" "F.Mask" "F.Paste")
			(net "GND")
		)
		(pad "S2" smd rect
			(at 14.605 -1.82499 270)
			(size 0.6096 2.3622)
			(layers "F.Cu" "F.Mask" "F.Paste")
			(net "SAS_HDD_RX_P8")
		)
		(pad "S3" smd rect
			(at 13.335 -1.82499 270)
			(size 0.6096 2.3622)
			(layers "F.Cu" "F.Mask" "F.Paste")
			(net "SAS_HDD_RX_N8")
		)
		(pad "S4" smd rect
			(at 12.065 -1.82499 270)
			(size 0.6096 2.3622)
			(layers "F.Cu" "F.Mask" "F.Paste")
			(net "GND")
		)
		(pad "S5" smd rect
			(at 10.795 -1.82499 270)
			(size 0.6096 2.3622)
			(layers "F.Cu" "F.Mask" "F.Paste")
			(net "PHY_DRV_B_TO_SCC_B_8_DN")
		)
		(pad "S6" smd rect
			(at 9.525 -1.82499 270)
			(size 0.6096 2.3622)
			(layers "F.Cu" "F.Mask" "F.Paste")
			(net "PHY_DRV_B_TO_SCC_B_8_DP")
		)
		(pad "S7" smd rect
			(at 8.255 -1.82499 270)
			(size 0.6096 2.3622)
			(layers "F.Cu" "F.Mask" "F.Paste")
			(net "GND")
		)
		(pad "S8" smd rect
			(at 7.480046 2.845054 270)
			(size 0.508 2.3622)
			(layers "F.Cu" "F.Mask" "F.Paste")
			(net "GND")
		)
		(pad "S9" smd rect
			(at 6.679946 2.845054 270)
			(size 0.508 2.3622)
			(layers "F.Cu" "F.Mask" "F.Paste")
			(net "Net_466")
		)
		(pad "S10" smd rect
			(at 5.8801 2.845054 270)
			(size 0.508 2.3622)
			(layers "F.Cu" "F.Mask" "F.Paste")
			(net "Net_358")
		)
		(pad "S11" smd rect
			(at 5.08 2.845054 270)
			(size 0.508 2.3622)
			(layers "F.Cu" "F.Mask" "F.Paste")
			(net "GND")
		)
		(pad "S12" smd rect
			(at 4.2799 2.845054 270)
			(size 0.508 2.3622)
			(layers "F.Cu" "F.Mask" "F.Paste")
			(net "Net_394")
		)
		(pad "S13" smd rect
			(at 3.480054 2.845054 270)
			(size 0.508 2.3622)
			(layers "F.Cu" "F.Mask" "F.Paste")
			(net "Net_430")
		)
		(pad "S14" smd rect
			(at 2.679954 2.845054 270)
			(size 0.508 2.3622)
			(layers "F.Cu" "F.Mask" "F.Paste")
			(net "GND")
		)
		(zone
			(layer "F.Cu")
			(hatch none 0.5)
			(connect_pads
				(clearance 0)
			)
			(min_thickness 0.25)
			(keepout
				(tracks allowed)
				(vias not_allowed)
				(pads allowed)
				(copperpour not_allowed)
				(footprints allowed)
			)
			(placement
				(enabled no)
				(sheetname "")
			)
			(fill
				(thermal_gap 0.5)
				(thermal_bridge_width 0.5)
				(island_removal_mode 0)
			)
			(polygon
				(pts
					(xy 392.307572 -275.648674) (xy 385.233672 -275.648674) (xy 385.233672 -282.582874) (xy 386.338572 -282.582874)
					(xy 386.338572 -278.468074) (xy 390.961372 -278.468074) (xy 390.961372 -282.582874) (xy 392.307572 -282.582874)
				)
			)
		)
		(zone
			(layer "F.Cu")
			(hatch none 0.5)
			(connect_pads
				(clearance 0)
			)
			(min_thickness 0.25)
			(keepout
				(tracks not_allowed)
				(vias allowed)
				(pads allowed)
				(copperpour not_allowed)
				(footprints allowed)
			)
			(placement
				(enabled no)
				(sheetname "")
			)
			(fill
				(thermal_gap 0.5)
				(thermal_bridge_width 0.5)
				(island_removal_mode 0)
			)
			(polygon
				(pts
					(xy 392.307572 -275.648674) (xy 385.233672 -275.648674) (xy 385.233672 -282.582874) (xy 386.338572 -282.582874)
					(xy 386.338572 -278.468074) (xy 390.961372 -278.468074) (xy 390.961372 -282.582874) (xy 392.307572 -282.582874)
				)
			)
		)
		(zone
			(layer "F.Cu")
			(hatch none 0.5)
			(connect_pads
				(clearance 0)
			)
			(min_thickness 0.25)
			(keepout
				(tracks not_allowed)
				(vias allowed)
				(pads allowed)
				(copperpour not_allowed)
				(footprints allowed)
			)
			(placement
				(enabled no)
				(sheetname "")
			)
			(fill
				(thermal_gap 0.5)
				(thermal_bridge_width 0.5)
				(island_removal_mode 0)
			)
			(polygon
				(pts
					(xy 392.307572 -242.171474) (xy 385.233672 -242.171474) (xy 385.233672 -235.237274) (xy 386.338572 -235.237274)
					(xy 386.338572 -239.352074) (xy 390.961372 -239.352074) (xy 390.961372 -235.237274) (xy 392.307572 -235.237274)
				)
			)
		)
		(zone
			(layer "F.Cu")
			(hatch none 0.5)
			(connect_pads
				(clearance 0)
			)
			(min_thickness 0.25)
			(keepout
				(tracks allowed)
				(vias not_allowed)
				(pads allowed)
				(copperpour not_allowed)
				(footprints allowed)
			)
			(placement
				(enabled no)
				(sheetname "")
			)
			(fill
				(thermal_gap 0.5)
				(thermal_bridge_width 0.5)
				(island_removal_mode 0)
			)
			(polygon
				(pts
					(xy 392.307572 -242.171474) (xy 385.233672 -242.171474) (xy 385.233672 -235.237274) (xy 386.338572 -235.237274)
					(xy 386.338572 -239.352074) (xy 390.961372 -239.352074) (xy 390.961372 -235.237274) (xy 392.307572 -235.237274)
				)
			)
		)
		(zone
			(layers "F.Cu" "B.Cu" "In1.Cu" "In2.Cu" "In3.Cu" "In4.Cu" "In5.Cu" "In6.Cu")
			(hatch none 0.5)
			(connect_pads
				(clearance 0)
			)
			(min_thickness 0.25)
			(keepout
				(tracks not_allowed)
				(vias allowed)
				(pads allowed)
				(copperpour not_allowed)
				(footprints allowed)
			)
			(placement
				(enabled no)
				(sheetname "")
			)
			(fill
				(thermal_gap 0.5)
				(thermal_bridge_width 0.5)
				(island_removal_mode 0)
			)
			(polygon
				(pts
					(arc
						(start 389.424672 -240.03508)
						(mid 387.875272 -240.03508)
						(end 389.424672 -240.03508)
					)
				)
			)
		)
		(zone
			(layers "F.Cu" "B.Cu" "In1.Cu" "In2.Cu" "In3.Cu" "In4.Cu" "In5.Cu" "In6.Cu")
			(hatch none 0.5)
			(connect_pads
				(clearance 0)
			)
			(min_thickness 0.25)
			(keepout
				(tracks not_allowed)
				(vias allowed)
				(pads allowed)
				(copperpour not_allowed)
				(footprints allowed)
			)
			(placement
				(enabled no)
				(sheetname "")
			)
			(fill
				(thermal_gap 0.5)
				(thermal_bridge_width 0.5)
				(island_removal_mode 0)
			)
			(polygon
				(pts
					(arc
						(start 389.627872 -277.785068)
						(mid 387.672072 -277.785068)
						(end 389.627872 -277.785068)
					)
				)
			)
		)
	)
	(footprint ""
		(layer "F.Cu")
		(at 330.67498 -178.799998)
		(property "Reference" ""
			(at 0 0 0)
			(layer "F.SilkS")
			(hide yes)
			(effects
				(font
					(size 1.27 1.27)
				)
			)
		)
		(property "Value" "*"
			(at -8.398764 -8.057642 0)
			(unlocked yes)
			(layer "F.Fab")
			(hide yes)
			(effects
				(font
					(size 1.016 1.016)
					(thickness 0.1524)
				)
			)
		)
		(duplicate_pad_numbers_are_jumpers no)
		(fp_poly
			(pts
				(arc
					(start 7.3152 0)
					(mid 0 7.3152)
					(end -7.3152 0)
				)
				(arc
					(start -7.3152 -5.9944)
					(mid 0 -13.3096)
					(end 7.3152 -5.9944)
				)
			)
			(stroke
				(width 0)
				(type default)
			)
			(fill no)
			(layer "B.CrtYd")
		)
		(fp_poly
			(pts
				(arc
					(start 7.3152 0)
					(mid 0 7.3152)
					(end -7.3152 0)
				)
				(arc
					(start -7.3152 -5.9944)
					(mid 0 -13.3096)
					(end 7.3152 -5.9944)
				)
			)
			(stroke
				(width 0)
				(type default)
			)
			(fill no)
			(layer "F.CrtYd")
		)
		(fp_poly
			(pts
				(arc
					(start 7.3152 0)
					(mid 0 7.3152)
					(end -7.3152 0)
				)
				(arc
					(start -7.3152 -5.9944)
					(mid 0 -13.3096)
					(end 7.3152 -5.9944)
				)
			)
			(stroke
				(width 0)
				(type default)
			)
			(fill no)
			(layer "B.Fab")
		)
		(fp_poly
			(pts
				(arc
					(start 7.3152 0)
					(mid 0 7.3152)
					(end -7.3152 0)
				)
				(arc
					(start -7.3152 -5.9944)
					(mid 0 -13.3096)
					(end 7.3152 -5.9944)
				)
			)
			(stroke
				(width 0)
				(type default)
			)
			(fill no)
			(layer "F.Fab")
		)
		(pad "1" thru_hole oval
			(at 0 0)
			(size 14.0208 20.0152)
			(drill 0.0254
				(offset 0 -2.9972)
			)
			(layers "*.Cu" "*.Mask")
			(remove_unused_layers no)
			(net "Net_44")
			(clearance -1.002284)
			(thermal_gap 0.1524)
			(padstack
				(mode front_inner_back)
				(layer "Inner"
					(shape custom)
					(size 2.928012 2.928012)
					(options
						(anchor circle)
					)
					(primitives
						(gr_poly
							(pts
								(arc
									(start 4.571746 -2.084324)
									(mid 0.000333 7.430372)
									(end -4.571492 -2.084324)
								)
								(arc
									(start -4.571492 -2.084324)
									(mid -3.570296 -3.611977)
									(end -2.875026 -5.30098)
								)
								(arc
									(start -2.875026 -5.30098)
									(mid 0.000217 -7.43089)
									(end 2.87528 -5.30098)
								)
								(arc
									(start 2.87528 -5.30098)
									(mid 3.570511 -3.611956)
									(end 4.571746 -2.084324)
								)
							)
							(width 0)
							(fill yes)
						)
					)
					(clearance 0.1524)
				)
				(layer "B.Cu"
					(shape oval)
					(size 14.0208 20.0152)
					(offset 0 -2.9972)
					(clearance -1.002284)
				)
			)
		)
		(zone
			(layers "F.Cu" "B.Cu" "In1.Cu" "In2.Cu" "In3.Cu" "In4.Cu" "In5.Cu" "In6.Cu")
			(hatch none 0.5)
			(connect_pads
				(clearance 0)
			)
			(min_thickness 0.25)
			(keepout
				(tracks not_allowed)
				(vias allowed)
				(pads allowed)
				(copperpour not_allowed)
				(footprints allowed)
			)
			(placement
				(enabled no)
				(sheetname "")
			)
			(fill
				(thermal_gap 0.5)
				(thermal_bridge_width 0.5)
				(island_removal_mode 0)
			)
			(polygon
				(pts
					(arc
						(start 323.66458 -184.794398)
						(mid 330.67498 -191.804798)
						(end 337.68538 -184.794398)
					)
					(arc
						(start 337.68538 -178.799998)
						(mid 330.67498 -171.789598)
						(end 323.66458 -178.799998)
					)
				)
			)
		)
	)
	(footprint ""
		(layer "F.Cu")
		(at 384.9116 -261.6454)
		(property "Reference" "C141"
			(at 0 0 0)
			(layer "F.SilkS")
			(hide yes)
			(effects
				(font
					(size 1.27 1.27)
				)
			)
		)
		(property "Value" "SCD01U50V2KX-1GP"
			(at 1.1811 -2.7051 0)
			(unlocked yes)
			(layer "F.Fab")
			(hide yes)
			(effects
				(font
					(size 1.016 1.016)
					(thickness 0.1524)
				)
			)
		)
		(property "Device Type" "C402H22"
			(at 1.1811 -4.2291 0)
			(unlocked yes)
			(layer "F.Fab")
			(hide yes)
			(effects
				(font
					(size 1.016 1.016)
					(thickness 0.1524)
				)
			)
		)
		(duplicate_pad_numbers_are_jumpers no)
		(fp_rect
			(start -0.4318 0.9525)
			(end 0.4318 -0.9525)
			(stroke
				(width 0)
				(type default)
			)
			(fill no)
			(layer "F.CrtYd")
		)
		(fp_rect
			(start -0.4318 0.9525)
			(end 0.4318 -0.9525)
			(stroke
				(width 0)
				(type default)
			)
			(fill no)
			(layer "F.Fab")
		)
		(pad "1" smd custom
			(at 0 -0.4445)
			(size 0.1524 0.1524)
			(layers "F.Cu" "F.Mask" "F.Paste")
			(net "HDD_PRSNT_8")
			(options
				(clearance outline)
				(anchor circle)
			)
			(primitives
				(gr_poly
					(pts
						(arc
							(start 0.3048 -0.2032)
							(mid 0.275042 -0.275042)
							(end 0.2032 -0.3048)
						)
						(arc
							(start -0.2032 -0.3048)
							(mid -0.275042 -0.275042)
							(end -0.3048 -0.2032)
						)
						(arc
							(start -0.3048 0.2032)
							(mid -0.275042 0.275042)
							(end -0.2032 0.3048)
						)
						(arc
							(start 0.2032 0.3048)
							(mid 0.275042 0.275042)
							(end 0.3048 0.2032)
						)
					)
					(width 0)
					(fill yes)
				)
			)
		)
		(pad "2" smd custom
			(at 0 0.4445)
			(size 0.1524 0.1524)
			(layers "F.Cu" "F.Mask" "F.Paste")
			(net "GND")
			(options
				(clearance outline)
				(anchor circle)
			)
			(primitives
				(gr_poly
					(pts
						(arc
							(start 0.3048 -0.2032)
							(mid 0.275042 -0.275042)
							(end 0.2032 -0.3048)
						)
						(arc
							(start -0.2032 -0.3048)
							(mid -0.275042 -0.275042)
							(end -0.3048 -0.2032)
						)
						(arc
							(start -0.3048 0.2032)
							(mid -0.275042 0.275042)
							(end -0.2032 0.3048)
						)
						(arc
							(start 0.2032 0.3048)
							(mid 0.275042 0.275042)
							(end 0.3048 0.2032)
						)
					)
					(width 0)
					(fill yes)
				)
			)
		)
	)
	(footprint ""
		(layer "F.Cu")
		(at 335.788 -246.761 180)
		(property "Reference" "R267"
			(at 0 0 180)
			(layer "F.SilkS")
			(hide yes)
			(effects
				(font
					(size 1.27 1.27)
				)
			)
		)
		(property "Value" "0R2J-2-GP"
			(at 0.064008 -3.993896 180)
			(unlocked yes)
			(layer "F.Fab")
			(hide yes)
			(effects
				(font
					(size 1.016 1.016)
					(thickness 0.1524)
				)
			)
		)
		(property "Device Type" "R402H16"
			(at 0.064008 -5.517896 180)
			(unlocked yes)
			(layer "F.Fab")
			(hide yes)
			(effects
				(font
					(size 1.016 1.016)
					(thickness 0.1524)
				)
			)
		)
		(duplicate_pad_numbers_are_jumpers no)
		(fp_line
			(start 0.508 -0.9398)
			(end -0.508 -0.9398)
			(stroke
				(width 0.1524)
				(type default)
			)
			(layer "F.SilkS")
		)
		(fp_line
			(start -0.508 -0.9398)
			(end -0.508 0.9398)
			(stroke
				(width 0.1524)
				(type default)
			)
			(layer "F.SilkS")
		)
		(fp_rect
			(start -0.508 0.9398)
			(end 0.508 -0.9398)
			(stroke
				(width 0)
				(type default)
			)
			(fill no)
			(layer "F.CrtYd")
		)
		(fp_rect
			(start -0.508 0.9398)
			(end 0.508 -0.9398)
			(stroke
				(width 0)
				(type default)
			)
			(fill no)
			(layer "F.Fab")
		)
		(pad "1" smd custom
			(at 0 -0.4445 180)
			(size 0.1397 0.1397)
			(layers "F.Cu" "F.Mask" "F.Paste")
			(net "SW_HDD_G6")
			(options
				(clearance outline)
				(anchor circle)
			)
			(primitives
				(gr_poly
					(pts
						(arc
							(start -0.1778 -0.2794)
							(mid -0.249642 -0.249642)
							(end -0.2794 -0.1778)
						)
						(arc
							(start -0.2794 0.1778)
							(mid -0.249642 0.249642)
							(end -0.1778 0.2794)
						)
						(arc
							(start 0.1778 0.2794)
							(mid 0.249642 0.249642)
							(end 0.2794 0.1778)
						)
						(arc
							(start 0.2794 -0.1778)
							(mid 0.249642 -0.249642)
							(end 0.1778 -0.2794)
						)
					)
					(width 0)
					(fill yes)
				)
			)
		)
		(pad "2" smd custom
			(at 0 0.4445 180)
			(size 0.1397 0.1397)
			(layers "F.Cu" "F.Mask" "F.Paste")
			(net "SW_HDD_R6")
			(options
				(clearance outline)
				(anchor circle)
			)
			(primitives
				(gr_poly
					(pts
						(arc
							(start -0.1778 -0.2794)
							(mid -0.249642 -0.249642)
							(end -0.2794 -0.1778)
						)
						(arc
							(start -0.2794 0.1778)
							(mid -0.249642 0.249642)
							(end -0.1778 0.2794)
						)
						(arc
							(start 0.1778 0.2794)
							(mid 0.249642 0.249642)
							(end 0.2794 0.1778)
						)
						(arc
							(start 0.2794 -0.1778)
							(mid 0.249642 -0.249642)
							(end 0.1778 -0.2794)
						)
					)
					(width 0)
					(fill yes)
				)
			)
		)
	)
	(footprint ""
		(layer "F.Cu")
		(at 35.306 -147.066 90)
		(property "Reference" "C188"
			(at 0 0 90)
			(layer "F.SilkS")
			(hide yes)
			(effects
				(font
					(size 1.27 1.27)
				)
			)
		)
		(property "Value" "SCD01U50V2KX-1GP"
			(at 1.1811 -2.7051 90)
			(unlocked yes)
			(layer "F.Fab")
			(hide yes)
			(effects
				(font
					(size 1.016 1.016)
					(thickness 0.1524)
				)
			)
		)
		(property "Device Type" "C402H22"
			(at 1.1811 -4.2291 90)
			(unlocked yes)
			(layer "F.Fab")
			(hide yes)
			(effects
				(font
					(size 1.016 1.016)
					(thickness 0.1524)
				)
			)
		)
		(duplicate_pad_numbers_are_jumpers no)
		(fp_rect
			(start -0.4318 0.9525)
			(end 0.4318 -0.9525)
			(stroke
				(width 0)
				(type default)
			)
			(fill no)
			(layer "F.CrtYd")
		)
		(fp_rect
			(start -0.4318 0.9525)
			(end 0.4318 -0.9525)
			(stroke
				(width 0)
				(type default)
			)
			(fill no)
			(layer "F.Fab")
		)
		(pad "1" smd custom
			(at 0 -0.4445 90)
			(size 0.1524 0.1524)
			(layers "F.Cu" "F.Mask" "F.Paste")
			(net "HDD_PRSNT_12")
			(options
				(clearance outline)
				(anchor circle)
			)
			(primitives
				(gr_poly
					(pts
						(arc
							(start 0.3048 -0.2032)
							(mid 0.275042 -0.275042)
							(end 0.2032 -0.3048)
						)
						(arc
							(start -0.2032 -0.3048)
							(mid -0.275042 -0.275042)
							(end -0.3048 -0.2032)
						)
						(arc
							(start -0.3048 0.2032)
							(mid -0.275042 0.275042)
							(end -0.2032 0.3048)
						)
						(arc
							(start 0.2032 0.3048)
							(mid 0.275042 0.275042)
							(end 0.3048 0.2032)
						)
					)
					(width 0)
					(fill yes)
				)
			)
		)
		(pad "2" smd custom
			(at 0 0.4445 90)
			(size 0.1524 0.1524)
			(layers "F.Cu" "F.Mask" "F.Paste")
			(net "GND")
			(options
				(clearance outline)
				(anchor circle)
			)
			(primitives
				(gr_poly
					(pts
						(arc
							(start 0.3048 -0.2032)
							(mid 0.275042 -0.275042)
							(end 0.2032 -0.3048)
						)
						(arc
							(start -0.2032 -0.3048)
							(mid -0.275042 -0.275042)
							(end -0.3048 -0.2032)
						)
						(arc
							(start -0.3048 0.2032)
							(mid -0.275042 0.275042)
							(end -0.2032 0.3048)
						)
						(arc
							(start 0.2032 0.3048)
							(mid 0.275042 0.275042)
							(end 0.3048 0.2032)
						)
					)
					(width 0)
					(fill yes)
				)
			)
		)
	)
	(footprint ""
		(layer "F.Cu")
		(at 177.8 -146.939 -90)
		(property "Reference" "C252"
			(at 0 0 270)
			(layer "F.SilkS")
			(hide yes)
			(effects
				(font
					(size 1.27 1.27)
				)
			)
		)
		(property "Value" "SC10U16V6KX-2GP"
			(at -0.0762 -5.1308 270)
			(unlocked yes)
			(layer "F.Fab")
			(hide yes)
			(effects
				(font
					(size 1.016 1.016)
					(thickness 0.1524)
				)
			)
		)
		(property "Device Type" "C1206H71"
			(at -0.127 -6.6548 270)
			(unlocked yes)
			(layer "F.Fab")
			(hide yes)
			(effects
				(font
					(size 1.016 1.016)
					(thickness 0.1524)
				)
			)
		)
		(duplicate_pad_numbers_are_jumpers no)
		(fp_line
			(start -1.016 2.2352)
			(end -1.016 0.8382)
			(stroke
				(width 0.1524)
				(type default)
			)
			(layer "F.SilkS")
		)
		(fp_line
			(start 1.016 2.2352)
			(end -1.016 2.2352)
			(stroke
				(width 0.1524)
				(type default)
			)
			(layer "F.SilkS")
		)
		(fp_line
			(start 1.016 0.8382)
			(end 1.016 2.2352)
			(stroke
				(width 0.1524)
				(type default)
			)
			(layer "F.SilkS")
		)
		(fp_line
			(start -1.016 -0.8382)
			(end -1.016 -2.2352)
			(stroke
				(width 0.1524)
				(type default)
			)
			(layer "F.SilkS")
		)
		(fp_line
			(start -1.016 -2.2352)
			(end 1.016 -2.2352)
			(stroke
				(width 0.1524)
				(type default)
			)
			(layer "F.SilkS")
		)
		(fp_line
			(start 1.016 -2.2352)
			(end 1.016 -0.8382)
			(stroke
				(width 0.1524)
				(type default)
			)
			(layer "F.SilkS")
		)
		(fp_rect
			(start -1.0922 2.3114)
			(end 1.0922 -2.3114)
			(stroke
				(width 0)
				(type default)
			)
			(fill no)
			(layer "F.CrtYd")
		)
		(fp_poly
			(pts
				(xy 1.0922 -2.3114) (xy 1.0922 2.3114) (xy -1.0922 2.3114) (xy -1.0922 -2.3114)
			)
			(stroke
				(width 0)
				(type default)
			)
			(fill no)
			(layer "F.Fab")
		)
		(pad "1" smd rect
			(at 0 -1.397 270)
			(size 1.651 1.27)
			(layers "F.Cu" "F.Mask" "F.Paste")
			(net "P5V_HDD17")
		)
		(pad "2" smd rect
			(at 0 1.397 270)
			(size 1.651 1.27)
			(layers "F.Cu" "F.Mask" "F.Paste")
			(net "GND")
		)
	)
	(footprint ""
		(layer "F.Cu")
		(at 458.47 -151.892 180)
		(property "Reference" "C317"
			(at 0 0 180)
			(layer "F.SilkS")
			(hide yes)
			(effects
				(font
					(size 1.27 1.27)
				)
			)
		)
		(property "Value" "SC10U16V6KX-2GP"
			(at -0.0762 -5.1308 180)
			(unlocked yes)
			(layer "F.Fab")
			(hide yes)
			(effects
				(font
					(size 1.016 1.016)
					(thickness 0.1524)
				)
			)
		)
		(property "Device Type" "C1206H71"
			(at -0.127 -6.6548 180)
			(unlocked yes)
			(layer "F.Fab")
			(hide yes)
			(effects
				(font
					(size 1.016 1.016)
					(thickness 0.1524)
				)
			)
		)
		(duplicate_pad_numbers_are_jumpers no)
		(fp_line
			(start 1.016 2.2352)
			(end -1.016 2.2352)
			(stroke
				(width 0.1524)
				(type default)
			)
			(layer "F.SilkS")
		)
		(fp_line
			(start 1.016 0.8382)
			(end 1.016 2.2352)
			(stroke
				(width 0.1524)
				(type default)
			)
			(layer "F.SilkS")
		)
		(fp_line
			(start 1.016 -2.2352)
			(end 1.016 -0.8382)
			(stroke
				(width 0.1524)
				(type default)
			)
			(layer "F.SilkS")
		)
		(fp_line
			(start -1.016 2.2352)
			(end -1.016 0.8382)
			(stroke
				(width 0.1524)
				(type default)
			)
			(layer "F.SilkS")
		)
		(fp_line
			(start -1.016 -0.8382)
			(end -1.016 -2.2352)
			(stroke
				(width 0.1524)
				(type default)
			)
			(layer "F.SilkS")
		)
		(fp_line
			(start -1.016 -2.2352)
			(end 1.016 -2.2352)
			(stroke
				(width 0.1524)
				(type default)
			)
			(layer "F.SilkS")
		)
		(fp_rect
			(start -1.0922 2.3114)
			(end 1.0922 -2.3114)
			(stroke
				(width 0)
				(type default)
			)
			(fill no)
			(layer "F.CrtYd")
		)
		(fp_poly
			(pts
				(xy 1.0922 -2.3114) (xy 1.0922 2.3114) (xy -1.0922 2.3114) (xy -1.0922 -2.3114)
			)
			(stroke
				(width 0)
				(type default)
			)
			(fill no)
			(layer "F.Fab")
		)
		(pad "1" smd rect
			(at 0 -1.397 180)
			(size 1.651 1.27)
			(layers "F.Cu" "F.Mask" "F.Paste")
			(net "P5V_HDD22")
		)
		(pad "2" smd rect
			(at 0 1.397 180)
			(size 1.651 1.27)
			(layers "F.Cu" "F.Mask" "F.Paste")
			(net "GND")
		)
	)
	(footprint ""
		(layer "F.Cu")
		(at 263.129522 -363.194346)
		(property "Reference" "C105"
			(at 0 0 0)
			(layer "F.SilkS")
			(hide yes)
			(effects
				(font
					(size 1.27 1.27)
				)
			)
		)
		(property "Value" "SCD1U16V2KX-3GP"
			(at 1.1811 -2.7051 0)
			(unlocked yes)
			(layer "F.Fab")
			(hide yes)
			(effects
				(font
					(size 1.016 1.016)
					(thickness 0.1524)
				)
			)
		)
		(property "Device Type" "C402H22"
			(at 1.1811 -4.2291 0)
			(unlocked yes)
			(layer "F.Fab")
			(hide yes)
			(effects
				(font
					(size 1.016 1.016)
					(thickness 0.1524)
				)
			)
		)
		(duplicate_pad_numbers_are_jumpers no)
		(fp_rect
			(start -0.4318 0.9525)
			(end 0.4318 -0.9525)
			(stroke
				(width 0)
				(type default)
			)
			(fill no)
			(layer "F.CrtYd")
		)
		(fp_rect
			(start -0.4318 0.9525)
			(end 0.4318 -0.9525)
			(stroke
				(width 0)
				(type default)
			)
			(fill no)
			(layer "F.Fab")
		)
		(pad "1" smd custom
			(at 0 -0.4445)
			(size 0.1524 0.1524)
			(layers "F.Cu" "F.Mask" "F.Paste")
			(net "P3V3_IN_BIAS")
			(options
				(clearance outline)
				(anchor circle)
			)
			(primitives
				(gr_poly
					(pts
						(arc
							(start 0.3048 -0.2032)
							(mid 0.275042 -0.275042)
							(end 0.2032 -0.3048)
						)
						(arc
							(start -0.2032 -0.3048)
							(mid -0.275042 -0.275042)
							(end -0.3048 -0.2032)
						)
						(arc
							(start -0.3048 0.2032)
							(mid -0.275042 0.275042)
							(end -0.2032 0.3048)
						)
						(arc
							(start 0.2032 0.3048)
							(mid 0.275042 0.275042)
							(end 0.3048 0.2032)
						)
					)
					(width 0)
					(fill yes)
				)
			)
		)
		(pad "2" smd custom
			(at 0 0.4445)
			(size 0.1524 0.1524)
			(layers "F.Cu" "F.Mask" "F.Paste")
			(net "GND")
			(options
				(clearance outline)
				(anchor circle)
			)
			(primitives
				(gr_poly
					(pts
						(arc
							(start 0.3048 -0.2032)
							(mid 0.275042 -0.275042)
							(end 0.2032 -0.3048)
						)
						(arc
							(start -0.2032 -0.3048)
							(mid -0.275042 -0.275042)
							(end -0.3048 -0.2032)
						)
						(arc
							(start -0.3048 0.2032)
							(mid -0.275042 0.275042)
							(end -0.2032 0.3048)
						)
						(arc
							(start 0.2032 0.3048)
							(mid 0.275042 0.275042)
							(end 0.3048 0.2032)
						)
					)
					(width 0)
					(fill yes)
				)
			)
		)
	)
	(footprint ""
		(layer "F.Cu")
		(at 113.538 -150.622 90)
		(property "Reference" "R416"
			(at 0 0 90)
			(layer "F.SilkS")
			(hide yes)
			(effects
				(font
					(size 1.27 1.27)
				)
			)
		)
		(property "Value" "2R6F-GP"
			(at -0.0508 -4.8514 90)
			(unlocked yes)
			(layer "F.Fab")
			(hide yes)
			(effects
				(font
					(size 1.016 1.016)
					(thickness 0.1524)
				)
			)
		)
		(property "Device Type" "R1206H26"
			(at 0 -6.3754 90)
			(unlocked yes)
			(layer "F.Fab")
			(hide yes)
			(effects
				(font
					(size 1.016 1.016)
					(thickness 0.1524)
				)
			)
		)
		(duplicate_pad_numbers_are_jumpers no)
		(fp_line
			(start 1.016 -2.2352)
			(end 1.016 2.2352)
			(stroke
				(width 0.1524)
				(type default)
			)
			(layer "F.SilkS")
		)
		(fp_line
			(start -1.016 -2.2352)
			(end 1.016 -2.2352)
			(stroke
				(width 0.1524)
				(type default)
			)
			(layer "F.SilkS")
		)
		(fp_line
			(start 1.016 2.2352)
			(end -1.016 2.2352)
			(stroke
				(width 0.1524)
				(type default)
			)
			(layer "F.SilkS")
		)
		(fp_line
			(start -1.016 2.2352)
			(end -1.016 -2.2352)
			(stroke
				(width 0.1524)
				(type default)
			)
			(layer "F.SilkS")
		)
		(fp_rect
			(start -1.0922 2.3114)
			(end 1.0922 -2.3114)
			(stroke
				(width 0)
				(type default)
			)
			(fill no)
			(layer "F.CrtYd")
		)
		(fp_poly
			(pts
				(xy -1.0922 -2.3114) (xy 1.0922 -2.3114) (xy 1.0922 2.3114) (xy -1.0922 2.3114)
			)
			(stroke
				(width 0)
				(type default)
			)
			(fill no)
			(layer "F.Fab")
		)
		(pad "1" smd rect
			(at 0 -1.397 90)
			(size 1.651 1.27)
			(layers "F.Cu" "F.Mask" "F.Paste")
			(net "P12V_HDD15")
		)
		(pad "2" smd rect
			(at 0 1.397 90)
			(size 1.651 1.27)
			(layers "F.Cu" "F.Mask" "F.Paste")
			(net "12V_PRE_15")
		)
	)
	(footprint ""
		(layer "F.Cu")
		(at 127.15875 -18.750026 -90)
		(property "Reference" "VIA56"
			(at 0 0 270)
			(layer "F.SilkS")
			(hide yes)
			(effects
				(font
					(size 1.27 1.27)
				)
			)
		)
		(property "Value" "100OHM-8L-2D36MM-L16-GP"
			(at -3.4036 -0.4572 270)
			(unlocked yes)
			(layer "F.Fab")
			(hide yes)
			(effects
				(font
					(size 1.016 1.016)
					(thickness 0.1524)
				)
			)
		)
		(property "Device Type" "VIA-PCIE-4P-427097"
			(at -3.4036 -1.9812 270)
			(unlocked yes)
			(layer "F.Fab")
			(hide yes)
			(effects
				(font
					(size 1.016 1.016)
					(thickness 0.1524)
				)
			)
		)
		(duplicate_pad_numbers_are_jumpers no)
		(fp_rect
			(start -2.1336 0.4826)
			(end 2.1336 -0.4826)
			(stroke
				(width 0)
				(type default)
			)
			(fill no)
			(layer "F.CrtYd")
		)
		(fp_rect
			(start -2.1336 0.4826)
			(end 2.1336 -0.4826)
			(stroke
				(width 0)
				(type default)
			)
			(fill no)
			(layer "F.Fab")
		)
		(pad "1" thru_hole circle
			(at -1.651 0 270)
			(size 0.508 0.508)
			(drill 0.254)
			(layers "*.Cu" "*.Mask")
			(remove_unused_layers no)
			(net "GND")
			(clearance 0.2286)
			(thermal_gap 0.2286)
		)
		(pad "2" thru_hole circle
			(at -0.635 0 270)
			(size 0.508 0.508)
			(drill 0.254)
			(layers "*.Cu" "*.Mask")
			(remove_unused_layers no)
			(net "PHY_DRV_B_TO_SCC_B_27_DP")
			(clearance 0.2286)
			(thermal_gap 0.2286)
		)
		(pad "3" thru_hole circle
			(at 0.635 0 270)
			(size 0.508 0.508)
			(drill 0.254)
			(layers "*.Cu" "*.Mask")
			(remove_unused_layers no)
			(net "PHY_DRV_B_TO_SCC_B_27_DN")
			(clearance 0.2286)
			(thermal_gap 0.2286)
		)
		(pad "4" thru_hole circle
			(at 1.651 0 270)
			(size 0.508 0.508)
			(drill 0.254)
			(layers "*.Cu" "*.Mask")
			(remove_unused_layers no)
			(net "GND")
			(clearance 0.2286)
			(thermal_gap 0.2286)
		)
	)
	(footprint ""
		(layer "F.Cu")
		(at 420.200074 -28.910026 -90)
		(property "Reference" "HDDSAS33"
			(at 0 0 270)
			(layer "F.SilkS")
			(hide yes)
			(effects
				(font
					(size 1.27 1.27)
				)
			)
		)
		(property "Value" "SKT-SAS15P-14P-45-GP"
			(at -20.7645 -8.9789 270)
			(unlocked yes)
			(layer "F.Fab")
			(hide yes)
			(effects
				(font
					(size 1.016 1.016)
					(thickness 0.1524)
				)
			)
		)
		(property "Device Type" "10120818-001C-TRLF"
			(at -20.7645 -10.5029 270)
			(unlocked yes)
			(layer "F.Fab")
			(hide yes)
			(effects
				(font
					(size 1.016 1.016)
					(thickness 0.1524)
				)
			)
		)
		(duplicate_pad_numbers_are_jumpers no)
		(fp_line
			(start 1.651 4.2926)
			(end 1.651 3.0099)
			(stroke
				(width 0.1524)
				(type default)
			)
			(layer "F.SilkS")
		)
		(fp_line
			(start 8.509 4.2926)
			(end 1.651 4.2926)
			(stroke
				(width 0.1524)
				(type default)
			)
			(layer "F.SilkS")
		)
		(fp_line
			(start -23.4188 3.0099)
			(end -23.4188 -3.2512)
			(stroke
				(width 0.1524)
				(type default)
			)
			(layer "F.SilkS")
		)
		(fp_line
			(start 1.651 3.0099)
			(end -23.4188 3.0099)
			(stroke
				(width 0.1524)
				(type default)
			)
			(layer "F.SilkS")
		)
		(fp_line
			(start 8.509 3.0099)
			(end 8.509 4.2926)
			(stroke
				(width 0.1524)
				(type default)
			)
			(layer "F.SilkS")
		)
		(fp_line
			(start 23.4188 3.0099)
			(end 8.509 3.0099)
			(stroke
				(width 0.1524)
				(type default)
			)
			(layer "F.SilkS")
		)
		(fp_line
			(start -23.4188 -3.2512)
			(end 23.4188 -3.2512)
			(stroke
				(width 0.1524)
				(type default)
			)
			(layer "F.SilkS")
		)
		(fp_line
			(start 23.4188 -3.2512)
			(end 23.4188 3.0099)
			(stroke
				(width 0.1524)
				(type default)
			)
			(layer "F.SilkS")
		)
		(fp_line
			(start 15.5067 -3.3401)
			(end 16.2687 -3.3401)
			(stroke
				(width 0.3302)
				(type default)
			)
			(layer "F.SilkS")
		)
		(fp_poly
			(pts
				(xy 15.868904 -3.230372) (xy 16.503904 -3.865372) (xy 15.233904 -3.865372)
			)
			(stroke
				(width 0)
				(type default)
			)
			(fill yes)
			(layer "F.SilkS")
		)
		(fp_poly
			(pts
				(xy -22.8727 -2.7559) (xy 22.8727 -2.7559) (xy 22.8727 2.7559) (xy 8.255 2.7559) (xy 8.255 3.5179)
				(xy 1.905 3.5179) (xy 1.905 2.7559) (xy -22.8727 2.7559)
			)
			(stroke
				(width 0)
				(type default)
			)
			(fill no)
			(layer "F.CrtYd")
		)
		(fp_poly
			(pts
				(xy 1.397 4.5466) (xy 1.397 3.2639) (xy -23.6728 3.2639) (xy -23.6728 -3.5052) (xy 23.6728 -3.5052)
				(xy 23.6728 -0.00635) (xy 22.8727 -0.00635) (xy 22.8727 -2.7559) (xy -22.8727 -2.7559) (xy -22.8727 2.7559)
				(xy 1.905 2.7559) (xy 1.905 3.5179) (xy 8.255 3.5179) (xy 8.255 2.7559) (xy 22.8727 2.7559) (xy 22.8727 0.00635)
				(xy 23.6728 0.00635) (xy 23.6728 3.2639) (xy 8.763 3.2639) (xy 8.763 4.5466)
			)
			(stroke
				(width 0)
				(type default)
			)
			(fill no)
			(layer "F.CrtYd")
		)
		(fp_poly
			(pts
				(xy 1.397 4.5466) (xy 1.397 3.2639) (xy -23.6728 3.2639) (xy -23.6728 -3.5052) (xy 23.6728 -3.5052)
				(xy 23.6728 3.2639) (xy 8.763 3.2639) (xy 8.763 4.5466)
			)
			(stroke
				(width 0)
				(type default)
			)
			(fill no)
			(layer "F.Fab")
		)
		(pad "" np_thru_hole circle
			(at -18.874994 0 270)
			(size 0.254 0.254)
			(drill 1.3462)
			(layers "*.Cu" "*.Mask")
			(clearance 0.9017)
			(thermal_gap 0.9017)
		)
		(pad "" np_thru_hole circle
			(at 18.874994 0 270)
			(size 0.254 0.254)
			(drill 0.9398)
			(layers "*.Cu" "*.Mask")
			(clearance 0.6985)
			(thermal_gap 0.6985)
		)
		(pad "G1" smd rect
			(at 21.874988 0 270)
			(size 2.5908 2.5908)
			(layers "F.Cu" "F.Mask" "F.Paste")
			(net "GND")
		)
		(pad "G2" smd rect
			(at -21.874988 0 270)
			(size 2.5908 2.5908)
			(layers "F.Cu" "F.Mask" "F.Paste")
			(net "GND")
		)
		(pad "P1" smd rect
			(at 1.905 -1.82499 270)
			(size 0.6096 2.3622)
			(layers "F.Cu" "F.Mask" "F.Paste")
			(net "Net_1629")
		)
		(pad "P2" smd rect
			(at 0.635 -1.82499 270)
			(size 0.6096 2.3622)
			(layers "F.Cu" "F.Mask" "F.Paste")
			(net "Net_1630")
		)
		(pad "P3" smd rect
			(at -0.635 -1.82499 270)
			(size 0.6096 2.3622)
			(layers "F.Cu" "F.Mask" "F.Paste")
			(net "Net_1631")
		)
		(pad "P4" smd rect
			(at -1.905 -1.82499 270)
			(size 0.6096 2.3622)
			(layers "F.Cu" "F.Mask" "F.Paste")
			(net "GND")
		)
		(pad "P5" smd rect
			(at -3.175 -1.82499 270)
			(size 0.6096 2.3622)
			(layers "F.Cu" "F.Mask" "F.Paste")
			(net "HDD_PRSNT_33")
		)
		(pad "P6" smd rect
			(at -4.445 -1.82499 270)
			(size 0.6096 2.3622)
			(layers "F.Cu" "F.Mask" "F.Paste")
			(net "GND")
		)
		(pad "P7" smd rect
			(at -5.715 -1.82499 270)
			(size 0.6096 2.3622)
			(layers "F.Cu" "F.Mask" "F.Paste")
			(net "5V_PRE_33")
		)
		(pad "P8" smd rect
			(at -6.985 -1.82499 270)
			(size 0.6096 2.3622)
			(layers "F.Cu" "F.Mask" "F.Paste")
			(net "P5V_HDD33")
		)
		(pad "P9" smd rect
			(at -8.255 -1.82499 270)
			(size 0.6096 2.3622)
			(layers "F.Cu" "F.Mask" "F.Paste")
			(net "P5V_HDD33")
		)
		(pad "P10" smd rect
			(at -9.525 -1.82499 270)
			(size 0.6096 2.3622)
			(layers "F.Cu" "F.Mask" "F.Paste")
			(net "GND")
		)
		(pad "P11" smd rect
			(at -10.795 -1.82499 270)
			(size 0.6096 2.3622)
			(layers "F.Cu" "F.Mask" "F.Paste")
			(net "ACT_HDD_33")
		)
		(pad "P12" smd rect
			(at -12.065 -1.82499 270)
			(size 0.6096 2.3622)
			(layers "F.Cu" "F.Mask" "F.Paste")
			(net "GND")
		)
		(pad "P13" smd rect
			(at -13.335 -1.82499 270)
			(size 0.6096 2.3622)
			(layers "F.Cu" "F.Mask" "F.Paste")
			(net "12V_PRE_33")
		)
		(pad "P14" smd rect
			(at -14.605 -1.82499 270)
			(size 0.6096 2.3622)
			(layers "F.Cu" "F.Mask" "F.Paste")
			(net "P12V_HDD33")
		)
		(pad "P15" smd rect
			(at -15.875 -1.82499 270)
			(size 0.6096 2.3622)
			(layers "F.Cu" "F.Mask" "F.Paste")
			(net "P12V_HDD33")
		)
		(pad "S1" smd rect
			(at 15.875 -1.82499 270)
			(size 0.6096 2.3622)
			(layers "F.Cu" "F.Mask" "F.Paste")
			(net "GND")
		)
		(pad "S2" smd rect
			(at 14.605 -1.82499 270)
			(size 0.6096 2.3622)
			(layers "F.Cu" "F.Mask" "F.Paste")
			(net "SAS_HDD_RX_P33")
		)
		(pad "S3" smd rect
			(at 13.335 -1.82499 270)
			(size 0.6096 2.3622)
			(layers "F.Cu" "F.Mask" "F.Paste")
			(net "SAS_HDD_RX_N33")
		)
		(pad "S4" smd rect
			(at 12.065 -1.82499 270)
			(size 0.6096 2.3622)
			(layers "F.Cu" "F.Mask" "F.Paste")
			(net "GND")
		)
		(pad "S5" smd rect
			(at 10.795 -1.82499 270)
			(size 0.6096 2.3622)
			(layers "F.Cu" "F.Mask" "F.Paste")
			(net "PHY_DRV_B_TO_SCC_B_33_DN")
		)
		(pad "S6" smd rect
			(at 9.525 -1.82499 270)
			(size 0.6096 2.3622)
			(layers "F.Cu" "F.Mask" "F.Paste")
			(net "PHY_DRV_B_TO_SCC_B_33_DP")
		)
		(pad "S7" smd rect
			(at 8.255 -1.82499 270)
			(size 0.6096 2.3622)
			(layers "F.Cu" "F.Mask" "F.Paste")
			(net "GND")
		)
		(pad "S8" smd rect
			(at 7.480046 2.845054 270)
			(size 0.508 2.3622)
			(layers "F.Cu" "F.Mask" "F.Paste")
			(net "GND")
		)
		(pad "S9" smd rect
			(at 6.679946 2.845054 270)
			(size 0.508 2.3622)
			(layers "F.Cu" "F.Mask" "F.Paste")
			(net "Net_458")
		)
		(pad "S10" smd rect
			(at 5.8801 2.845054 270)
			(size 0.508 2.3622)
			(layers "F.Cu" "F.Mask" "F.Paste")
			(net "Net_350")
		)
		(pad "S11" smd rect
			(at 5.08 2.845054 270)
			(size 0.508 2.3622)
			(layers "F.Cu" "F.Mask" "F.Paste")
			(net "GND")
		)
		(pad "S12" smd rect
			(at 4.2799 2.845054 270)
			(size 0.508 2.3622)
			(layers "F.Cu" "F.Mask" "F.Paste")
			(net "Net_386")
		)
		(pad "S13" smd rect
			(at 3.480054 2.845054 270)
			(size 0.508 2.3622)
			(layers "F.Cu" "F.Mask" "F.Paste")
			(net "Net_422")
		)
		(pad "S14" smd rect
			(at 2.679954 2.845054 270)
			(size 0.508 2.3622)
			(layers "F.Cu" "F.Mask" "F.Paste")
			(net "GND")
		)
		(zone
			(layer "F.Cu")
			(hatch none 0.5)
			(connect_pads
				(clearance 0)
			)
			(min_thickness 0.25)
			(keepout
				(tracks not_allowed)
				(vias allowed)
				(pads allowed)
				(copperpour not_allowed)
				(footprints allowed)
			)
			(placement
				(enabled no)
				(sheetname "")
			)
			(fill
				(thermal_gap 0.5)
				(thermal_bridge_width 0.5)
				(island_removal_mode 0)
			)
			(polygon
				(pts
					(xy 423.857674 -45.648626) (xy 416.783774 -45.648626) (xy 416.783774 -52.582826) (xy 417.888674 -52.582826)
					(xy 417.888674 -48.468026) (xy 422.511474 -48.468026) (xy 422.511474 -52.582826) (xy 423.857674 -52.582826)
				)
			)
		)
		(zone
			(layer "F.Cu")
			(hatch none 0.5)
			(connect_pads
				(clearance 0)
			)
			(min_thickness 0.25)
			(keepout
				(tracks allowed)
				(vias not_allowed)
				(pads allowed)
				(copperpour not_allowed)
				(footprints allowed)
			)
			(placement
				(enabled no)
				(sheetname "")
			)
			(fill
				(thermal_gap 0.5)
				(thermal_bridge_width 0.5)
				(island_removal_mode 0)
			)
			(polygon
				(pts
					(xy 423.857674 -45.648626) (xy 416.783774 -45.648626) (xy 416.783774 -52.582826) (xy 417.888674 -52.582826)
					(xy 417.888674 -48.468026) (xy 422.511474 -48.468026) (xy 422.511474 -52.582826) (xy 423.857674 -52.582826)
				)
			)
		)
		(zone
			(layer "F.Cu")
			(hatch none 0.5)
			(connect_pads
				(clearance 0)
			)
			(min_thickness 0.25)
			(keepout
				(tracks not_allowed)
				(vias allowed)
				(pads allowed)
				(copperpour not_allowed)
				(footprints allowed)
			)
			(placement
				(enabled no)
				(sheetname "")
			)
			(fill
				(thermal_gap 0.5)
				(thermal_bridge_width 0.5)
				(island_removal_mode 0)
			)
			(polygon
				(pts
					(xy 423.857674 -12.171426) (xy 416.783774 -12.171426) (xy 416.783774 -5.237226) (xy 417.888674 -5.237226)
					(xy 417.888674 -9.352026) (xy 422.511474 -9.352026) (xy 422.511474 -5.237226) (xy 423.857674 -5.237226)
				)
			)
		)
		(zone
			(layer "F.Cu")
			(hatch none 0.5)
			(connect_pads
				(clearance 0)
			)
			(min_thickness 0.25)
			(keepout
				(tracks allowed)
				(vias not_allowed)
				(pads allowed)
				(copperpour not_allowed)
				(footprints allowed)
			)
			(placement
				(enabled no)
				(sheetname "")
			)
			(fill
				(thermal_gap 0.5)
				(thermal_bridge_width 0.5)
				(island_removal_mode 0)
			)
			(polygon
				(pts
					(xy 423.857674 -12.171426) (xy 416.783774 -12.171426) (xy 416.783774 -5.237226) (xy 417.888674 -5.237226)
					(xy 417.888674 -9.352026) (xy 422.511474 -9.352026) (xy 422.511474 -5.237226) (xy 423.857674 -5.237226)
				)
			)
		)
		(zone
			(layers "F.Cu" "B.Cu" "In1.Cu" "In2.Cu" "In3.Cu" "In4.Cu" "In5.Cu" "In6.Cu")
			(hatch none 0.5)
			(connect_pads
				(clearance 0)
			)
			(min_thickness 0.25)
			(keepout
				(tracks not_allowed)
				(vias allowed)
				(pads allowed)
				(copperpour not_allowed)
				(footprints allowed)
			)
			(placement
				(enabled no)
				(sheetname "")
			)
			(fill
				(thermal_gap 0.5)
				(thermal_bridge_width 0.5)
				(island_removal_mode 0)
			)
			(polygon
				(pts
					(arc
						(start 420.974774 -10.035032)
						(mid 419.425374 -10.035032)
						(end 420.974774 -10.035032)
					)
				)
			)
		)
		(zone
			(layers "F.Cu" "B.Cu" "In1.Cu" "In2.Cu" "In3.Cu" "In4.Cu" "In5.Cu" "In6.Cu")
			(hatch none 0.5)
			(connect_pads
				(clearance 0)
			)
			(min_thickness 0.25)
			(keepout
				(tracks not_allowed)
				(vias allowed)
				(pads allowed)
				(copperpour not_allowed)
				(footprints allowed)
			)
			(placement
				(enabled no)
				(sheetname "")
			)
			(fill
				(thermal_gap 0.5)
				(thermal_bridge_width 0.5)
				(island_removal_mode 0)
			)
			(polygon
				(pts
					(arc
						(start 421.177974 -47.78502)
						(mid 419.222174 -47.78502)
						(end 421.177974 -47.78502)
					)
				)
			)
		)
	)
	(footprint ""
		(layer "F.Cu")
		(at 77.978 -16.637 90)
		(property "Reference" "R682"
			(at 0 0 90)
			(layer "F.SilkS")
			(hide yes)
			(effects
				(font
					(size 1.27 1.27)
				)
			)
		)
		(property "Value" "4K7R2J-2-GP"
			(at 0.064008 -3.993896 90)
			(unlocked yes)
			(layer "F.Fab")
			(hide yes)
			(effects
				(font
					(size 1.016 1.016)
					(thickness 0.1524)
				)
			)
		)
		(property "Device Type" "R402H16"
			(at 0.064008 -5.517896 90)
			(unlocked yes)
			(layer "F.Fab")
			(hide yes)
			(effects
				(font
					(size 1.016 1.016)
					(thickness 0.1524)
				)
			)
		)
		(duplicate_pad_numbers_are_jumpers no)
		(fp_line
			(start 0.508 -0.9398)
			(end -0.508 -0.9398)
			(stroke
				(width 0.1524)
				(type default)
			)
			(layer "F.SilkS")
		)
		(fp_line
			(start -0.508 -0.9398)
			(end -0.508 0.9398)
			(stroke
				(width 0.1524)
				(type default)
			)
			(layer "F.SilkS")
		)
		(fp_rect
			(start -0.508 0.9398)
			(end 0.508 -0.9398)
			(stroke
				(width 0)
				(type default)
			)
			(fill no)
			(layer "F.CrtYd")
		)
		(fp_rect
			(start -0.508 0.9398)
			(end 0.508 -0.9398)
			(stroke
				(width 0)
				(type default)
			)
			(fill no)
			(layer "F.Fab")
		)
		(pad "1" smd custom
			(at 0 -0.4445 90)
			(size 0.1397 0.1397)
			(layers "F.Cu" "F.Mask" "F.Paste")
			(net "P12V_B")
			(options
				(clearance outline)
				(anchor circle)
			)
			(primitives
				(gr_poly
					(pts
						(arc
							(start -0.1778 -0.2794)
							(mid -0.249642 -0.249642)
							(end -0.2794 -0.1778)
						)
						(arc
							(start -0.2794 0.1778)
							(mid -0.249642 0.249642)
							(end -0.1778 0.2794)
						)
						(arc
							(start 0.1778 0.2794)
							(mid 0.249642 0.249642)
							(end 0.2794 0.1778)
						)
						(arc
							(start 0.2794 -0.1778)
							(mid 0.249642 -0.249642)
							(end 0.1778 -0.2794)
						)
					)
					(width 0)
					(fill yes)
				)
			)
		)
		(pad "2" smd custom
			(at 0 0.4445 90)
			(size 0.1397 0.1397)
			(layers "F.Cu" "F.Mask" "F.Paste")
			(net "SW_HDD_R26")
			(options
				(clearance outline)
				(anchor circle)
			)
			(primitives
				(gr_poly
					(pts
						(arc
							(start -0.1778 -0.2794)
							(mid -0.249642 -0.249642)
							(end -0.2794 -0.1778)
						)
						(arc
							(start -0.2794 0.1778)
							(mid -0.249642 0.249642)
							(end -0.1778 0.2794)
						)
						(arc
							(start 0.1778 0.2794)
							(mid 0.249642 0.249642)
							(end 0.2794 0.1778)
						)
						(arc
							(start 0.2794 -0.1778)
							(mid 0.249642 -0.249642)
							(end 0.1778 -0.2794)
						)
					)
					(width 0)
					(fill yes)
				)
			)
		)
	)
	(footprint ""
		(layer "F.Cu")
		(at 393.674854 -293.799768)
		(property "Reference" ""
			(at 0 0 0)
			(layer "F.SilkS")
			(hide yes)
			(effects
				(font
					(size 1.27 1.27)
				)
			)
		)
		(property "Value" "*"
			(at -8.398764 -8.057642 0)
			(unlocked yes)
			(layer "F.Fab")
			(hide yes)
			(effects
				(font
					(size 1.016 1.016)
					(thickness 0.1524)
				)
			)
		)
		(duplicate_pad_numbers_are_jumpers no)
		(fp_poly
			(pts
				(arc
					(start 7.3152 0)
					(mid 0 7.3152)
					(end -7.3152 0)
				)
				(arc
					(start -7.3152 -5.9944)
					(mid 0 -13.3096)
					(end 7.3152 -5.9944)
				)
			)
			(stroke
				(width 0)
				(type default)
			)
			(fill no)
			(layer "B.CrtYd")
		)
		(fp_poly
			(pts
				(arc
					(start 7.3152 0)
					(mid 0 7.3152)
					(end -7.3152 0)
				)
				(arc
					(start -7.3152 -5.9944)
					(mid 0 -13.3096)
					(end 7.3152 -5.9944)
				)
			)
			(stroke
				(width 0)
				(type default)
			)
			(fill no)
			(layer "F.CrtYd")
		)
		(fp_poly
			(pts
				(arc
					(start 7.3152 0)
					(mid 0 7.3152)
					(end -7.3152 0)
				)
				(arc
					(start -7.3152 -5.9944)
					(mid 0 -13.3096)
					(end 7.3152 -5.9944)
				)
			)
			(stroke
				(width 0)
				(type default)
			)
			(fill no)
			(layer "B.Fab")
		)
		(fp_poly
			(pts
				(arc
					(start 7.3152 0)
					(mid 0 7.3152)
					(end -7.3152 0)
				)
				(arc
					(start -7.3152 -5.9944)
					(mid 0 -13.3096)
					(end 7.3152 -5.9944)
				)
			)
			(stroke
				(width 0)
				(type default)
			)
			(fill no)
			(layer "F.Fab")
		)
		(pad "1" thru_hole oval
			(at 0 0)
			(size 14.0208 20.0152)
			(drill 0.0254
				(offset 0 -2.9972)
			)
			(layers "*.Cu" "*.Mask")
			(remove_unused_layers no)
			(net "Net_41")
			(clearance -1.002284)
			(thermal_gap 0.1524)
			(padstack
				(mode front_inner_back)
				(layer "Inner"
					(shape custom)
					(size 2.928012 2.928012)
					(options
						(anchor circle)
					)
					(primitives
						(gr_poly
							(pts
								(arc
									(start 4.571746 -2.084324)
									(mid 0.000333 7.430372)
									(end -4.571492 -2.084324)
								)
								(arc
									(start -4.571492 -2.084324)
									(mid -3.570296 -3.611977)
									(end -2.875026 -5.30098)
								)
								(arc
									(start -2.875026 -5.30098)
									(mid 0.000217 -7.43089)
									(end 2.87528 -5.30098)
								)
								(arc
									(start 2.87528 -5.30098)
									(mid 3.570511 -3.611956)
									(end 4.571746 -2.084324)
								)
							)
							(width 0)
							(fill yes)
						)
					)
					(clearance 0.1524)
				)
				(layer "B.Cu"
					(shape oval)
					(size 14.0208 20.0152)
					(offset 0 -2.9972)
					(clearance -1.002284)
				)
			)
		)
		(zone
			(layers "F.Cu" "B.Cu" "In1.Cu" "In2.Cu" "In3.Cu" "In4.Cu" "In5.Cu" "In6.Cu")
			(hatch none 0.5)
			(connect_pads
				(clearance 0)
			)
			(min_thickness 0.25)
			(keepout
				(tracks not_allowed)
				(vias allowed)
				(pads allowed)
				(copperpour not_allowed)
				(footprints allowed)
			)
			(placement
				(enabled no)
				(sheetname "")
			)
			(fill
				(thermal_gap 0.5)
				(thermal_bridge_width 0.5)
				(island_removal_mode 0)
			)
			(polygon
				(pts
					(arc
						(start 386.664454 -299.794168)
						(mid 393.674854 -306.804568)
						(end 400.685254 -299.794168)
					)
					(arc
						(start 400.685254 -293.799768)
						(mid 393.674854 -286.789368)
						(end 386.664454 -293.799768)
					)
				)
			)
		)
	)
	(footprint ""
		(layer "F.Cu")
		(at 150.114 -157.226)
		(property "Reference" "C242"
			(at 0 0 0)
			(layer "F.SilkS")
			(hide yes)
			(effects
				(font
					(size 1.27 1.27)
				)
			)
		)
		(property "Value" "SC4D7U25V5KX-1-GP"
			(at -0.0762 -6.1214 0)
			(unlocked yes)
			(layer "F.Fab")
			(hide yes)
			(effects
				(font
					(size 1.016 1.016)
					(thickness 0.1524)
				)
			)
		)
		(property "Device Type" "C805H58"
			(at -0.0762 -8.1534 0)
			(unlocked yes)
			(layer "F.Fab")
			(hide yes)
			(effects
				(font
					(size 1.016 1.016)
					(thickness 0.1524)
				)
			)
		)
		(duplicate_pad_numbers_are_jumpers no)
		(fp_line
			(start 0.635 0)
			(end -0.635 0)
			(stroke
				(width 0.508)
				(type default)
			)
			(layer "F.SilkS")
		)
		(fp_rect
			(start -0.9652 1.778)
			(end 0.9652 -1.778)
			(stroke
				(width 0)
				(type default)
			)
			(fill no)
			(layer "F.CrtYd")
		)
		(fp_poly
			(pts
				(xy -0.9652 -1.778) (xy 0.9652 -1.778) (xy 0.9652 1.778) (xy -0.9652 1.778)
			)
			(stroke
				(width 0)
				(type default)
			)
			(fill no)
			(layer "F.Fab")
		)
		(pad "1" smd rect
			(at 0 -0.9652)
			(size 1.397 1.143)
			(layers "F.Cu" "F.Mask" "F.Paste")
			(net "P12V_HDD16")
		)
		(pad "2" smd rect
			(at 0 0.9652)
			(size 1.397 1.143)
			(layers "F.Cu" "F.Mask" "F.Paste")
			(net "GND")
		)
	)
	(footprint ""
		(layer "F.Cu")
		(at 109.474 -131.572 90)
		(property "Reference" "R429"
			(at 0 0 90)
			(layer "F.SilkS")
			(hide yes)
			(effects
				(font
					(size 1.27 1.27)
				)
			)
		)
		(property "Value" "4K7R2J-2-GP"
			(at 0.064008 -3.993896 90)
			(unlocked yes)
			(layer "F.Fab")
			(hide yes)
			(effects
				(font
					(size 1.016 1.016)
					(thickness 0.1524)
				)
			)
		)
		(property "Device Type" "R402H16"
			(at 0.064008 -5.517896 90)
			(unlocked yes)
			(layer "F.Fab")
			(hide yes)
			(effects
				(font
					(size 1.016 1.016)
					(thickness 0.1524)
				)
			)
		)
		(duplicate_pad_numbers_are_jumpers no)
		(fp_line
			(start 0.508 -0.9398)
			(end -0.508 -0.9398)
			(stroke
				(width 0.1524)
				(type default)
			)
			(layer "F.SilkS")
		)
		(fp_line
			(start -0.508 -0.9398)
			(end -0.508 0.9398)
			(stroke
				(width 0.1524)
				(type default)
			)
			(layer "F.SilkS")
		)
		(fp_rect
			(start -0.508 0.9398)
			(end 0.508 -0.9398)
			(stroke
				(width 0)
				(type default)
			)
			(fill no)
			(layer "F.CrtYd")
		)
		(fp_rect
			(start -0.508 0.9398)
			(end 0.508 -0.9398)
			(stroke
				(width 0)
				(type default)
			)
			(fill no)
			(layer "F.Fab")
		)
		(pad "1" smd custom
			(at 0 -0.4445 90)
			(size 0.1397 0.1397)
			(layers "F.Cu" "F.Mask" "F.Paste")
			(net "P12V_B")
			(options
				(clearance outline)
				(anchor circle)
			)
			(primitives
				(gr_poly
					(pts
						(arc
							(start -0.1778 -0.2794)
							(mid -0.249642 -0.249642)
							(end -0.2794 -0.1778)
						)
						(arc
							(start -0.2794 0.1778)
							(mid -0.249642 0.249642)
							(end -0.1778 0.2794)
						)
						(arc
							(start 0.1778 0.2794)
							(mid 0.249642 0.249642)
							(end 0.2794 0.1778)
						)
						(arc
							(start 0.2794 -0.1778)
							(mid 0.249642 -0.249642)
							(end 0.1778 -0.2794)
						)
					)
					(width 0)
					(fill yes)
				)
			)
		)
		(pad "2" smd custom
			(at 0 0.4445 90)
			(size 0.1397 0.1397)
			(layers "F.Cu" "F.Mask" "F.Paste")
			(net "SW_HDD_R15")
			(options
				(clearance outline)
				(anchor circle)
			)
			(primitives
				(gr_poly
					(pts
						(arc
							(start -0.1778 -0.2794)
							(mid -0.249642 -0.249642)
							(end -0.2794 -0.1778)
						)
						(arc
							(start -0.2794 0.1778)
							(mid -0.249642 0.249642)
							(end -0.1778 0.2794)
						)
						(arc
							(start 0.1778 0.2794)
							(mid 0.249642 0.249642)
							(end 0.2794 0.1778)
						)
						(arc
							(start 0.2794 -0.1778)
							(mid 0.249642 -0.249642)
							(end 0.1778 -0.2794)
						)
					)
					(width 0)
					(fill yes)
				)
			)
		)
	)
	(footprint ""
		(layer "F.Cu")
		(at 266.1158 -359.918 90)
		(property "Reference" "R1293"
			(at 0 0 90)
			(layer "F.SilkS")
			(hide yes)
			(effects
				(font
					(size 1.27 1.27)
				)
			)
		)
		(property "Value" "3K3R3F-GP"
			(at -0.0254 -2.5146 90)
			(unlocked yes)
			(layer "F.Fab")
			(hide yes)
			(effects
				(font
					(size 1.016 1.016)
					(thickness 0.1524)
				)
			)
		)
		(property "Device Type" "R603H22"
			(at -0.0254 -4.0386 90)
			(unlocked yes)
			(layer "F.Fab")
			(hide yes)
			(effects
				(font
					(size 1.016 1.016)
					(thickness 0.1524)
				)
			)
		)
		(duplicate_pad_numbers_are_jumpers no)
		(fp_line
			(start 0.2032 0)
			(end 0.4826 0)
			(stroke
				(width 0.2032)
				(type default)
			)
			(layer "F.SilkS")
		)
		(fp_line
			(start -0.4826 0)
			(end -0.2032 0)
			(stroke
				(width 0.2032)
				(type default)
			)
			(layer "F.SilkS")
		)
		(fp_rect
			(start -0.5842 1.3335)
			(end 0.5842 -1.3335)
			(stroke
				(width 0)
				(type default)
			)
			(fill no)
			(layer "F.CrtYd")
		)
		(fp_rect
			(start -0.5842 1.3335)
			(end 0.5842 -1.3335)
			(stroke
				(width 0)
				(type default)
			)
			(fill no)
			(layer "F.Fab")
		)
		(pad "1" smd custom
			(at 0 -0.762 90)
			(size 0.2159 0.2159)
			(layers "F.Cu" "F.Mask" "F.Paste")
			(net "P12V_IN")
			(options
				(clearance outline)
				(anchor circle)
			)
			(primitives
				(gr_poly
					(pts
						(arc
							(start -0.3302 -0.4318)
							(mid -0.402042 -0.402042)
							(end -0.4318 -0.3302)
						)
						(arc
							(start -0.4318 0.3302)
							(mid -0.402042 0.402042)
							(end -0.3302 0.4318)
						)
						(arc
							(start 0.3302 0.4318)
							(mid 0.402042 0.402042)
							(end 0.4318 0.3302)
						)
						(arc
							(start 0.4318 -0.3302)
							(mid 0.402042 -0.402042)
							(end 0.3302 -0.4318)
						)
					)
					(width 0)
					(fill yes)
				)
			)
		)
		(pad "2" smd custom
			(at 0 0.762 90)
			(size 0.2159 0.2159)
			(layers "F.Cu" "F.Mask" "F.Paste")
			(net "VCCP_IN")
			(options
				(clearance outline)
				(anchor circle)
			)
			(primitives
				(gr_poly
					(pts
						(arc
							(start -0.3302 -0.4318)
							(mid -0.402042 -0.402042)
							(end -0.4318 -0.3302)
						)
						(arc
							(start -0.4318 0.3302)
							(mid -0.402042 0.402042)
							(end -0.3302 0.4318)
						)
						(arc
							(start 0.3302 0.4318)
							(mid 0.402042 0.402042)
							(end 0.4318 0.3302)
						)
						(arc
							(start 0.4318 -0.3302)
							(mid 0.402042 -0.402042)
							(end 0.3302 -0.4318)
						)
					)
					(width 0)
					(fill yes)
				)
			)
		)
	)
	(footprint ""
		(layer "F.Cu")
		(at 333.5528 -155.6004 -90)
		(property "Reference" "R485"
			(at 0 0 270)
			(layer "F.SilkS")
			(hide yes)
			(effects
				(font
					(size 1.27 1.27)
				)
			)
		)
		(property "Value" "2R6F-GP"
			(at -0.0508 -4.8514 270)
			(unlocked yes)
			(layer "F.Fab")
			(hide yes)
			(effects
				(font
					(size 1.016 1.016)
					(thickness 0.1524)
				)
			)
		)
		(property "Device Type" "R1206H26"
			(at 0 -6.3754 270)
			(unlocked yes)
			(layer "F.Fab")
			(hide yes)
			(effects
				(font
					(size 1.016 1.016)
					(thickness 0.1524)
				)
			)
		)
		(duplicate_pad_numbers_are_jumpers no)
		(fp_line
			(start -1.016 2.2352)
			(end -1.016 -2.2352)
			(stroke
				(width 0.1524)
				(type default)
			)
			(layer "F.SilkS")
		)
		(fp_line
			(start 1.016 2.2352)
			(end -1.016 2.2352)
			(stroke
				(width 0.1524)
				(type default)
			)
			(layer "F.SilkS")
		)
		(fp_line
			(start -1.016 -2.2352)
			(end 1.016 -2.2352)
			(stroke
				(width 0.1524)
				(type default)
			)
			(layer "F.SilkS")
		)
		(fp_line
			(start 1.016 -2.2352)
			(end 1.016 2.2352)
			(stroke
				(width 0.1524)
				(type default)
			)
			(layer "F.SilkS")
		)
		(fp_rect
			(start -1.0922 2.3114)
			(end 1.0922 -2.3114)
			(stroke
				(width 0)
				(type default)
			)
			(fill no)
			(layer "F.CrtYd")
		)
		(fp_poly
			(pts
				(xy -1.0922 -2.3114) (xy 1.0922 -2.3114) (xy 1.0922 2.3114) (xy -1.0922 2.3114)
			)
			(stroke
				(width 0)
				(type default)
			)
			(fill no)
			(layer "F.Fab")
		)
		(pad "1" smd rect
			(at 0 -1.397 270)
			(size 1.651 1.27)
			(layers "F.Cu" "F.Mask" "F.Paste")
			(net "P12V_HDD18")
		)
		(pad "2" smd rect
			(at 0 1.397 270)
			(size 1.651 1.27)
			(layers "F.Cu" "F.Mask" "F.Paste")
			(net "12V_PRE_18")
		)
	)
	(footprint ""
		(layer "F.Cu")
		(at 433.737004 -358.3559)
		(property "Reference" "R146"
			(at 0 0 0)
			(layer "F.SilkS")
			(hide yes)
			(effects
				(font
					(size 1.27 1.27)
				)
			)
		)
		(property "Value" "200KR2F-L-GP"
			(at 0.064008 -3.993896 0)
			(unlocked yes)
			(layer "F.Fab")
			(hide yes)
			(effects
				(font
					(size 1.016 1.016)
					(thickness 0.1524)
				)
			)
		)
		(property "Device Type" "R402H16"
			(at 0.064008 -5.517896 0)
			(unlocked yes)
			(layer "F.Fab")
			(hide yes)
			(effects
				(font
					(size 1.016 1.016)
					(thickness 0.1524)
				)
			)
		)
		(duplicate_pad_numbers_are_jumpers no)
		(fp_line
			(start -0.508 -0.9398)
			(end -0.508 0.9398)
			(stroke
				(width 0.1524)
				(type default)
			)
			(layer "F.SilkS")
		)
		(fp_line
			(start 0.508 -0.9398)
			(end -0.508 -0.9398)
			(stroke
				(width 0.1524)
				(type default)
			)
			(layer "F.SilkS")
		)
		(fp_rect
			(start -0.508 0.9398)
			(end 0.508 -0.9398)
			(stroke
				(width 0)
				(type default)
			)
			(fill no)
			(layer "F.CrtYd")
		)
		(fp_rect
			(start -0.508 0.9398)
			(end 0.508 -0.9398)
			(stroke
				(width 0)
				(type default)
			)
			(fill no)
			(layer "F.Fab")
		)
		(pad "1" smd custom
			(at 0 -0.4445)
			(size 0.1397 0.1397)
			(layers "F.Cu" "F.Mask" "F.Paste")
			(net "GATE_FAN3")
			(options
				(clearance outline)
				(anchor circle)
			)
			(primitives
				(gr_poly
					(pts
						(arc
							(start -0.1778 -0.2794)
							(mid -0.249642 -0.249642)
							(end -0.2794 -0.1778)
						)
						(arc
							(start -0.2794 0.1778)
							(mid -0.249642 0.249642)
							(end -0.1778 0.2794)
						)
						(arc
							(start 0.1778 0.2794)
							(mid 0.249642 0.249642)
							(end 0.2794 0.1778)
						)
						(arc
							(start 0.2794 -0.1778)
							(mid 0.249642 -0.249642)
							(end 0.1778 -0.2794)
						)
					)
					(width 0)
					(fill yes)
				)
			)
		)
		(pad "2" smd custom
			(at 0 0.4445)
			(size 0.1397 0.1397)
			(layers "F.Cu" "F.Mask" "F.Paste")
			(net "GATE_FAN3_R")
			(options
				(clearance outline)
				(anchor circle)
			)
			(primitives
				(gr_poly
					(pts
						(arc
							(start -0.1778 -0.2794)
							(mid -0.249642 -0.249642)
							(end -0.2794 -0.1778)
						)
						(arc
							(start -0.2794 0.1778)
							(mid -0.249642 0.249642)
							(end -0.1778 0.2794)
						)
						(arc
							(start 0.1778 0.2794)
							(mid 0.249642 0.249642)
							(end 0.2794 0.1778)
						)
						(arc
							(start 0.2794 -0.1778)
							(mid 0.249642 -0.249642)
							(end 0.1778 -0.2794)
						)
					)
					(width 0)
					(fill yes)
				)
			)
		)
	)
	(footprint ""
		(layer "F.Cu")
		(at 171.831 -375.412 180)
		(property "Reference" "R982"
			(at 0 0 180)
			(layer "F.SilkS")
			(hide yes)
			(effects
				(font
					(size 1.27 1.27)
				)
			)
		)
		(property "Value" "100R2D-GP"
			(at 0.064008 -3.993896 180)
			(unlocked yes)
			(layer "F.Fab")
			(hide yes)
			(effects
				(font
					(size 1.016 1.016)
					(thickness 0.1524)
				)
			)
		)
		(property "Device Type" "R402H14"
			(at 0.064008 -5.517896 180)
			(unlocked yes)
			(layer "F.Fab")
			(hide yes)
			(effects
				(font
					(size 1.016 1.016)
					(thickness 0.1524)
				)
			)
		)
		(duplicate_pad_numbers_are_jumpers no)
		(fp_line
			(start 0.508 -0.9398)
			(end -0.508 -0.9398)
			(stroke
				(width 0.1524)
				(type default)
			)
			(layer "F.SilkS")
		)
		(fp_line
			(start -0.508 -0.9398)
			(end -0.508 0.9398)
			(stroke
				(width 0.1524)
				(type default)
			)
			(layer "F.SilkS")
		)
		(fp_rect
			(start -0.508 0.9398)
			(end 0.508 -0.9398)
			(stroke
				(width 0)
				(type default)
			)
			(fill no)
			(layer "F.CrtYd")
		)
		(fp_rect
			(start -0.508 0.9398)
			(end 0.508 -0.9398)
			(stroke
				(width 0)
				(type default)
			)
			(fill no)
			(layer "F.Fab")
		)
		(pad "1" smd custom
			(at 0 -0.4445 180)
			(size 0.1397 0.1397)
			(layers "F.Cu" "F.Mask" "F.Paste")
			(net "MB0_TEMP")
			(options
				(clearance outline)
				(anchor circle)
			)
			(primitives
				(gr_poly
					(pts
						(arc
							(start -0.1778 -0.2794)
							(mid -0.249642 -0.249642)
							(end -0.2794 -0.1778)
						)
						(arc
							(start -0.2794 0.1778)
							(mid -0.249642 0.249642)
							(end -0.1778 0.2794)
						)
						(arc
							(start 0.1778 0.2794)
							(mid 0.249642 0.249642)
							(end 0.2794 0.1778)
						)
						(arc
							(start 0.2794 -0.1778)
							(mid 0.249642 -0.249642)
							(end 0.1778 -0.2794)
						)
					)
					(width 0)
					(fill yes)
				)
			)
		)
		(pad "2" smd custom
			(at 0 0.4445 180)
			(size 0.1397 0.1397)
			(layers "F.Cu" "F.Mask" "F.Paste")
			(net "MB0_TEMP_B")
			(options
				(clearance outline)
				(anchor circle)
			)
			(primitives
				(gr_poly
					(pts
						(arc
							(start -0.1778 -0.2794)
							(mid -0.249642 -0.249642)
							(end -0.2794 -0.1778)
						)
						(arc
							(start -0.2794 0.1778)
							(mid -0.249642 0.249642)
							(end -0.1778 0.2794)
						)
						(arc
							(start 0.1778 0.2794)
							(mid 0.249642 0.249642)
							(end 0.2794 0.1778)
						)
						(arc
							(start 0.2794 -0.1778)
							(mid 0.249642 -0.249642)
							(end 0.1778 -0.2794)
						)
					)
					(width 0)
					(fill yes)
				)
			)
		)
	)
	(footprint ""
		(layer "F.Cu")
		(at 427.863 -243.586 180)
		(property "Reference" "R308"
			(at 0 0 180)
			(layer "F.SilkS")
			(hide yes)
			(effects
				(font
					(size 1.27 1.27)
				)
			)
		)
		(property "Value" "1KR2F-3-GP"
			(at 0.064008 -3.993896 180)
			(unlocked yes)
			(layer "F.Fab")
			(hide yes)
			(effects
				(font
					(size 1.016 1.016)
					(thickness 0.1524)
				)
			)
		)
		(property "Device Type" "R402H16"
			(at 0.064008 -5.517896 180)
			(unlocked yes)
			(layer "F.Fab")
			(hide yes)
			(effects
				(font
					(size 1.016 1.016)
					(thickness 0.1524)
				)
			)
		)
		(duplicate_pad_numbers_are_jumpers no)
		(fp_line
			(start 0.508 -0.9398)
			(end -0.508 -0.9398)
			(stroke
				(width 0.1524)
				(type default)
			)
			(layer "F.SilkS")
		)
		(fp_line
			(start -0.508 -0.9398)
			(end -0.508 0.9398)
			(stroke
				(width 0.1524)
				(type default)
			)
			(layer "F.SilkS")
		)
		(fp_rect
			(start -0.508 0.9398)
			(end 0.508 -0.9398)
			(stroke
				(width 0)
				(type default)
			)
			(fill no)
			(layer "F.CrtYd")
		)
		(fp_rect
			(start -0.508 0.9398)
			(end 0.508 -0.9398)
			(stroke
				(width 0)
				(type default)
			)
			(fill no)
			(layer "F.Fab")
		)
		(pad "1" smd custom
			(at 0 -0.4445 180)
			(size 0.1397 0.1397)
			(layers "F.Cu" "F.Mask" "F.Paste")
			(net "P3V3_STBY_B")
			(options
				(clearance outline)
				(anchor circle)
			)
			(primitives
				(gr_poly
					(pts
						(arc
							(start -0.1778 -0.2794)
							(mid -0.249642 -0.249642)
							(end -0.2794 -0.1778)
						)
						(arc
							(start -0.2794 0.1778)
							(mid -0.249642 0.249642)
							(end -0.1778 0.2794)
						)
						(arc
							(start 0.1778 0.2794)
							(mid 0.249642 0.249642)
							(end 0.2794 0.1778)
						)
						(arc
							(start 0.2794 -0.1778)
							(mid 0.249642 -0.249642)
							(end 0.1778 -0.2794)
						)
					)
					(width 0)
					(fill yes)
				)
			)
		)
		(pad "2" smd custom
			(at 0 0.4445 180)
			(size 0.1397 0.1397)
			(layers "F.Cu" "F.Mask" "F.Paste")
			(net "SW_PWR_R_HDD9")
			(options
				(clearance outline)
				(anchor circle)
			)
			(primitives
				(gr_poly
					(pts
						(arc
							(start -0.1778 -0.2794)
							(mid -0.249642 -0.249642)
							(end -0.2794 -0.1778)
						)
						(arc
							(start -0.2794 0.1778)
							(mid -0.249642 0.249642)
							(end -0.1778 0.2794)
						)
						(arc
							(start 0.1778 0.2794)
							(mid 0.249642 0.249642)
							(end 0.2794 0.1778)
						)
						(arc
							(start 0.2794 -0.1778)
							(mid 0.249642 -0.249642)
							(end 0.1778 -0.2794)
						)
					)
					(width 0)
					(fill yes)
				)
			)
		)
	)
	(footprint ""
		(layer "F.Cu")
		(at 357.100124 -258.910074 -90)
		(property "Reference" "HDDSAS7"
			(at 0 0 270)
			(layer "F.SilkS")
			(hide yes)
			(effects
				(font
					(size 1.27 1.27)
				)
			)
		)
		(property "Value" "SKT-SAS15P-14P-45-GP"
			(at -20.7645 -8.9789 270)
			(unlocked yes)
			(layer "F.Fab")
			(hide yes)
			(effects
				(font
					(size 1.016 1.016)
					(thickness 0.1524)
				)
			)
		)
		(property "Device Type" "10120818-001C-TRLF"
			(at -20.7645 -10.5029 270)
			(unlocked yes)
			(layer "F.Fab")
			(hide yes)
			(effects
				(font
					(size 1.016 1.016)
					(thickness 0.1524)
				)
			)
		)
		(duplicate_pad_numbers_are_jumpers no)
		(fp_line
			(start 1.651 4.2926)
			(end 1.651 3.0099)
			(stroke
				(width 0.1524)
				(type default)
			)
			(layer "F.SilkS")
		)
		(fp_line
			(start 8.509 4.2926)
			(end 1.651 4.2926)
			(stroke
				(width 0.1524)
				(type default)
			)
			(layer "F.SilkS")
		)
		(fp_line
			(start -23.4188 3.0099)
			(end -23.4188 -3.2512)
			(stroke
				(width 0.1524)
				(type default)
			)
			(layer "F.SilkS")
		)
		(fp_line
			(start 1.651 3.0099)
			(end -23.4188 3.0099)
			(stroke
				(width 0.1524)
				(type default)
			)
			(layer "F.SilkS")
		)
		(fp_line
			(start 8.509 3.0099)
			(end 8.509 4.2926)
			(stroke
				(width 0.1524)
				(type default)
			)
			(layer "F.SilkS")
		)
		(fp_line
			(start 23.4188 3.0099)
			(end 8.509 3.0099)
			(stroke
				(width 0.1524)
				(type default)
			)
			(layer "F.SilkS")
		)
		(fp_line
			(start -23.4188 -3.2512)
			(end 23.4188 -3.2512)
			(stroke
				(width 0.1524)
				(type default)
			)
			(layer "F.SilkS")
		)
		(fp_line
			(start 23.4188 -3.2512)
			(end 23.4188 3.0099)
			(stroke
				(width 0.1524)
				(type default)
			)
			(layer "F.SilkS")
		)
		(fp_line
			(start 15.5067 -3.3401)
			(end 16.2687 -3.3401)
			(stroke
				(width 0.3302)
				(type default)
			)
			(layer "F.SilkS")
		)
		(fp_poly
			(pts
				(xy 15.868904 -3.230372) (xy 16.503904 -3.865372) (xy 15.233904 -3.865372)
			)
			(stroke
				(width 0)
				(type default)
			)
			(fill yes)
			(layer "F.SilkS")
		)
		(fp_poly
			(pts
				(xy -22.8727 -2.7559) (xy 22.8727 -2.7559) (xy 22.8727 2.7559) (xy 8.255 2.7559) (xy 8.255 3.5179)
				(xy 1.905 3.5179) (xy 1.905 2.7559) (xy -22.8727 2.7559)
			)
			(stroke
				(width 0)
				(type default)
			)
			(fill no)
			(layer "F.CrtYd")
		)
		(fp_poly
			(pts
				(xy 1.397 4.5466) (xy 1.397 3.2639) (xy -23.6728 3.2639) (xy -23.6728 -3.5052) (xy 23.6728 -3.5052)
				(xy 23.6728 -0.00635) (xy 22.8727 -0.00635) (xy 22.8727 -2.7559) (xy -22.8727 -2.7559) (xy -22.8727 2.7559)
				(xy 1.905 2.7559) (xy 1.905 3.5179) (xy 8.255 3.5179) (xy 8.255 2.7559) (xy 22.8727 2.7559) (xy 22.8727 0.00635)
				(xy 23.6728 0.00635) (xy 23.6728 3.2639) (xy 8.763 3.2639) (xy 8.763 4.5466)
			)
			(stroke
				(width 0)
				(type default)
			)
			(fill no)
			(layer "F.CrtYd")
		)
		(fp_poly
			(pts
				(xy 1.397 4.5466) (xy 1.397 3.2639) (xy -23.6728 3.2639) (xy -23.6728 -3.5052) (xy 23.6728 -3.5052)
				(xy 23.6728 3.2639) (xy 8.763 3.2639) (xy 8.763 4.5466)
			)
			(stroke
				(width 0)
				(type default)
			)
			(fill no)
			(layer "F.Fab")
		)
		(pad "" np_thru_hole circle
			(at -18.874994 0 270)
			(size 0.254 0.254)
			(drill 1.3462)
			(layers "*.Cu" "*.Mask")
			(clearance 0.9017)
			(thermal_gap 0.9017)
		)
		(pad "" np_thru_hole circle
			(at 18.874994 0 270)
			(size 0.254 0.254)
			(drill 0.9398)
			(layers "*.Cu" "*.Mask")
			(clearance 0.6985)
			(thermal_gap 0.6985)
		)
		(pad "G1" smd rect
			(at 21.874988 0 270)
			(size 2.5908 2.5908)
			(layers "F.Cu" "F.Mask" "F.Paste")
			(net "GND")
		)
		(pad "G2" smd rect
			(at -21.874988 0 270)
			(size 2.5908 2.5908)
			(layers "F.Cu" "F.Mask" "F.Paste")
			(net "GND")
		)
		(pad "P1" smd rect
			(at 1.905 -1.82499 270)
			(size 0.6096 2.3622)
			(layers "F.Cu" "F.Mask" "F.Paste")
			(net "Net_1594")
		)
		(pad "P2" smd rect
			(at 0.635 -1.82499 270)
			(size 0.6096 2.3622)
			(layers "F.Cu" "F.Mask" "F.Paste")
			(net "Net_1595")
		)
		(pad "P3" smd rect
			(at -0.635 -1.82499 270)
			(size 0.6096 2.3622)
			(layers "F.Cu" "F.Mask" "F.Paste")
			(net "Net_1596")
		)
		(pad "P4" smd rect
			(at -1.905 -1.82499 270)
			(size 0.6096 2.3622)
			(layers "F.Cu" "F.Mask" "F.Paste")
			(net "GND")
		)
		(pad "P5" smd rect
			(at -3.175 -1.82499 270)
			(size 0.6096 2.3622)
			(layers "F.Cu" "F.Mask" "F.Paste")
			(net "HDD_PRSNT_7")
		)
		(pad "P6" smd rect
			(at -4.445 -1.82499 270)
			(size 0.6096 2.3622)
			(layers "F.Cu" "F.Mask" "F.Paste")
			(net "GND")
		)
		(pad "P7" smd rect
			(at -5.715 -1.82499 270)
			(size 0.6096 2.3622)
			(layers "F.Cu" "F.Mask" "F.Paste")
			(net "5V_PRE_7")
		)
		(pad "P8" smd rect
			(at -6.985 -1.82499 270)
			(size 0.6096 2.3622)
			(layers "F.Cu" "F.Mask" "F.Paste")
			(net "P5V_HDD7")
		)
		(pad "P9" smd rect
			(at -8.255 -1.82499 270)
			(size 0.6096 2.3622)
			(layers "F.Cu" "F.Mask" "F.Paste")
			(net "P5V_HDD7")
		)
		(pad "P10" smd rect
			(at -9.525 -1.82499 270)
			(size 0.6096 2.3622)
			(layers "F.Cu" "F.Mask" "F.Paste")
			(net "GND")
		)
		(pad "P11" smd rect
			(at -10.795 -1.82499 270)
			(size 0.6096 2.3622)
			(layers "F.Cu" "F.Mask" "F.Paste")
			(net "ACT_HDD_7")
		)
		(pad "P12" smd rect
			(at -12.065 -1.82499 270)
			(size 0.6096 2.3622)
			(layers "F.Cu" "F.Mask" "F.Paste")
			(net "GND")
		)
		(pad "P13" smd rect
			(at -13.335 -1.82499 270)
			(size 0.6096 2.3622)
			(layers "F.Cu" "F.Mask" "F.Paste")
			(net "12V_PRE_7")
		)
		(pad "P14" smd rect
			(at -14.605 -1.82499 270)
			(size 0.6096 2.3622)
			(layers "F.Cu" "F.Mask" "F.Paste")
			(net "P12V_HDD7")
		)
		(pad "P15" smd rect
			(at -15.875 -1.82499 270)
			(size 0.6096 2.3622)
			(layers "F.Cu" "F.Mask" "F.Paste")
			(net "P12V_HDD7")
		)
		(pad "S1" smd rect
			(at 15.875 -1.82499 270)
			(size 0.6096 2.3622)
			(layers "F.Cu" "F.Mask" "F.Paste")
			(net "GND")
		)
		(pad "S2" smd rect
			(at 14.605 -1.82499 270)
			(size 0.6096 2.3622)
			(layers "F.Cu" "F.Mask" "F.Paste")
			(net "SAS_HDD_RX_P7")
		)
		(pad "S3" smd rect
			(at 13.335 -1.82499 270)
			(size 0.6096 2.3622)
			(layers "F.Cu" "F.Mask" "F.Paste")
			(net "SAS_HDD_RX_N7")
		)
		(pad "S4" smd rect
			(at 12.065 -1.82499 270)
			(size 0.6096 2.3622)
			(layers "F.Cu" "F.Mask" "F.Paste")
			(net "GND")
		)
		(pad "S5" smd rect
			(at 10.795 -1.82499 270)
			(size 0.6096 2.3622)
			(layers "F.Cu" "F.Mask" "F.Paste")
			(net "PHY_DRV_B_TO_SCC_B_7_DN")
		)
		(pad "S6" smd rect
			(at 9.525 -1.82499 270)
			(size 0.6096 2.3622)
			(layers "F.Cu" "F.Mask" "F.Paste")
			(net "PHY_DRV_B_TO_SCC_B_7_DP")
		)
		(pad "S7" smd rect
			(at 8.255 -1.82499 270)
			(size 0.6096 2.3622)
			(layers "F.Cu" "F.Mask" "F.Paste")
			(net "GND")
		)
		(pad "S8" smd rect
			(at 7.480046 2.845054 270)
			(size 0.508 2.3622)
			(layers "F.Cu" "F.Mask" "F.Paste")
			(net "GND")
		)
		(pad "S9" smd rect
			(at 6.679946 2.845054 270)
			(size 0.508 2.3622)
			(layers "F.Cu" "F.Mask" "F.Paste")
			(net "Net_465")
		)
		(pad "S10" smd rect
			(at 5.8801 2.845054 270)
			(size 0.508 2.3622)
			(layers "F.Cu" "F.Mask" "F.Paste")
			(net "Net_357")
		)
		(pad "S11" smd rect
			(at 5.08 2.845054 270)
			(size 0.508 2.3622)
			(layers "F.Cu" "F.Mask" "F.Paste")
			(net "GND")
		)
		(pad "S12" smd rect
			(at 4.2799 2.845054 270)
			(size 0.508 2.3622)
			(layers "F.Cu" "F.Mask" "F.Paste")
			(net "Net_393")
		)
		(pad "S13" smd rect
			(at 3.480054 2.845054 270)
			(size 0.508 2.3622)
			(layers "F.Cu" "F.Mask" "F.Paste")
			(net "Net_429")
		)
		(pad "S14" smd rect
			(at 2.679954 2.845054 270)
			(size 0.508 2.3622)
			(layers "F.Cu" "F.Mask" "F.Paste")
			(net "GND")
		)
		(zone
			(layer "F.Cu")
			(hatch none 0.5)
			(connect_pads
				(clearance 0)
			)
			(min_thickness 0.25)
			(keepout
				(tracks allowed)
				(vias not_allowed)
				(pads allowed)
				(copperpour not_allowed)
				(footprints allowed)
			)
			(placement
				(enabled no)
				(sheetname "")
			)
			(fill
				(thermal_gap 0.5)
				(thermal_bridge_width 0.5)
				(island_removal_mode 0)
			)
			(polygon
				(pts
					(xy 360.757724 -275.648674) (xy 353.683824 -275.648674) (xy 353.683824 -282.582874) (xy 354.788724 -282.582874)
					(xy 354.788724 -278.468074) (xy 359.411524 -278.468074) (xy 359.411524 -282.582874) (xy 360.757724 -282.582874)
				)
			)
		)
		(zone
			(layer "F.Cu")
			(hatch none 0.5)
			(connect_pads
				(clearance 0)
			)
			(min_thickness 0.25)
			(keepout
				(tracks not_allowed)
				(vias allowed)
				(pads allowed)
				(copperpour not_allowed)
				(footprints allowed)
			)
			(placement
				(enabled no)
				(sheetname "")
			)
			(fill
				(thermal_gap 0.5)
				(thermal_bridge_width 0.5)
				(island_removal_mode 0)
			)
			(polygon
				(pts
					(xy 360.757724 -275.648674) (xy 353.683824 -275.648674) (xy 353.683824 -282.582874) (xy 354.788724 -282.582874)
					(xy 354.788724 -278.468074) (xy 359.411524 -278.468074) (xy 359.411524 -282.582874) (xy 360.757724 -282.582874)
				)
			)
		)
		(zone
			(layer "F.Cu")
			(hatch none 0.5)
			(connect_pads
				(clearance 0)
			)
			(min_thickness 0.25)
			(keepout
				(tracks not_allowed)
				(vias allowed)
				(pads allowed)
				(copperpour not_allowed)
				(footprints allowed)
			)
			(placement
				(enabled no)
				(sheetname "")
			)
			(fill
				(thermal_gap 0.5)
				(thermal_bridge_width 0.5)
				(island_removal_mode 0)
			)
			(polygon
				(pts
					(xy 360.757724 -242.171474) (xy 353.683824 -242.171474) (xy 353.683824 -235.237274) (xy 354.788724 -235.237274)
					(xy 354.788724 -239.352074) (xy 359.411524 -239.352074) (xy 359.411524 -235.237274) (xy 360.757724 -235.237274)
				)
			)
		)
		(zone
			(layer "F.Cu")
			(hatch none 0.5)
			(connect_pads
				(clearance 0)
			)
			(min_thickness 0.25)
			(keepout
				(tracks allowed)
				(vias not_allowed)
				(pads allowed)
				(copperpour not_allowed)
				(footprints allowed)
			)
			(placement
				(enabled no)
				(sheetname "")
			)
			(fill
				(thermal_gap 0.5)
				(thermal_bridge_width 0.5)
				(island_removal_mode 0)
			)
			(polygon
				(pts
					(xy 360.757724 -242.171474) (xy 353.683824 -242.171474) (xy 353.683824 -235.237274) (xy 354.788724 -235.237274)
					(xy 354.788724 -239.352074) (xy 359.411524 -239.352074) (xy 359.411524 -235.237274) (xy 360.757724 -235.237274)
				)
			)
		)
		(zone
			(layers "F.Cu" "B.Cu" "In1.Cu" "In2.Cu" "In3.Cu" "In4.Cu" "In5.Cu" "In6.Cu")
			(hatch none 0.5)
			(connect_pads
				(clearance 0)
			)
			(min_thickness 0.25)
			(keepout
				(tracks not_allowed)
				(vias allowed)
				(pads allowed)
				(copperpour not_allowed)
				(footprints allowed)
			)
			(placement
				(enabled no)
				(sheetname "")
			)
			(fill
				(thermal_gap 0.5)
				(thermal_bridge_width 0.5)
				(island_removal_mode 0)
			)
			(polygon
				(pts
					(arc
						(start 357.874824 -240.03508)
						(mid 356.325424 -240.03508)
						(end 357.874824 -240.03508)
					)
				)
			)
		)
		(zone
			(layers "F.Cu" "B.Cu" "In1.Cu" "In2.Cu" "In3.Cu" "In4.Cu" "In5.Cu" "In6.Cu")
			(hatch none 0.5)
			(connect_pads
				(clearance 0)
			)
			(min_thickness 0.25)
			(keepout
				(tracks not_allowed)
				(vias allowed)
				(pads allowed)
				(copperpour not_allowed)
				(footprints allowed)
			)
			(placement
				(enabled no)
				(sheetname "")
			)
			(fill
				(thermal_gap 0.5)
				(thermal_bridge_width 0.5)
				(island_removal_mode 0)
			)
			(polygon
				(pts
					(arc
						(start 358.078024 -277.785068)
						(mid 356.122224 -277.785068)
						(end 358.078024 -277.785068)
					)
				)
			)
		)
	)
	(footprint ""
		(layer "F.Cu")
		(at 159.512 -31.623 180)
		(property "Reference" "R714"
			(at 0 0 180)
			(layer "F.SilkS")
			(hide yes)
			(effects
				(font
					(size 1.27 1.27)
				)
			)
		)
		(property "Value" "10KR2F-2-GP"
			(at 0.064008 -3.993896 180)
			(unlocked yes)
			(layer "F.Fab")
			(hide yes)
			(effects
				(font
					(size 1.016 1.016)
					(thickness 0.1524)
				)
			)
		)
		(property "Device Type" "R402H16"
			(at 0.064008 -5.517896 180)
			(unlocked yes)
			(layer "F.Fab")
			(hide yes)
			(effects
				(font
					(size 1.016 1.016)
					(thickness 0.1524)
				)
			)
		)
		(duplicate_pad_numbers_are_jumpers no)
		(fp_line
			(start 0.508 -0.9398)
			(end -0.508 -0.9398)
			(stroke
				(width 0.1524)
				(type default)
			)
			(layer "F.SilkS")
		)
		(fp_line
			(start -0.508 -0.9398)
			(end -0.508 0.9398)
			(stroke
				(width 0.1524)
				(type default)
			)
			(layer "F.SilkS")
		)
		(fp_rect
			(start -0.508 0.9398)
			(end 0.508 -0.9398)
			(stroke
				(width 0)
				(type default)
			)
			(fill no)
			(layer "F.CrtYd")
		)
		(fp_rect
			(start -0.508 0.9398)
			(end 0.508 -0.9398)
			(stroke
				(width 0)
				(type default)
			)
			(fill no)
			(layer "F.Fab")
		)
		(pad "1" smd custom
			(at 0 -0.4445 180)
			(size 0.1397 0.1397)
			(layers "F.Cu" "F.Mask" "F.Paste")
			(net "P3V3_STBY_B")
			(options
				(clearance outline)
				(anchor circle)
			)
			(primitives
				(gr_poly
					(pts
						(arc
							(start -0.1778 -0.2794)
							(mid -0.249642 -0.249642)
							(end -0.2794 -0.1778)
						)
						(arc
							(start -0.2794 0.1778)
							(mid -0.249642 0.249642)
							(end -0.1778 0.2794)
						)
						(arc
							(start 0.1778 0.2794)
							(mid 0.249642 0.249642)
							(end 0.2794 0.1778)
						)
						(arc
							(start 0.2794 -0.1778)
							(mid 0.249642 -0.249642)
							(end 0.1778 -0.2794)
						)
					)
					(width 0)
					(fill yes)
				)
			)
		)
		(pad "2" smd custom
			(at 0 0.4445 180)
			(size 0.1397 0.1397)
			(layers "F.Cu" "F.Mask" "F.Paste")
			(net "HDD_PRSNT_28")
			(options
				(clearance outline)
				(anchor circle)
			)
			(primitives
				(gr_poly
					(pts
						(arc
							(start -0.1778 -0.2794)
							(mid -0.249642 -0.249642)
							(end -0.2794 -0.1778)
						)
						(arc
							(start -0.2794 0.1778)
							(mid -0.249642 0.249642)
							(end -0.1778 0.2794)
						)
						(arc
							(start 0.1778 0.2794)
							(mid 0.249642 0.249642)
							(end 0.2794 0.1778)
						)
						(arc
							(start 0.2794 -0.1778)
							(mid 0.249642 -0.249642)
							(end 0.1778 -0.2794)
						)
					)
					(width 0)
					(fill yes)
				)
			)
		)
	)
	(footprint ""
		(layer "F.Cu")
		(at 133.7818 -368.8334 90)
		(property "Reference" "R938"
			(at 0 0 90)
			(layer "F.SilkS")
			(hide yes)
			(effects
				(font
					(size 1.27 1.27)
				)
			)
		)
		(property "Value" "4K7R2F-GP"
			(at 0.064008 -3.993896 90)
			(unlocked yes)
			(layer "F.Fab")
			(hide yes)
			(effects
				(font
					(size 1.016 1.016)
					(thickness 0.1524)
				)
			)
		)
		(property "Device Type" "R402H16"
			(at 0.064008 -5.517896 90)
			(unlocked yes)
			(layer "F.Fab")
			(hide yes)
			(effects
				(font
					(size 1.016 1.016)
					(thickness 0.1524)
				)
			)
		)
		(duplicate_pad_numbers_are_jumpers no)
		(fp_line
			(start 0.508 -0.9398)
			(end -0.508 -0.9398)
			(stroke
				(width 0.1524)
				(type default)
			)
			(layer "F.SilkS")
		)
		(fp_line
			(start -0.508 -0.9398)
			(end -0.508 0.9398)
			(stroke
				(width 0.1524)
				(type default)
			)
			(layer "F.SilkS")
		)
		(fp_rect
			(start -0.508 0.9398)
			(end 0.508 -0.9398)
			(stroke
				(width 0)
				(type default)
			)
			(fill no)
			(layer "F.CrtYd")
		)
		(fp_rect
			(start -0.508 0.9398)
			(end 0.508 -0.9398)
			(stroke
				(width 0)
				(type default)
			)
			(fill no)
			(layer "F.Fab")
		)
		(pad "1" smd custom
			(at 0 -0.4445 90)
			(size 0.1397 0.1397)
			(layers "F.Cu" "F.Mask" "F.Paste")
			(net "P12V_IN")
			(options
				(clearance outline)
				(anchor circle)
			)
			(primitives
				(gr_poly
					(pts
						(arc
							(start -0.1778 -0.2794)
							(mid -0.249642 -0.249642)
							(end -0.2794 -0.1778)
						)
						(arc
							(start -0.2794 0.1778)
							(mid -0.249642 0.249642)
							(end -0.1778 0.2794)
						)
						(arc
							(start 0.1778 0.2794)
							(mid 0.249642 0.249642)
							(end 0.2794 0.1778)
						)
						(arc
							(start 0.2794 -0.1778)
							(mid 0.249642 -0.249642)
							(end 0.1778 -0.2794)
						)
					)
					(width 0)
					(fill yes)
				)
			)
		)
		(pad "2" smd custom
			(at 0 0.4445 90)
			(size 0.1397 0.1397)
			(layers "F.Cu" "F.Mask" "F.Paste")
			(net "FAN_1_TACH1")
			(options
				(clearance outline)
				(anchor circle)
			)
			(primitives
				(gr_poly
					(pts
						(arc
							(start -0.1778 -0.2794)
							(mid -0.249642 -0.249642)
							(end -0.2794 -0.1778)
						)
						(arc
							(start -0.2794 0.1778)
							(mid -0.249642 0.249642)
							(end -0.1778 0.2794)
						)
						(arc
							(start 0.1778 0.2794)
							(mid 0.249642 0.249642)
							(end 0.2794 0.1778)
						)
						(arc
							(start 0.2794 -0.1778)
							(mid 0.249642 -0.249642)
							(end 0.1778 -0.2794)
						)
					)
					(width 0)
					(fill yes)
				)
			)
		)
	)
	(footprint ""
		(layer "F.Cu")
		(at 347.345 -214.376)
		(property "Reference" "R317"
			(at 0 0 0)
			(layer "F.SilkS")
			(hide yes)
			(effects
				(font
					(size 1.27 1.27)
				)
			)
		)
		(property "Value" "91R3F-1-GP"
			(at -0.0254 -2.5146 0)
			(unlocked yes)
			(layer "F.Fab")
			(hide yes)
			(effects
				(font
					(size 1.016 1.016)
					(thickness 0.1524)
				)
			)
		)
		(property "Device Type" "R603H22"
			(at -0.0254 -4.0386 0)
			(unlocked yes)
			(layer "F.Fab")
			(hide yes)
			(effects
				(font
					(size 1.016 1.016)
					(thickness 0.1524)
				)
			)
		)
		(duplicate_pad_numbers_are_jumpers no)
		(fp_line
			(start -0.4826 0)
			(end -0.2032 0)
			(stroke
				(width 0.2032)
				(type default)
			)
			(layer "F.SilkS")
		)
		(fp_line
			(start 0.2032 0)
			(end 0.4826 0)
			(stroke
				(width 0.2032)
				(type default)
			)
			(layer "F.SilkS")
		)
		(fp_rect
			(start -0.5842 1.3335)
			(end 0.5842 -1.3335)
			(stroke
				(width 0)
				(type default)
			)
			(fill no)
			(layer "F.CrtYd")
		)
		(fp_rect
			(start -0.5842 1.3335)
			(end 0.5842 -1.3335)
			(stroke
				(width 0)
				(type default)
			)
			(fill no)
			(layer "F.Fab")
		)
		(pad "1" smd custom
			(at 0 -0.762)
			(size 0.2159 0.2159)
			(layers "F.Cu" "F.Mask" "F.Paste")
			(net "P5V_B_3")
			(options
				(clearance outline)
				(anchor circle)
			)
			(primitives
				(gr_poly
					(pts
						(arc
							(start -0.3302 -0.4318)
							(mid -0.402042 -0.402042)
							(end -0.4318 -0.3302)
						)
						(arc
							(start -0.4318 0.3302)
							(mid -0.402042 0.402042)
							(end -0.3302 0.4318)
						)
						(arc
							(start 0.3302 0.4318)
							(mid 0.402042 0.402042)
							(end 0.4318 0.3302)
						)
						(arc
							(start 0.4318 -0.3302)
							(mid 0.402042 -0.402042)
							(end 0.3302 -0.4318)
						)
					)
					(width 0)
					(fill yes)
				)
			)
		)
		(pad "2" smd custom
			(at 0 0.762)
			(size 0.2159 0.2159)
			(layers "F.Cu" "F.Mask" "F.Paste")
			(net "DRV_ACT_7")
			(options
				(clearance outline)
				(anchor circle)
			)
			(primitives
				(gr_poly
					(pts
						(arc
							(start -0.3302 -0.4318)
							(mid -0.402042 -0.402042)
							(end -0.4318 -0.3302)
						)
						(arc
							(start -0.4318 0.3302)
							(mid -0.402042 0.402042)
							(end -0.3302 0.4318)
						)
						(arc
							(start 0.3302 0.4318)
							(mid 0.402042 0.402042)
							(end 0.4318 0.3302)
						)
						(arc
							(start 0.4318 -0.3302)
							(mid 0.402042 -0.402042)
							(end 0.3302 -0.4318)
						)
					)
					(width 0)
					(fill yes)
				)
			)
		)
	)
	(footprint ""
		(layer "F.Cu")
		(at 19.37766 -223.994218 90)
		(property "Reference" "C621"
			(at 0 0 90)
			(layer "F.SilkS")
			(hide yes)
			(effects
				(font
					(size 1.27 1.27)
				)
			)
		)
		(property "Value" "SC10U16V5KX-7-GP-U"
			(at -0.0762 -6.1214 90)
			(unlocked yes)
			(layer "F.Fab")
			(hide yes)
			(effects
				(font
					(size 1.016 1.016)
					(thickness 0.1524)
				)
			)
		)
		(property "Device Type" "C805H58"
			(at -0.0762 -8.1534 90)
			(unlocked yes)
			(layer "F.Fab")
			(hide yes)
			(effects
				(font
					(size 1.016 1.016)
					(thickness 0.1524)
				)
			)
		)
		(duplicate_pad_numbers_are_jumpers no)
		(fp_line
			(start 0.635 0)
			(end -0.635 0)
			(stroke
				(width 0.508)
				(type default)
			)
			(layer "F.SilkS")
		)
		(fp_rect
			(start -0.9652 1.778)
			(end 0.9652 -1.778)
			(stroke
				(width 0)
				(type default)
			)
			(fill no)
			(layer "F.CrtYd")
		)
		(fp_poly
			(pts
				(xy -0.9652 -1.778) (xy 0.9652 -1.778) (xy 0.9652 1.778) (xy -0.9652 1.778)
			)
			(stroke
				(width 0)
				(type default)
			)
			(fill no)
			(layer "F.Fab")
		)
		(pad "1" smd rect
			(at 0 -0.9652 90)
			(size 1.397 1.143)
			(layers "F.Cu" "F.Mask" "F.Paste")
			(net "P12V_B_1_VIN_U31")
		)
		(pad "2" smd rect
			(at 0 0.9652 90)
			(size 1.397 1.143)
			(layers "F.Cu" "F.Mask" "F.Paste")
			(net "GND")
		)
	)
	(footprint ""
		(layer "F.Cu")
		(at 327.373996 -370.078 90)
		(property "Reference" "R945"
			(at 0 0 90)
			(layer "F.SilkS")
			(hide yes)
			(effects
				(font
					(size 1.27 1.27)
				)
			)
		)
		(property "Value" "27KR3F-GP"
			(at -0.0254 -2.5146 90)
			(unlocked yes)
			(layer "F.Fab")
			(hide yes)
			(effects
				(font
					(size 1.016 1.016)
					(thickness 0.1524)
				)
			)
		)
		(property "Device Type" "R603H22"
			(at -0.0254 -4.0386 90)
			(unlocked yes)
			(layer "F.Fab")
			(hide yes)
			(effects
				(font
					(size 1.016 1.016)
					(thickness 0.1524)
				)
			)
		)
		(duplicate_pad_numbers_are_jumpers no)
		(fp_line
			(start 0.2032 0)
			(end 0.4826 0)
			(stroke
				(width 0.2032)
				(type default)
			)
			(layer "F.SilkS")
		)
		(fp_line
			(start -0.4826 0)
			(end -0.2032 0)
			(stroke
				(width 0.2032)
				(type default)
			)
			(layer "F.SilkS")
		)
		(fp_rect
			(start -0.5842 1.3335)
			(end 0.5842 -1.3335)
			(stroke
				(width 0)
				(type default)
			)
			(fill no)
			(layer "F.CrtYd")
		)
		(fp_rect
			(start -0.5842 1.3335)
			(end 0.5842 -1.3335)
			(stroke
				(width 0)
				(type default)
			)
			(fill no)
			(layer "F.Fab")
		)
		(pad "1" smd custom
			(at 0 -0.762 90)
			(size 0.2159 0.2159)
			(layers "F.Cu" "F.Mask" "F.Paste")
			(net "FANTACH_R2")
			(options
				(clearance outline)
				(anchor circle)
			)
			(primitives
				(gr_poly
					(pts
						(arc
							(start -0.3302 -0.4318)
							(mid -0.402042 -0.402042)
							(end -0.4318 -0.3302)
						)
						(arc
							(start -0.4318 0.3302)
							(mid -0.402042 0.402042)
							(end -0.3302 0.4318)
						)
						(arc
							(start 0.3302 0.4318)
							(mid 0.402042 0.402042)
							(end 0.4318 0.3302)
						)
						(arc
							(start 0.4318 -0.3302)
							(mid 0.402042 -0.402042)
							(end 0.3302 -0.4318)
						)
					)
					(width 0)
					(fill yes)
				)
			)
		)
		(pad "2" smd custom
			(at 0 0.762 90)
			(size 0.2159 0.2159)
			(layers "F.Cu" "F.Mask" "F.Paste")
			(net "FAN_2_TACH0")
			(options
				(clearance outline)
				(anchor circle)
			)
			(primitives
				(gr_poly
					(pts
						(arc
							(start -0.3302 -0.4318)
							(mid -0.402042 -0.402042)
							(end -0.4318 -0.3302)
						)
						(arc
							(start -0.4318 0.3302)
							(mid -0.402042 0.402042)
							(end -0.3302 0.4318)
						)
						(arc
							(start 0.3302 0.4318)
							(mid 0.402042 0.402042)
							(end 0.4318 0.3302)
						)
						(arc
							(start 0.4318 -0.3302)
							(mid 0.402042 -0.402042)
							(end 0.3302 -0.4318)
						)
					)
					(width 0)
					(fill yes)
				)
			)
		)
	)
	(footprint ""
		(layer "F.Cu")
		(at 176.657 -150.622 90)
		(property "Reference" "R462"
			(at 0 0 90)
			(layer "F.SilkS")
			(hide yes)
			(effects
				(font
					(size 1.27 1.27)
				)
			)
		)
		(property "Value" "2R6F-GP"
			(at -0.0508 -4.8514 90)
			(unlocked yes)
			(layer "F.Fab")
			(hide yes)
			(effects
				(font
					(size 1.016 1.016)
					(thickness 0.1524)
				)
			)
		)
		(property "Device Type" "R1206H26"
			(at 0 -6.3754 90)
			(unlocked yes)
			(layer "F.Fab")
			(hide yes)
			(effects
				(font
					(size 1.016 1.016)
					(thickness 0.1524)
				)
			)
		)
		(duplicate_pad_numbers_are_jumpers no)
		(fp_line
			(start 1.016 -2.2352)
			(end 1.016 2.2352)
			(stroke
				(width 0.1524)
				(type default)
			)
			(layer "F.SilkS")
		)
		(fp_line
			(start -1.016 -2.2352)
			(end 1.016 -2.2352)
			(stroke
				(width 0.1524)
				(type default)
			)
			(layer "F.SilkS")
		)
		(fp_line
			(start 1.016 2.2352)
			(end -1.016 2.2352)
			(stroke
				(width 0.1524)
				(type default)
			)
			(layer "F.SilkS")
		)
		(fp_line
			(start -1.016 2.2352)
			(end -1.016 -2.2352)
			(stroke
				(width 0.1524)
				(type default)
			)
			(layer "F.SilkS")
		)
		(fp_rect
			(start -1.0922 2.3114)
			(end 1.0922 -2.3114)
			(stroke
				(width 0)
				(type default)
			)
			(fill no)
			(layer "F.CrtYd")
		)
		(fp_poly
			(pts
				(xy -1.0922 -2.3114) (xy 1.0922 -2.3114) (xy 1.0922 2.3114) (xy -1.0922 2.3114)
			)
			(stroke
				(width 0)
				(type default)
			)
			(fill no)
			(layer "F.Fab")
		)
		(pad "1" smd rect
			(at 0 -1.397 90)
			(size 1.651 1.27)
			(layers "F.Cu" "F.Mask" "F.Paste")
			(net "P12V_HDD17")
		)
		(pad "2" smd rect
			(at 0 1.397 90)
			(size 1.651 1.27)
			(layers "F.Cu" "F.Mask" "F.Paste")
			(net "12V_PRE_17")
		)
	)
	(footprint ""
		(layer "F.Cu")
		(at 368.808 -133.858 90)
		(property "Reference" "D19"
			(at 0 0 90)
			(layer "F.SilkS")
			(hide yes)
			(effects
				(font
					(size 1.27 1.27)
				)
			)
		)
		(property "Value" "RB551V30-GP"
			(at 0 -6.7818 90)
			(unlocked yes)
			(layer "F.Fab")
			(hide yes)
			(effects
				(font
					(size 1.016 1.016)
					(thickness 0.1524)
				)
			)
		)
		(property "Device Type" "SOD323AKH38"
			(at 0 -8.6868 90)
			(unlocked yes)
			(layer "F.Fab")
			(hide yes)
			(effects
				(font
					(size 1.016 1.016)
					(thickness 0.1524)
				)
			)
		)
		(duplicate_pad_numbers_are_jumpers no)
		(fp_line
			(start 0.889 -1.9304)
			(end 0.889 2.159)
			(stroke
				(width 0.1524)
				(type default)
			)
			(layer "F.SilkS")
		)
		(fp_line
			(start -0.889 -1.9304)
			(end 0.889 -1.9304)
			(stroke
				(width 0.1524)
				(type default)
			)
			(layer "F.SilkS")
		)
		(fp_line
			(start 0.762 2.0574)
			(end -0.762 2.0574)
			(stroke
				(width 0.508)
				(type default)
			)
			(layer "F.SilkS")
		)
		(fp_line
			(start 0.889 2.159)
			(end -0.889 2.159)
			(stroke
				(width 0.1524)
				(type default)
			)
			(layer "F.SilkS")
		)
		(fp_line
			(start -0.889 2.159)
			(end -0.889 -1.9304)
			(stroke
				(width 0.1524)
				(type default)
			)
			(layer "F.SilkS")
		)
		(fp_rect
			(start -1.016 2.3114)
			(end 1.016 -2.0066)
			(stroke
				(width 0)
				(type default)
			)
			(fill no)
			(layer "F.CrtYd")
		)
		(fp_poly
			(pts
				(xy -1.016 -2.0066) (xy 1.016 -2.0066) (xy 1.016 2.3114) (xy -1.016 2.3114)
			)
			(stroke
				(width 0)
				(type default)
			)
			(fill no)
			(layer "F.Fab")
		)
		(pad "A" smd rect
			(at 0 -1.143 90)
			(size 0.5588 1.016)
			(layers "F.Cu" "F.Mask" "F.Paste")
			(net "SW_HDD_R19")
		)
		(pad "K" smd rect
			(at 0 1.143 90)
			(size 0.5588 1.016)
			(layers "F.Cu" "F.Mask" "F.Paste")
			(net "SW_HDD_N19")
		)
	)
	(footprint ""
		(layer "F.Cu")
		(at 220.963998 -352.711766)
		(property "Reference" "R1021"
			(at 0 0 0)
			(layer "F.SilkS")
			(hide yes)
			(effects
				(font
					(size 1.27 1.27)
				)
			)
		)
		(property "Value" "1KR2J-1-GP"
			(at 0.064008 -3.993896 0)
			(unlocked yes)
			(layer "F.Fab")
			(hide yes)
			(effects
				(font
					(size 1.016 1.016)
					(thickness 0.1524)
				)
			)
		)
		(property "Device Type" "R402H16"
			(at 0.064008 -5.517896 0)
			(unlocked yes)
			(layer "F.Fab")
			(hide yes)
			(effects
				(font
					(size 1.016 1.016)
					(thickness 0.1524)
				)
			)
		)
		(duplicate_pad_numbers_are_jumpers no)
		(fp_line
			(start -0.508 -0.9398)
			(end -0.508 0.9398)
			(stroke
				(width 0.1524)
				(type default)
			)
			(layer "F.SilkS")
		)
		(fp_line
			(start 0.508 -0.9398)
			(end -0.508 -0.9398)
			(stroke
				(width 0.1524)
				(type default)
			)
			(layer "F.SilkS")
		)
		(fp_rect
			(start -0.508 0.9398)
			(end 0.508 -0.9398)
			(stroke
				(width 0)
				(type default)
			)
			(fill no)
			(layer "F.CrtYd")
		)
		(fp_rect
			(start -0.508 0.9398)
			(end 0.508 -0.9398)
			(stroke
				(width 0)
				(type default)
			)
			(fill no)
			(layer "F.Fab")
		)
		(pad "1" smd custom
			(at 0 -0.4445)
			(size 0.1397 0.1397)
			(layers "F.Cu" "F.Mask" "F.Paste")
			(net "MB0_CM_VOUT_R")
			(options
				(clearance outline)
				(anchor circle)
			)
			(primitives
				(gr_poly
					(pts
						(arc
							(start -0.1778 -0.2794)
							(mid -0.249642 -0.249642)
							(end -0.2794 -0.1778)
						)
						(arc
							(start -0.2794 0.1778)
							(mid -0.249642 0.249642)
							(end -0.1778 0.2794)
						)
						(arc
							(start 0.1778 0.2794)
							(mid 0.249642 0.249642)
							(end 0.2794 0.1778)
						)
						(arc
							(start 0.2794 -0.1778)
							(mid 0.249642 -0.249642)
							(end 0.1778 -0.2794)
						)
					)
					(width 0)
					(fill yes)
				)
			)
		)
		(pad "2" smd custom
			(at 0 0.4445)
			(size 0.1397 0.1397)
			(layers "F.Cu" "F.Mask" "F.Paste")
			(net "P12V_IN")
			(options
				(clearance outline)
				(anchor circle)
			)
			(primitives
				(gr_poly
					(pts
						(arc
							(start -0.1778 -0.2794)
							(mid -0.249642 -0.249642)
							(end -0.2794 -0.1778)
						)
						(arc
							(start -0.2794 0.1778)
							(mid -0.249642 0.249642)
							(end -0.1778 0.2794)
						)
						(arc
							(start 0.1778 0.2794)
							(mid 0.249642 0.249642)
							(end 0.2794 0.1778)
						)
						(arc
							(start 0.2794 -0.1778)
							(mid 0.249642 -0.249642)
							(end 0.1778 -0.2794)
						)
					)
					(width 0)
					(fill yes)
				)
			)
		)
	)
	(footprint ""
		(layer "F.Cu")
		(at 478.79 -148.209)
		(property "Reference" "R598"
			(at 0 0 0)
			(layer "F.SilkS")
			(hide yes)
			(effects
				(font
					(size 1.27 1.27)
				)
			)
		)
		(property "Value" "2R6F-GP"
			(at -0.0508 -4.8514 0)
			(unlocked yes)
			(layer "F.Fab")
			(hide yes)
			(effects
				(font
					(size 1.016 1.016)
					(thickness 0.1524)
				)
			)
		)
		(property "Device Type" "R1206H26"
			(at 0 -6.3754 0)
			(unlocked yes)
			(layer "F.Fab")
			(hide yes)
			(effects
				(font
					(size 1.016 1.016)
					(thickness 0.1524)
				)
			)
		)
		(duplicate_pad_numbers_are_jumpers no)
		(fp_line
			(start -1.016 -2.2352)
			(end 1.016 -2.2352)
			(stroke
				(width 0.1524)
				(type default)
			)
			(layer "F.SilkS")
		)
		(fp_line
			(start -1.016 2.2352)
			(end -1.016 -2.2352)
			(stroke
				(width 0.1524)
				(type default)
			)
			(layer "F.SilkS")
		)
		(fp_line
			(start 1.016 -2.2352)
			(end 1.016 2.2352)
			(stroke
				(width 0.1524)
				(type default)
			)
			(layer "F.SilkS")
		)
		(fp_line
			(start 1.016 2.2352)
			(end -1.016 2.2352)
			(stroke
				(width 0.1524)
				(type default)
			)
			(layer "F.SilkS")
		)
		(fp_rect
			(start -1.0922 2.3114)
			(end 1.0922 -2.3114)
			(stroke
				(width 0)
				(type default)
			)
			(fill no)
			(layer "F.CrtYd")
		)
		(fp_poly
			(pts
				(xy -1.0922 -2.3114) (xy 1.0922 -2.3114) (xy 1.0922 2.3114) (xy -1.0922 2.3114)
			)
			(stroke
				(width 0)
				(type default)
			)
			(fill no)
			(layer "F.Fab")
		)
		(pad "1" smd rect
			(at 0 -1.397)
			(size 1.651 1.27)
			(layers "F.Cu" "F.Mask" "F.Paste")
			(net "P5V_HDD23")
		)
		(pad "2" smd rect
			(at 0 1.397)
			(size 1.651 1.27)
			(layers "F.Cu" "F.Mask" "F.Paste")
			(net "5V_PRE_23")
		)
	)
	(footprint ""
		(layer "F.Cu")
		(at 146.939 -26.289 180)
		(property "Reference" "Q142"
			(at 0 0 180)
			(layer "F.SilkS")
			(hide yes)
			(effects
				(font
					(size 1.27 1.27)
				)
			)
		)
		(property "Value" "AO4406AL-GP"
			(at -3.707384 -1.5367 180)
			(unlocked yes)
			(layer "F.Fab")
			(hide yes)
			(effects
				(font
					(size 1.016 1.016)
					(thickness 0.1524)
				)
			)
		)
		(property "Device Type" "SOIC8H69"
			(at -3.707384 -3.0607 180)
			(unlocked yes)
			(layer "F.Fab")
			(hide yes)
			(effects
				(font
					(size 1.016 1.016)
					(thickness 0.1524)
				)
			)
		)
		(duplicate_pad_numbers_are_jumpers no)
		(fp_line
			(start 2.1336 1.4224)
			(end 2.1336 -1.4224)
			(stroke
				(width 0.1524)
				(type default)
			)
			(layer "F.SilkS")
		)
		(fp_line
			(start 2.1336 -1.4224)
			(end -2.7432 -1.4224)
			(stroke
				(width 0.1524)
				(type default)
			)
			(layer "F.SilkS")
		)
		(fp_line
			(start -2.1844 -0.0508)
			(end -2.7178 0.508)
			(stroke
				(width 0.1524)
				(type default)
			)
			(layer "F.SilkS")
		)
		(fp_line
			(start -2.6289 3.4417)
			(end -2.6289 1.4732)
			(stroke
				(width 0.381)
				(type default)
			)
			(layer "F.SilkS")
		)
		(fp_line
			(start -2.7178 -0.508)
			(end -2.1844 -0.0508)
			(stroke
				(width 0.1524)
				(type default)
			)
			(layer "F.SilkS")
		)
		(fp_line
			(start -2.7432 1.4224)
			(end 2.1336 1.4224)
			(stroke
				(width 0.1524)
				(type default)
			)
			(layer "F.SilkS")
		)
		(fp_line
			(start -2.7432 1.4224)
			(end -2.6416 1.4224)
			(stroke
				(width 0.1524)
				(type default)
			)
			(layer "F.SilkS")
		)
		(fp_line
			(start -2.7432 -1.4224)
			(end -2.7432 1.4224)
			(stroke
				(width 0.1524)
				(type default)
			)
			(layer "F.SilkS")
		)
		(fp_poly
			(pts
				(xy -2.2098 -1.4224) (xy -2.2098 1.4224) (xy 2.2098 1.4224) (xy 2.2098 -1.4224)
			)
			(stroke
				(width 0)
				(type default)
			)
			(fill yes)
			(layer "F.SilkS")
		)
		(fp_rect
			(start -2.450084 2.999994)
			(end 2.450084 -2.999994)
			(stroke
				(width 0)
				(type default)
			)
			(fill no)
			(layer "F.CrtYd")
		)
		(fp_poly
			(pts
				(xy -2.8194 3.6322) (xy -2.8194 -3.6322) (xy 2.8194 -3.6322) (xy 2.8194 1.18364) (xy 2.450084 1.18364)
				(xy 2.450084 -2.999994) (xy -2.450084 -2.999994) (xy -2.450084 2.999994) (xy 2.450084 2.999994)
				(xy 2.450084 1.18618) (xy 2.8194 1.18618) (xy 2.8194 3.6322)
			)
			(stroke
				(width 0)
				(type default)
			)
			(fill no)
			(layer "F.CrtYd")
		)
		(fp_rect
			(start -2.8194 3.6322)
			(end 2.8194 -3.6322)
			(stroke
				(width 0)
				(type default)
			)
			(fill no)
			(layer "F.Fab")
		)
		(pad "1" smd rect
			(at -1.905 2.54 180)
			(size 0.635 1.651)
			(layers "F.Cu" "F.Mask" "F.Paste")
			(net "P5V_HDD28")
		)
		(pad "2" smd rect
			(at -0.635 2.54 180)
			(size 0.635 1.651)
			(layers "F.Cu" "F.Mask" "F.Paste")
			(net "P5V_HDD28")
		)
		(pad "3" smd rect
			(at 0.635 2.54 180)
			(size 0.635 1.651)
			(layers "F.Cu" "F.Mask" "F.Paste")
			(net "P5V_HDD28")
		)
		(pad "4" smd rect
			(at 1.905 2.54 180)
			(size 0.635 1.651)
			(layers "F.Cu" "F.Mask" "F.Paste")
			(net "SW_HDD_P28")
		)
		(pad "5" smd rect
			(at 1.905 -2.54 180)
			(size 0.635 1.651)
			(layers "F.Cu" "F.Mask" "F.Paste")
			(net "P5V_B_2")
		)
		(pad "6" smd rect
			(at 0.635 -2.54 180)
			(size 0.635 1.651)
			(layers "F.Cu" "F.Mask" "F.Paste")
			(net "P5V_B_2")
		)
		(pad "7" smd rect
			(at -0.635 -2.54 180)
			(size 0.635 1.651)
			(layers "F.Cu" "F.Mask" "F.Paste")
			(net "P5V_B_2")
		)
		(pad "8" smd rect
			(at -1.905 -2.54 180)
			(size 0.635 1.651)
			(layers "F.Cu" "F.Mask" "F.Paste")
			(net "P5V_B_2")
		)
	)
	(footprint ""
		(layer "F.Cu")
		(at 461.899 -246.761 180)
		(property "Reference" "R331"
			(at 0 0 180)
			(layer "F.SilkS")
			(hide yes)
			(effects
				(font
					(size 1.27 1.27)
				)
			)
		)
		(property "Value" "0R2J-2-GP"
			(at 0.064008 -3.993896 180)
			(unlocked yes)
			(layer "F.Fab")
			(hide yes)
			(effects
				(font
					(size 1.016 1.016)
					(thickness 0.1524)
				)
			)
		)
		(property "Device Type" "R402H16"
			(at 0.064008 -5.517896 180)
			(unlocked yes)
			(layer "F.Fab")
			(hide yes)
			(effects
				(font
					(size 1.016 1.016)
					(thickness 0.1524)
				)
			)
		)
		(duplicate_pad_numbers_are_jumpers no)
		(fp_line
			(start 0.508 -0.9398)
			(end -0.508 -0.9398)
			(stroke
				(width 0.1524)
				(type default)
			)
			(layer "F.SilkS")
		)
		(fp_line
			(start -0.508 -0.9398)
			(end -0.508 0.9398)
			(stroke
				(width 0.1524)
				(type default)
			)
			(layer "F.SilkS")
		)
		(fp_rect
			(start -0.508 0.9398)
			(end 0.508 -0.9398)
			(stroke
				(width 0)
				(type default)
			)
			(fill no)
			(layer "F.CrtYd")
		)
		(fp_rect
			(start -0.508 0.9398)
			(end 0.508 -0.9398)
			(stroke
				(width 0)
				(type default)
			)
			(fill no)
			(layer "F.Fab")
		)
		(pad "1" smd custom
			(at 0 -0.4445 180)
			(size 0.1397 0.1397)
			(layers "F.Cu" "F.Mask" "F.Paste")
			(net "SW_HDD_G10")
			(options
				(clearance outline)
				(anchor circle)
			)
			(primitives
				(gr_poly
					(pts
						(arc
							(start -0.1778 -0.2794)
							(mid -0.249642 -0.249642)
							(end -0.2794 -0.1778)
						)
						(arc
							(start -0.2794 0.1778)
							(mid -0.249642 0.249642)
							(end -0.1778 0.2794)
						)
						(arc
							(start 0.1778 0.2794)
							(mid 0.249642 0.249642)
							(end 0.2794 0.1778)
						)
						(arc
							(start 0.2794 -0.1778)
							(mid 0.249642 -0.249642)
							(end 0.1778 -0.2794)
						)
					)
					(width 0)
					(fill yes)
				)
			)
		)
		(pad "2" smd custom
			(at 0 0.4445 180)
			(size 0.1397 0.1397)
			(layers "F.Cu" "F.Mask" "F.Paste")
			(net "SW_HDD_R10")
			(options
				(clearance outline)
				(anchor circle)
			)
			(primitives
				(gr_poly
					(pts
						(arc
							(start -0.1778 -0.2794)
							(mid -0.249642 -0.249642)
							(end -0.2794 -0.1778)
						)
						(arc
							(start -0.2794 0.1778)
							(mid -0.249642 0.249642)
							(end -0.1778 0.2794)
						)
						(arc
							(start 0.1778 0.2794)
							(mid 0.249642 0.249642)
							(end 0.2794 0.1778)
						)
						(arc
							(start 0.2794 -0.1778)
							(mid 0.249642 -0.249642)
							(end 0.1778 -0.2794)
						)
					)
					(width 0)
					(fill yes)
				)
			)
		)
	)
	(footprint ""
		(layer "B.Cu")
		(at 448.018408 -120.594882 -90)
		(property "Reference" "C683"
			(at 0 0 90)
			(layer "B.SilkS")
			(hide yes)
			(effects
				(font
					(size 1.27 1.27)
				)
				(justify mirror)
			)
		)
		(property "Value" "SC470P50V2KX-3GP"
			(at -1.1811 -2.7051 270)
			(unlocked yes)
			(layer "B.Fab")
			(hide yes)
			(effects
				(font
					(size 1.016 1.016)
					(thickness 0.1524)
				)
				(justify mirror)
			)
		)
		(property "Device Type" "C402H22"
			(at -1.1811 -4.2291 270)
			(unlocked yes)
			(layer "B.Fab")
			(hide yes)
			(effects
				(font
					(size 1.016 1.016)
					(thickness 0.1524)
				)
				(justify mirror)
			)
		)
		(duplicate_pad_numbers_are_jumpers no)
		(fp_rect
			(start 0.4318 0.9525)
			(end -0.4318 -0.9525)
			(stroke
				(width 0)
				(type default)
			)
			(fill no)
			(layer "B.CrtYd")
		)
		(fp_rect
			(start 0.4318 0.9525)
			(end -0.4318 -0.9525)
			(stroke
				(width 0)
				(type default)
			)
			(fill no)
			(layer "B.Fab")
		)
		(pad "1" smd custom
			(at 0 -0.4445 90)
			(size 0.1524 0.1524)
			(layers "B.Cu" "B.Mask" "B.Paste")
			(net "P5V_B_4_LL_R")
			(options
				(clearance outline)
				(anchor circle)
			)
			(primitives
				(gr_poly
					(pts
						(arc
							(start 0.3048 0.2032)
							(mid 0.275042 0.275042)
							(end 0.2032 0.3048)
						)
						(arc
							(start -0.2032 0.3048)
							(mid -0.275042 0.275042)
							(end -0.3048 0.2032)
						)
						(arc
							(start -0.3048 -0.2032)
							(mid -0.275042 -0.275042)
							(end -0.2032 -0.3048)
						)
						(arc
							(start 0.2032 -0.3048)
							(mid 0.275042 -0.275042)
							(end 0.3048 -0.2032)
						)
					)
					(width 0)
					(fill yes)
				)
			)
		)
		(pad "2" smd custom
			(at 0 0.4445 90)
			(size 0.1524 0.1524)
			(layers "B.Cu" "B.Mask" "B.Paste")
			(net "P5V_B_4_VFB")
			(options
				(clearance outline)
				(anchor circle)
			)
			(primitives
				(gr_poly
					(pts
						(arc
							(start 0.3048 0.2032)
							(mid 0.275042 0.275042)
							(end 0.2032 0.3048)
						)
						(arc
							(start -0.2032 0.3048)
							(mid -0.275042 0.275042)
							(end -0.3048 0.2032)
						)
						(arc
							(start -0.3048 -0.2032)
							(mid -0.275042 -0.275042)
							(end -0.2032 -0.3048)
						)
						(arc
							(start 0.2032 -0.3048)
							(mid 0.275042 -0.275042)
							(end 0.3048 -0.2032)
						)
					)
					(width 0)
					(fill yes)
				)
			)
		)
	)
	(footprint ""
		(layer "B.Cu")
		(at 243.967 -286.004 180)
		(property "Reference" "C706"
			(at 0 0 0)
			(layer "B.SilkS")
			(hide yes)
			(effects
				(font
					(size 1.27 1.27)
				)
				(justify mirror)
			)
		)
		(property "Value" "SC10U6D3V5KX-4GP"
			(at 0.0762 -6.1214 180)
			(unlocked yes)
			(layer "B.Fab")
			(hide yes)
			(effects
				(font
					(size 1.016 1.016)
					(thickness 0.1524)
				)
				(justify mirror)
			)
		)
		(property "Device Type" "C805H58"
			(at 0.0762 -8.1534 180)
			(unlocked yes)
			(layer "B.Fab")
			(hide yes)
			(effects
				(font
					(size 1.016 1.016)
					(thickness 0.1524)
				)
				(justify mirror)
			)
		)
		(duplicate_pad_numbers_are_jumpers no)
		(fp_line
			(start -0.635 0)
			(end 0.635 0)
			(stroke
				(width 0.508)
				(type default)
			)
			(layer "B.SilkS")
		)
		(fp_rect
			(start 0.9652 1.778)
			(end -0.9652 -1.778)
			(stroke
				(width 0)
				(type default)
			)
			(fill no)
			(layer "B.CrtYd")
		)
		(fp_poly
			(pts
				(xy 0.9652 -1.778) (xy -0.9652 -1.778) (xy -0.9652 1.778) (xy 0.9652 1.778)
			)
			(stroke
				(width 0)
				(type default)
			)
			(fill no)
			(layer "B.Fab")
		)
		(pad "1" smd rect
			(at 0 -0.9652)
			(size 1.397 1.143)
			(layers "B.Cu" "B.Mask" "B.Paste")
			(net "P3V3_STBY_B")
		)
		(pad "2" smd rect
			(at 0 0.9652)
			(size 1.397 1.143)
			(layers "B.Cu" "B.Mask" "B.Paste")
			(net "GND")
		)
	)
	(footprint ""
		(layer "B.Cu")
		(at 449.005198 -118.777004 180)
		(property "Reference" "C680"
			(at 0 0 0)
			(layer "B.SilkS")
			(hide yes)
			(effects
				(font
					(size 1.27 1.27)
				)
				(justify mirror)
			)
		)
		(property "Value" "SCD1U50V3KX-GP"
			(at 0 -2.8194 180)
			(unlocked yes)
			(layer "B.Fab")
			(hide yes)
			(effects
				(font
					(size 1.016 1.016)
					(thickness 0.1524)
				)
				(justify mirror)
			)
		)
		(property "Device Type" "C603H36"
			(at 0 -4.3434 180)
			(unlocked yes)
			(layer "B.Fab")
			(hide yes)
			(effects
				(font
					(size 1.016 1.016)
					(thickness 0.1524)
				)
				(justify mirror)
			)
		)
		(duplicate_pad_numbers_are_jumpers no)
		(fp_line
			(start -0.508 0)
			(end 0.508 0)
			(stroke
				(width 0.2032)
				(type default)
			)
			(layer "B.SilkS")
		)
		(fp_rect
			(start 0.5842 1.3335)
			(end -0.5842 -1.3335)
			(stroke
				(width 0)
				(type default)
			)
			(fill no)
			(layer "B.CrtYd")
		)
		(fp_rect
			(start 0.5842 1.3335)
			(end -0.5842 -1.3335)
			(stroke
				(width 0)
				(type default)
			)
			(fill no)
			(layer "B.Fab")
		)
		(pad "1" smd custom
			(at 0 -0.762)
			(size 0.2159 0.2159)
			(layers "B.Cu" "B.Mask" "B.Paste")
			(net "P5V_B_4")
			(options
				(clearance outline)
				(anchor circle)
			)
			(primitives
				(gr_poly
					(pts
						(arc
							(start -0.3302 0.4318)
							(mid -0.402042 0.402042)
							(end -0.4318 0.3302)
						)
						(arc
							(start -0.4318 -0.3302)
							(mid -0.402042 -0.402042)
							(end -0.3302 -0.4318)
						)
						(arc
							(start 0.3302 -0.4318)
							(mid 0.402042 -0.402042)
							(end 0.4318 -0.3302)
						)
						(arc
							(start 0.4318 0.3302)
							(mid 0.402042 0.402042)
							(end 0.3302 0.4318)
						)
					)
					(width 0)
					(fill yes)
				)
			)
		)
		(pad "2" smd custom
			(at 0 0.762)
			(size 0.2159 0.2159)
			(layers "B.Cu" "B.Mask" "B.Paste")
			(net "P5V_B_4_LL_R")
			(options
				(clearance outline)
				(anchor circle)
			)
			(primitives
				(gr_poly
					(pts
						(arc
							(start -0.3302 0.4318)
							(mid -0.402042 0.402042)
							(end -0.4318 0.3302)
						)
						(arc
							(start -0.4318 -0.3302)
							(mid -0.402042 -0.402042)
							(end -0.3302 -0.4318)
						)
						(arc
							(start 0.3302 -0.4318)
							(mid 0.402042 -0.402042)
							(end 0.4318 -0.3302)
						)
						(arc
							(start 0.4318 0.3302)
							(mid 0.402042 0.402042)
							(end 0.3302 0.4318)
						)
					)
					(width 0)
					(fill yes)
				)
			)
		)
	)
	(footprint ""
		(layer "B.Cu")
		(at 482.285802 -228.35235 180)
		(property "Reference" "C670"
			(at 0 0 0)
			(layer "B.SilkS")
			(hide yes)
			(effects
				(font
					(size 1.27 1.27)
				)
				(justify mirror)
			)
		)
		(property "Value" "SC10U16V5KX-7-GP-U"
			(at 0.0762 -6.1214 180)
			(unlocked yes)
			(layer "B.Fab")
			(hide yes)
			(effects
				(font
					(size 1.016 1.016)
					(thickness 0.1524)
				)
				(justify mirror)
			)
		)
		(property "Device Type" "C805H58"
			(at 0.0762 -8.1534 180)
			(unlocked yes)
			(layer "B.Fab")
			(hide yes)
			(effects
				(font
					(size 1.016 1.016)
					(thickness 0.1524)
				)
				(justify mirror)
			)
		)
		(duplicate_pad_numbers_are_jumpers no)
		(fp_line
			(start -0.635 0)
			(end 0.635 0)
			(stroke
				(width 0.508)
				(type default)
			)
			(layer "B.SilkS")
		)
		(fp_rect
			(start 0.9652 1.778)
			(end -0.9652 -1.778)
			(stroke
				(width 0)
				(type default)
			)
			(fill no)
			(layer "B.CrtYd")
		)
		(fp_poly
			(pts
				(xy 0.9652 -1.778) (xy -0.9652 -1.778) (xy -0.9652 1.778) (xy 0.9652 1.778)
			)
			(stroke
				(width 0)
				(type default)
			)
			(fill no)
			(layer "B.Fab")
		)
		(pad "1" smd rect
			(at 0 -0.9652)
			(size 1.397 1.143)
			(layers "B.Cu" "B.Mask" "B.Paste")
			(net "P5V_B_3")
		)
		(pad "2" smd rect
			(at 0 0.9652)
			(size 1.397 1.143)
			(layers "B.Cu" "B.Mask" "B.Paste")
			(net "GND")
		)
	)
	(footprint ""
		(layer "B.Cu")
		(at 56.155082 -119.72671 -90)
		(property "Reference" "C647"
			(at 0 0 90)
			(layer "B.SilkS")
			(hide yes)
			(effects
				(font
					(size 1.27 1.27)
				)
				(justify mirror)
			)
		)
		(property "Value" "SC470P50V2KX-3GP"
			(at -1.1811 -2.7051 270)
			(unlocked yes)
			(layer "B.Fab")
			(hide yes)
			(effects
				(font
					(size 1.016 1.016)
					(thickness 0.1524)
				)
				(justify mirror)
			)
		)
		(property "Device Type" "C402H22"
			(at -1.1811 -4.2291 270)
			(unlocked yes)
			(layer "B.Fab")
			(hide yes)
			(effects
				(font
					(size 1.016 1.016)
					(thickness 0.1524)
				)
				(justify mirror)
			)
		)
		(duplicate_pad_numbers_are_jumpers no)
		(fp_rect
			(start 0.4318 0.9525)
			(end -0.4318 -0.9525)
			(stroke
				(width 0)
				(type default)
			)
			(fill no)
			(layer "B.CrtYd")
		)
		(fp_rect
			(start 0.4318 0.9525)
			(end -0.4318 -0.9525)
			(stroke
				(width 0)
				(type default)
			)
			(fill no)
			(layer "B.Fab")
		)
		(pad "1" smd custom
			(at 0 -0.4445 90)
			(size 0.1524 0.1524)
			(layers "B.Cu" "B.Mask" "B.Paste")
			(net "P5V_B_2_LL_R")
			(options
				(clearance outline)
				(anchor circle)
			)
			(primitives
				(gr_poly
					(pts
						(arc
							(start 0.3048 0.2032)
							(mid 0.275042 0.275042)
							(end 0.2032 0.3048)
						)
						(arc
							(start -0.2032 0.3048)
							(mid -0.275042 0.275042)
							(end -0.3048 0.2032)
						)
						(arc
							(start -0.3048 -0.2032)
							(mid -0.275042 -0.275042)
							(end -0.2032 -0.3048)
						)
						(arc
							(start 0.2032 -0.3048)
							(mid 0.275042 -0.275042)
							(end 0.3048 -0.2032)
						)
					)
					(width 0)
					(fill yes)
				)
			)
		)
		(pad "2" smd custom
			(at 0 0.4445 90)
			(size 0.1524 0.1524)
			(layers "B.Cu" "B.Mask" "B.Paste")
			(net "P5V_B_2_VFB")
			(options
				(clearance outline)
				(anchor circle)
			)
			(primitives
				(gr_poly
					(pts
						(arc
							(start 0.3048 0.2032)
							(mid 0.275042 0.275042)
							(end 0.2032 0.3048)
						)
						(arc
							(start -0.2032 0.3048)
							(mid -0.275042 0.275042)
							(end -0.3048 0.2032)
						)
						(arc
							(start -0.3048 -0.2032)
							(mid -0.275042 -0.275042)
							(end -0.2032 -0.3048)
						)
						(arc
							(start 0.2032 -0.3048)
							(mid 0.275042 -0.275042)
							(end 0.3048 -0.2032)
						)
					)
					(width 0)
					(fill yes)
				)
			)
		)
	)
	(footprint ""
		(layer "B.Cu")
		(at 8.194802 -222.51035 180)
		(property "Reference" "R1098"
			(at 0 0 0)
			(layer "B.SilkS")
			(hide yes)
			(effects
				(font
					(size 1.27 1.27)
				)
				(justify mirror)
			)
		)
		(property "Value" "2D2R3-1-U-GP"
			(at 0.0254 -2.5146 180)
			(unlocked yes)
			(layer "B.Fab")
			(hide yes)
			(effects
				(font
					(size 1.016 1.016)
					(thickness 0.1524)
				)
				(justify mirror)
			)
		)
		(property "Device Type" "R603H22"
			(at 0.0254 -4.0386 180)
			(unlocked yes)
			(layer "B.Fab")
			(hide yes)
			(effects
				(font
					(size 1.016 1.016)
					(thickness 0.1524)
				)
				(justify mirror)
			)
		)
		(duplicate_pad_numbers_are_jumpers no)
		(fp_line
			(start 0.4826 0)
			(end 0.2032 0)
			(stroke
				(width 0.2032)
				(type default)
			)
			(layer "B.SilkS")
		)
		(fp_line
			(start -0.2032 0)
			(end -0.4826 0)
			(stroke
				(width 0.2032)
				(type default)
			)
			(layer "B.SilkS")
		)
		(fp_rect
			(start 0.5842 1.3335)
			(end -0.5842 -1.3335)
			(stroke
				(width 0)
				(type default)
			)
			(fill no)
			(layer "B.CrtYd")
		)
		(fp_rect
			(start 0.5842 1.3335)
			(end -0.5842 -1.3335)
			(stroke
				(width 0)
				(type default)
			)
			(fill no)
			(layer "B.Fab")
		)
		(pad "1" smd custom
			(at 0 -0.762)
			(size 0.2159 0.2159)
			(layers "B.Cu" "B.Mask" "B.Paste")
			(net "P12V_B")
			(options
				(clearance outline)
				(anchor circle)
			)
			(primitives
				(gr_poly
					(pts
						(arc
							(start -0.3302 0.4318)
							(mid -0.402042 0.402042)
							(end -0.4318 0.3302)
						)
						(arc
							(start -0.4318 -0.3302)
							(mid -0.402042 -0.402042)
							(end -0.3302 -0.4318)
						)
						(arc
							(start 0.3302 -0.4318)
							(mid 0.402042 -0.402042)
							(end 0.4318 -0.3302)
						)
						(arc
							(start 0.4318 0.3302)
							(mid 0.402042 0.402042)
							(end 0.3302 0.4318)
						)
					)
					(width 0)
					(fill yes)
				)
			)
		)
		(pad "2" smd custom
			(at 0 0.762)
			(size 0.2159 0.2159)
			(layers "B.Cu" "B.Mask" "B.Paste")
			(net "P12V_B_1_VDD_U31")
			(options
				(clearance outline)
				(anchor circle)
			)
			(primitives
				(gr_poly
					(pts
						(arc
							(start -0.3302 0.4318)
							(mid -0.402042 0.402042)
							(end -0.4318 0.3302)
						)
						(arc
							(start -0.4318 -0.3302)
							(mid -0.402042 -0.402042)
							(end -0.3302 -0.4318)
						)
						(arc
							(start 0.3302 -0.4318)
							(mid 0.402042 -0.402042)
							(end 0.4318 -0.3302)
						)
						(arc
							(start 0.4318 0.3302)
							(mid 0.402042 0.402042)
							(end 0.3302 0.4318)
						)
					)
					(width 0)
					(fill yes)
				)
			)
		)
	)
	(footprint ""
		(layer "B.Cu")
		(at 480.253802 -228.35235 180)
		(property "Reference" "C668"
			(at 0 0 0)
			(layer "B.SilkS")
			(hide yes)
			(effects
				(font
					(size 1.27 1.27)
				)
				(justify mirror)
			)
		)
		(property "Value" "SC10U16V5KX-7-GP-U"
			(at 0.0762 -6.1214 180)
			(unlocked yes)
			(layer "B.Fab")
			(hide yes)
			(effects
				(font
					(size 1.016 1.016)
					(thickness 0.1524)
				)
				(justify mirror)
			)
		)
		(property "Device Type" "C805H58"
			(at 0.0762 -8.1534 180)
			(unlocked yes)
			(layer "B.Fab")
			(hide yes)
			(effects
				(font
					(size 1.016 1.016)
					(thickness 0.1524)
				)
				(justify mirror)
			)
		)
		(duplicate_pad_numbers_are_jumpers no)
		(fp_line
			(start -0.635 0)
			(end 0.635 0)
			(stroke
				(width 0.508)
				(type default)
			)
			(layer "B.SilkS")
		)
		(fp_rect
			(start 0.9652 1.778)
			(end -0.9652 -1.778)
			(stroke
				(width 0)
				(type default)
			)
			(fill no)
			(layer "B.CrtYd")
		)
		(fp_poly
			(pts
				(xy 0.9652 -1.778) (xy -0.9652 -1.778) (xy -0.9652 1.778) (xy 0.9652 1.778)
			)
			(stroke
				(width 0)
				(type default)
			)
			(fill no)
			(layer "B.Fab")
		)
		(pad "1" smd rect
			(at 0 -0.9652)
			(size 1.397 1.143)
			(layers "B.Cu" "B.Mask" "B.Paste")
			(net "P5V_B_3")
		)
		(pad "2" smd rect
			(at 0 0.9652)
			(size 1.397 1.143)
			(layers "B.Cu" "B.Mask" "B.Paste")
			(net "GND")
		)
	)
	(footprint ""
		(layer "B.Cu")
		(at 69.49186 -117.167406 180)
		(property "Reference" "C650"
			(at 0 0 0)
			(layer "B.SilkS")
			(hide yes)
			(effects
				(font
					(size 1.27 1.27)
				)
				(justify mirror)
			)
		)
		(property "Value" "SC10U16V5KX-7-GP-U"
			(at 0.0762 -6.1214 180)
			(unlocked yes)
			(layer "B.Fab")
			(hide yes)
			(effects
				(font
					(size 1.016 1.016)
					(thickness 0.1524)
				)
				(justify mirror)
			)
		)
		(property "Device Type" "C805H58"
			(at 0.0762 -8.1534 180)
			(unlocked yes)
			(layer "B.Fab")
			(hide yes)
			(effects
				(font
					(size 1.016 1.016)
					(thickness 0.1524)
				)
				(justify mirror)
			)
		)
		(duplicate_pad_numbers_are_jumpers no)
		(fp_line
			(start -0.635 0)
			(end 0.635 0)
			(stroke
				(width 0.508)
				(type default)
			)
			(layer "B.SilkS")
		)
		(fp_rect
			(start 0.9652 1.778)
			(end -0.9652 -1.778)
			(stroke
				(width 0)
				(type default)
			)
			(fill no)
			(layer "B.CrtYd")
		)
		(fp_poly
			(pts
				(xy 0.9652 -1.778) (xy -0.9652 -1.778) (xy -0.9652 1.778) (xy 0.9652 1.778)
			)
			(stroke
				(width 0)
				(type default)
			)
			(fill no)
			(layer "B.Fab")
		)
		(pad "1" smd rect
			(at 0 -0.9652)
			(size 1.397 1.143)
			(layers "B.Cu" "B.Mask" "B.Paste")
			(net "P5V_B_2")
		)
		(pad "2" smd rect
			(at 0 0.9652)
			(size 1.397 1.143)
			(layers "B.Cu" "B.Mask" "B.Paste")
			(net "GND")
		)
	)
	(footprint ""
		(layer "B.Cu")
		(at 127.431546 -364.12297 180)
		(property "Reference" "D50"
			(at 0 0 0)
			(layer "B.SilkS")
			(hide yes)
			(effects
				(font
					(size 1.27 1.27)
				)
				(justify mirror)
			)
		)
		(property "Value" "RB551V30-GP"
			(at 0 -6.7818 180)
			(unlocked yes)
			(layer "B.Fab")
			(hide yes)
			(effects
				(font
					(size 1.016 1.016)
					(thickness 0.1524)
				)
				(justify mirror)
			)
		)
		(property "Device Type" "SOD323AKH38"
			(at 0 -8.6868 180)
			(unlocked yes)
			(layer "B.Fab")
			(hide yes)
			(effects
				(font
					(size 1.016 1.016)
					(thickness 0.1524)
				)
				(justify mirror)
			)
		)
		(duplicate_pad_numbers_are_jumpers no)
		(fp_line
			(start 0.889 2.159)
			(end 0.889 -1.9304)
			(stroke
				(width 0.1524)
				(type default)
			)
			(layer "B.SilkS")
		)
		(fp_line
			(start 0.889 -1.9304)
			(end -0.889 -1.9304)
			(stroke
				(width 0.1524)
				(type default)
			)
			(layer "B.SilkS")
		)
		(fp_line
			(start -0.762 2.0574)
			(end 0.762 2.0574)
			(stroke
				(width 0.508)
				(type default)
			)
			(layer "B.SilkS")
		)
		(fp_line
			(start -0.889 2.159)
			(end 0.889 2.159)
			(stroke
				(width 0.1524)
				(type default)
			)
			(layer "B.SilkS")
		)
		(fp_line
			(start -0.889 -1.9304)
			(end -0.889 2.159)
			(stroke
				(width 0.1524)
				(type default)
			)
			(layer "B.SilkS")
		)
		(fp_rect
			(start 1.016 2.3114)
			(end -1.016 -2.0066)
			(stroke
				(width 0)
				(type default)
			)
			(fill no)
			(layer "B.CrtYd")
		)
		(fp_poly
			(pts
				(xy 1.016 -2.0066) (xy -1.016 -2.0066) (xy -1.016 2.3114) (xy 1.016 2.3114)
			)
			(stroke
				(width 0)
				(type default)
			)
			(fill no)
			(layer "B.Fab")
		)
		(pad "A" smd rect
			(at 0 -1.143)
			(size 0.5588 1.016)
			(layers "B.Cu" "B.Mask" "B.Paste")
			(net "GATE_FAN1")
		)
		(pad "K" smd rect
			(at 0 1.143)
			(size 0.5588 1.016)
			(layers "B.Cu" "B.Mask" "B.Paste")
			(net "GATE_FAN1_R")
		)
	)
	(footprint ""
		(layer "B.Cu")
		(at 41.0972 -219.96019)
		(property "Reference" "TC14"
			(at 0 0 0)
			(layer "B.SilkS")
			(hide yes)
			(effects
				(font
					(size 1.27 1.27)
				)
				(justify mirror)
			)
		)
		(property "Value" "ST220U10VDM-LGP"
			(at 0 -9.6012 0)
			(unlocked yes)
			(layer "B.Fab")
			(hide yes)
			(effects
				(font
					(size 1.016 1.016)
					(thickness 0.1524)
				)
				(justify mirror)
			)
		)
		(property "Device Type" "CT7343H119"
			(at 0 -11.1252 0)
			(unlocked yes)
			(layer "B.Fab")
			(hide yes)
			(effects
				(font
					(size 1.016 1.016)
					(thickness 0.1524)
				)
				(justify mirror)
			)
		)
		(duplicate_pad_numbers_are_jumpers no)
		(fp_line
			(start -2.286 -4.8768)
			(end 2.286 -4.8768)
			(stroke
				(width 0.1524)
				(type default)
			)
			(layer "B.SilkS")
		)
		(fp_line
			(start -2.286 -2.032)
			(end -2.286 -4.8768)
			(stroke
				(width 0.1524)
				(type default)
			)
			(layer "B.SilkS")
		)
		(fp_line
			(start -2.286 2.032)
			(end -2.286 4.8768)
			(stroke
				(width 0.1524)
				(type default)
			)
			(layer "B.SilkS")
		)
		(fp_line
			(start -2.286 4.8768)
			(end 2.286 4.8768)
			(stroke
				(width 0.1524)
				(type default)
			)
			(layer "B.SilkS")
		)
		(fp_line
			(start -2.1082 -4.699)
			(end 2.1082 -4.699)
			(stroke
				(width 0.508)
				(type default)
			)
			(layer "B.SilkS")
		)
		(fp_line
			(start 2.286 -4.8768)
			(end 2.286 -2.032)
			(stroke
				(width 0.1524)
				(type default)
			)
			(layer "B.SilkS")
		)
		(fp_line
			(start 2.286 4.8768)
			(end 2.286 2.032)
			(stroke
				(width 0.1524)
				(type default)
			)
			(layer "B.SilkS")
		)
		(fp_rect
			(start 2.1463 3.6449)
			(end -2.1463 -3.6449)
			(stroke
				(width 0)
				(type default)
			)
			(fill no)
			(layer "B.CrtYd")
		)
		(fp_poly
			(pts
				(xy 2.54 4.953) (xy 2.54 4.2926) (xy 3.81 4.2926) (xy 3.81 -4.2926) (xy 2.54 -4.2926) (xy 2.54 -4.953)
				(xy -2.54 -4.953) (xy -2.54 -4.2926) (xy -3.81 -4.2926) (xy -3.81 -1.6256) (xy -2.1463 -1.6256)
				(xy -2.1463 -3.6449) (xy 2.1463 -3.6449) (xy 2.1463 3.6449) (xy -2.1463 3.6449) (xy -2.1463 -1.6129)
				(xy -3.81 -1.6129) (xy -3.81 4.2926) (xy -2.54 4.2926) (xy -2.54 4.953)
			)
			(stroke
				(width 0)
				(type default)
			)
			(fill no)
			(layer "B.CrtYd")
		)
		(fp_rect
			(start -2.54 4.2926)
			(end -3.81 -4.2926)
			(stroke
				(width 0)
				(type default)
			)
			(fill no)
			(layer "B.Fab")
		)
		(fp_rect
			(start 2.54 4.953)
			(end -2.54 -4.953)
			(stroke
				(width 0)
				(type default)
			)
			(fill no)
			(layer "B.Fab")
		)
		(fp_rect
			(start 3.81 4.2926)
			(end 2.54 -4.2926)
			(stroke
				(width 0)
				(type default)
			)
			(fill no)
			(layer "B.Fab")
		)
		(pad "1" smd rect
			(at 0 -3.1496 180)
			(size 2.413 2.286)
			(layers "B.Cu" "B.Mask" "B.Paste")
			(net "P5V_B_1")
		)
		(pad "2" smd rect
			(at 0 3.1496 180)
			(size 2.413 2.286)
			(layers "B.Cu" "B.Mask" "B.Paste")
			(net "GND")
		)
		(zone
			(layer "B.Cu")
			(hatch none 0.5)
			(connect_pads
				(clearance 0)
			)
			(min_thickness 0.25)
			(keepout
				(tracks allowed)
				(vias not_allowed)
				(pads allowed)
				(copperpour not_allowed)
				(footprints allowed)
			)
			(placement
				(enabled no)
				(sheetname "")
			)
			(fill
				(thermal_gap 0.5)
				(thermal_bridge_width 0.5)
				(island_removal_mode 0)
			)
			(polygon
				(pts
					(xy 39.5859 -221.64929) (xy 39.5859 -224.55759) (xy 42.6085 -224.55759) (xy 42.6085 -221.66199)
					(xy 42.6085 -221.33179) (xy 39.5859 -221.33179)
				)
			)
		)
		(zone
			(layer "B.Cu")
			(hatch none 0.5)
			(connect_pads
				(clearance 0)
			)
			(min_thickness 0.25)
			(keepout
				(tracks allowed)
				(vias not_allowed)
				(pads allowed)
				(copperpour not_allowed)
				(footprints allowed)
			)
			(placement
				(enabled no)
				(sheetname "")
			)
			(fill
				(thermal_gap 0.5)
				(thermal_bridge_width 0.5)
				(island_removal_mode 0)
			)
			(polygon
				(pts
					(xy 42.6085 -215.36279) (xy 39.5859 -215.36279) (xy 39.5859 -218.25839) (xy 39.5859 -218.58859)
					(xy 42.6085 -218.58859) (xy 42.6085 -218.25839)
				)
			)
		)
	)
	(footprint ""
		(layer "B.Cu")
		(at 451.424802 -223.27235 180)
		(property "Reference" "C656"
			(at 0 0 0)
			(layer "B.SilkS")
			(hide yes)
			(effects
				(font
					(size 1.27 1.27)
				)
				(justify mirror)
			)
		)
		(property "Value" "SCD1U16V2KX-3GP"
			(at -1.1811 -2.7051 180)
			(unlocked yes)
			(layer "B.Fab")
			(hide yes)
			(effects
				(font
					(size 1.016 1.016)
					(thickness 0.1524)
				)
				(justify mirror)
			)
		)
		(property "Device Type" "C402H22"
			(at -1.1811 -4.2291 180)
			(unlocked yes)
			(layer "B.Fab")
			(hide yes)
			(effects
				(font
					(size 1.016 1.016)
					(thickness 0.1524)
				)
				(justify mirror)
			)
		)
		(duplicate_pad_numbers_are_jumpers no)
		(fp_rect
			(start 0.4318 0.9525)
			(end -0.4318 -0.9525)
			(stroke
				(width 0)
				(type default)
			)
			(fill no)
			(layer "B.CrtYd")
		)
		(fp_rect
			(start 0.4318 0.9525)
			(end -0.4318 -0.9525)
			(stroke
				(width 0)
				(type default)
			)
			(fill no)
			(layer "B.Fab")
		)
		(pad "1" smd custom
			(at 0 -0.4445)
			(size 0.1524 0.1524)
			(layers "B.Cu" "B.Mask" "B.Paste")
			(net "P12V_B_3_VIN_U33")
			(options
				(clearance outline)
				(anchor circle)
			)
			(primitives
				(gr_poly
					(pts
						(arc
							(start 0.3048 0.2032)
							(mid 0.275042 0.275042)
							(end 0.2032 0.3048)
						)
						(arc
							(start -0.2032 0.3048)
							(mid -0.275042 0.275042)
							(end -0.3048 0.2032)
						)
						(arc
							(start -0.3048 -0.2032)
							(mid -0.275042 -0.275042)
							(end -0.2032 -0.3048)
						)
						(arc
							(start 0.2032 -0.3048)
							(mid 0.275042 -0.275042)
							(end 0.3048 -0.2032)
						)
					)
					(width 0)
					(fill yes)
				)
			)
		)
		(pad "2" smd custom
			(at 0 0.4445)
			(size 0.1524 0.1524)
			(layers "B.Cu" "B.Mask" "B.Paste")
			(net "GND")
			(options
				(clearance outline)
				(anchor circle)
			)
			(primitives
				(gr_poly
					(pts
						(arc
							(start 0.3048 0.2032)
							(mid 0.275042 0.275042)
							(end 0.2032 0.3048)
						)
						(arc
							(start -0.2032 0.3048)
							(mid -0.275042 0.275042)
							(end -0.3048 0.2032)
						)
						(arc
							(start -0.3048 -0.2032)
							(mid -0.275042 -0.275042)
							(end -0.2032 -0.3048)
						)
						(arc
							(start 0.2032 -0.3048)
							(mid 0.275042 -0.275042)
							(end 0.3048 -0.2032)
						)
					)
					(width 0)
					(fill yes)
				)
			)
		)
	)
	(footprint ""
		(layer "B.Cu")
		(at 260.0198 -285.0896 -90)
		(property "Reference" "C699"
			(at 0 0 90)
			(layer "B.SilkS")
			(hide yes)
			(effects
				(font
					(size 1.27 1.27)
				)
				(justify mirror)
			)
		)
		(property "Value" "SC1KP50V2KX-1GP"
			(at -1.1811 -2.7051 270)
			(unlocked yes)
			(layer "B.Fab")
			(hide yes)
			(effects
				(font
					(size 1.016 1.016)
					(thickness 0.1524)
				)
				(justify mirror)
			)
		)
		(property "Device Type" "C402H22"
			(at -1.1811 -4.2291 270)
			(unlocked yes)
			(layer "B.Fab")
			(hide yes)
			(effects
				(font
					(size 1.016 1.016)
					(thickness 0.1524)
				)
				(justify mirror)
			)
		)
		(duplicate_pad_numbers_are_jumpers no)
		(fp_rect
			(start 0.4318 0.9525)
			(end -0.4318 -0.9525)
			(stroke
				(width 0)
				(type default)
			)
			(fill no)
			(layer "B.CrtYd")
		)
		(fp_rect
			(start 0.4318 0.9525)
			(end -0.4318 -0.9525)
			(stroke
				(width 0)
				(type default)
			)
			(fill no)
			(layer "B.Fab")
		)
		(pad "1" smd custom
			(at 0 -0.4445 90)
			(size 0.1524 0.1524)
			(layers "B.Cu" "B.Mask" "B.Paste")
			(net "P3V3_STBY_VFB_R")
			(options
				(clearance outline)
				(anchor circle)
			)
			(primitives
				(gr_poly
					(pts
						(arc
							(start 0.3048 0.2032)
							(mid 0.275042 0.275042)
							(end 0.2032 0.3048)
						)
						(arc
							(start -0.2032 0.3048)
							(mid -0.275042 0.275042)
							(end -0.3048 0.2032)
						)
						(arc
							(start -0.3048 -0.2032)
							(mid -0.275042 -0.275042)
							(end -0.2032 -0.3048)
						)
						(arc
							(start 0.2032 -0.3048)
							(mid 0.275042 -0.275042)
							(end 0.3048 -0.2032)
						)
					)
					(width 0)
					(fill yes)
				)
			)
		)
		(pad "2" smd custom
			(at 0 0.4445 90)
			(size 0.1524 0.1524)
			(layers "B.Cu" "B.Mask" "B.Paste")
			(net "P3V3_STBY_VFB")
			(options
				(clearance outline)
				(anchor circle)
			)
			(primitives
				(gr_poly
					(pts
						(arc
							(start 0.3048 0.2032)
							(mid 0.275042 0.275042)
							(end 0.2032 0.3048)
						)
						(arc
							(start -0.2032 0.3048)
							(mid -0.275042 0.275042)
							(end -0.3048 0.2032)
						)
						(arc
							(start -0.3048 -0.2032)
							(mid -0.275042 -0.275042)
							(end -0.2032 -0.3048)
						)
						(arc
							(start 0.2032 -0.3048)
							(mid 0.275042 -0.275042)
							(end 0.3048 -0.2032)
						)
					)
					(width 0)
					(fill yes)
				)
			)
		)
	)
	(footprint ""
		(layer "B.Cu")
		(at 251.714 -290.703 -90)
		(property "Reference" "C693"
			(at 0 0 90)
			(layer "B.SilkS")
			(hide yes)
			(effects
				(font
					(size 1.27 1.27)
				)
				(justify mirror)
			)
		)
		(property "Value" "SC10U16V5KX-7-GP-U"
			(at 0.0762 -6.1214 270)
			(unlocked yes)
			(layer "B.Fab")
			(hide yes)
			(effects
				(font
					(size 1.016 1.016)
					(thickness 0.1524)
				)
				(justify mirror)
			)
		)
		(property "Device Type" "C805H58"
			(at 0.0762 -8.1534 270)
			(unlocked yes)
			(layer "B.Fab")
			(hide yes)
			(effects
				(font
					(size 1.016 1.016)
					(thickness 0.1524)
				)
				(justify mirror)
			)
		)
		(duplicate_pad_numbers_are_jumpers no)
		(fp_line
			(start -0.635 0)
			(end 0.635 0)
			(stroke
				(width 0.508)
				(type default)
			)
			(layer "B.SilkS")
		)
		(fp_rect
			(start 0.9652 1.778)
			(end -0.9652 -1.778)
			(stroke
				(width 0)
				(type default)
			)
			(fill no)
			(layer "B.CrtYd")
		)
		(fp_poly
			(pts
				(xy 0.9652 -1.778) (xy -0.9652 -1.778) (xy -0.9652 1.778) (xy 0.9652 1.778)
			)
			(stroke
				(width 0)
				(type default)
			)
			(fill no)
			(layer "B.Fab")
		)
		(pad "1" smd rect
			(at 0 -0.9652 90)
			(size 1.397 1.143)
			(layers "B.Cu" "B.Mask" "B.Paste")
			(net "P3V3_STBY_VIN")
		)
		(pad "2" smd rect
			(at 0 0.9652 90)
			(size 1.397 1.143)
			(layers "B.Cu" "B.Mask" "B.Paste")
			(net "GND")
		)
	)
	(footprint ""
		(layer "B.Cu")
		(at 462.794604 -229.626414 -90)
		(property "Reference" "R1144"
			(at 0 0 90)
			(layer "B.SilkS")
			(hide yes)
			(effects
				(font
					(size 1.27 1.27)
				)
				(justify mirror)
			)
		)
		(property "Value" "10R3F-GP"
			(at 0.0254 -2.5146 270)
			(unlocked yes)
			(layer "B.Fab")
			(hide yes)
			(effects
				(font
					(size 1.016 1.016)
					(thickness 0.1524)
				)
				(justify mirror)
			)
		)
		(property "Device Type" "R603H22"
			(at 0.0254 -4.0386 270)
			(unlocked yes)
			(layer "B.Fab")
			(hide yes)
			(effects
				(font
					(size 1.016 1.016)
					(thickness 0.1524)
				)
				(justify mirror)
			)
		)
		(duplicate_pad_numbers_are_jumpers no)
		(fp_line
			(start -0.2032 0)
			(end -0.4826 0)
			(stroke
				(width 0.2032)
				(type default)
			)
			(layer "B.SilkS")
		)
		(fp_line
			(start 0.4826 0)
			(end 0.2032 0)
			(stroke
				(width 0.2032)
				(type default)
			)
			(layer "B.SilkS")
		)
		(fp_rect
			(start 0.5842 1.3335)
			(end -0.5842 -1.3335)
			(stroke
				(width 0)
				(type default)
			)
			(fill no)
			(layer "B.CrtYd")
		)
		(fp_rect
			(start 0.5842 1.3335)
			(end -0.5842 -1.3335)
			(stroke
				(width 0)
				(type default)
			)
			(fill no)
			(layer "B.Fab")
		)
		(pad "1" smd custom
			(at 0 -0.762 90)
			(size 0.2159 0.2159)
			(layers "B.Cu" "B.Mask" "B.Paste")
			(net "P5V_B_3_CC")
			(options
				(clearance outline)
				(anchor circle)
			)
			(primitives
				(gr_poly
					(pts
						(arc
							(start -0.3302 0.4318)
							(mid -0.402042 0.402042)
							(end -0.4318 0.3302)
						)
						(arc
							(start -0.4318 -0.3302)
							(mid -0.402042 -0.402042)
							(end -0.3302 -0.4318)
						)
						(arc
							(start 0.3302 -0.4318)
							(mid 0.402042 -0.402042)
							(end 0.4318 -0.3302)
						)
						(arc
							(start 0.4318 0.3302)
							(mid 0.402042 0.402042)
							(end 0.3302 0.4318)
						)
					)
					(width 0)
					(fill yes)
				)
			)
		)
		(pad "2" smd custom
			(at 0 0.762 90)
			(size 0.2159 0.2159)
			(layers "B.Cu" "B.Mask" "B.Paste")
			(net "P5V_B_3_VFB_R")
			(options
				(clearance outline)
				(anchor circle)
			)
			(primitives
				(gr_poly
					(pts
						(arc
							(start -0.3302 0.4318)
							(mid -0.402042 0.402042)
							(end -0.4318 0.3302)
						)
						(arc
							(start -0.4318 -0.3302)
							(mid -0.402042 -0.402042)
							(end -0.3302 -0.4318)
						)
						(arc
							(start 0.3302 -0.4318)
							(mid 0.402042 -0.402042)
							(end 0.4318 -0.3302)
						)
						(arc
							(start 0.4318 0.3302)
							(mid 0.402042 0.402042)
							(end 0.3302 0.4318)
						)
					)
					(width 0)
					(fill yes)
				)
			)
		)
	)
	(footprint ""
		(layer "B.Cu")
		(at 255.775206 -277.451312 90)
		(property "Reference" "R1184"
			(at 0 0 90)
			(layer "B.SilkS")
			(hide yes)
			(effects
				(font
					(size 1.27 1.27)
				)
				(justify mirror)
			)
		)
		(property "Value" "0R2J-2-GP"
			(at -0.064008 -3.993896 90)
			(unlocked yes)
			(layer "B.Fab")
			(hide yes)
			(effects
				(font
					(size 1.016 1.016)
					(thickness 0.1524)
				)
				(justify mirror)
			)
		)
		(property "Device Type" "R402H16"
			(at -0.064008 -5.517896 90)
			(unlocked yes)
			(layer "B.Fab")
			(hide yes)
			(effects
				(font
					(size 1.016 1.016)
					(thickness 0.1524)
				)
				(justify mirror)
			)
		)
		(duplicate_pad_numbers_are_jumpers no)
		(fp_line
			(start 0.508 -0.9398)
			(end 0.508 0.9398)
			(stroke
				(width 0.1524)
				(type default)
			)
			(layer "B.SilkS")
		)
		(fp_line
			(start -0.508 -0.9398)
			(end 0.508 -0.9398)
			(stroke
				(width 0.1524)
				(type default)
			)
			(layer "B.SilkS")
		)
		(fp_rect
			(start 0.508 0.9398)
			(end -0.508 -0.9398)
			(stroke
				(width 0)
				(type default)
			)
			(fill no)
			(layer "B.CrtYd")
		)
		(fp_rect
			(start 0.508 0.9398)
			(end -0.508 -0.9398)
			(stroke
				(width 0)
				(type default)
			)
			(fill no)
			(layer "B.Fab")
		)
		(pad "1" smd custom
			(at 0 -0.4445 270)
			(size 0.1397 0.1397)
			(layers "B.Cu" "B.Mask" "B.Paste")
			(net "P3V3_STBY_EN_R")
			(options
				(clearance outline)
				(anchor circle)
			)
			(primitives
				(gr_poly
					(pts
						(arc
							(start -0.1778 0.2794)
							(mid -0.249642 0.249642)
							(end -0.2794 0.1778)
						)
						(arc
							(start -0.2794 -0.1778)
							(mid -0.249642 -0.249642)
							(end -0.1778 -0.2794)
						)
						(arc
							(start 0.1778 -0.2794)
							(mid 0.249642 -0.249642)
							(end 0.2794 -0.1778)
						)
						(arc
							(start 0.2794 0.1778)
							(mid 0.249642 0.249642)
							(end 0.1778 0.2794)
						)
					)
					(width 0)
					(fill yes)
				)
			)
		)
		(pad "2" smd custom
			(at 0 0.4445 270)
			(size 0.1397 0.1397)
			(layers "B.Cu" "B.Mask" "B.Paste")
			(net "P12V_B_PGOOD")
			(options
				(clearance outline)
				(anchor circle)
			)
			(primitives
				(gr_poly
					(pts
						(arc
							(start -0.1778 0.2794)
							(mid -0.249642 0.249642)
							(end -0.2794 0.1778)
						)
						(arc
							(start -0.2794 -0.1778)
							(mid -0.249642 -0.249642)
							(end -0.1778 -0.2794)
						)
						(arc
							(start 0.1778 -0.2794)
							(mid 0.249642 -0.249642)
							(end 0.2794 -0.1778)
						)
						(arc
							(start 0.2794 0.1778)
							(mid 0.249642 0.249642)
							(end 0.1778 0.2794)
						)
					)
					(width 0)
					(fill yes)
				)
			)
		)
	)
	(footprint ""
		(layer "B.Cu")
		(at 240.705894 -277.824946 -90)
		(property "Reference" "C701"
			(at 0 0 90)
			(layer "B.SilkS")
			(hide yes)
			(effects
				(font
					(size 1.27 1.27)
				)
				(justify mirror)
			)
		)
		(property "Value" "SC10U6D3V5KX-4GP"
			(at 0.0762 -6.1214 270)
			(unlocked yes)
			(layer "B.Fab")
			(hide yes)
			(effects
				(font
					(size 1.016 1.016)
					(thickness 0.1524)
				)
				(justify mirror)
			)
		)
		(property "Device Type" "C805H58"
			(at 0.0762 -8.1534 270)
			(unlocked yes)
			(layer "B.Fab")
			(hide yes)
			(effects
				(font
					(size 1.016 1.016)
					(thickness 0.1524)
				)
				(justify mirror)
			)
		)
		(duplicate_pad_numbers_are_jumpers no)
		(fp_line
			(start -0.635 0)
			(end 0.635 0)
			(stroke
				(width 0.508)
				(type default)
			)
			(layer "B.SilkS")
		)
		(fp_rect
			(start 0.9652 1.778)
			(end -0.9652 -1.778)
			(stroke
				(width 0)
				(type default)
			)
			(fill no)
			(layer "B.CrtYd")
		)
		(fp_poly
			(pts
				(xy 0.9652 -1.778) (xy -0.9652 -1.778) (xy -0.9652 1.778) (xy 0.9652 1.778)
			)
			(stroke
				(width 0)
				(type default)
			)
			(fill no)
			(layer "B.Fab")
		)
		(pad "1" smd rect
			(at 0 -0.9652 90)
			(size 1.397 1.143)
			(layers "B.Cu" "B.Mask" "B.Paste")
			(net "P3V3_STBY_B")
		)
		(pad "2" smd rect
			(at 0 0.9652 90)
			(size 1.397 1.143)
			(layers "B.Cu" "B.Mask" "B.Paste")
			(net "GND")
		)
	)
	(footprint ""
		(layer "B.Cu")
		(at 167.7162 -369.189 90)
		(property "Reference" "R1059"
			(at 0 0 90)
			(layer "B.SilkS")
			(hide yes)
			(effects
				(font
					(size 1.27 1.27)
				)
				(justify mirror)
			)
		)
		(property "Value" "10R2F-L-GP"
			(at -0.064008 -3.993896 90)
			(unlocked yes)
			(layer "B.Fab")
			(hide yes)
			(effects
				(font
					(size 1.016 1.016)
					(thickness 0.1524)
				)
				(justify mirror)
			)
		)
		(property "Device Type" "R402H14"
			(at -0.064008 -5.517896 90)
			(unlocked yes)
			(layer "B.Fab")
			(hide yes)
			(effects
				(font
					(size 1.016 1.016)
					(thickness 0.1524)
				)
				(justify mirror)
			)
		)
		(duplicate_pad_numbers_are_jumpers no)
		(fp_line
			(start 0.508 -0.9398)
			(end 0.508 0.9398)
			(stroke
				(width 0.1524)
				(type default)
			)
			(layer "B.SilkS")
		)
		(fp_line
			(start -0.508 -0.9398)
			(end 0.508 -0.9398)
			(stroke
				(width 0.1524)
				(type default)
			)
			(layer "B.SilkS")
		)
		(fp_rect
			(start 0.508 0.9398)
			(end -0.508 -0.9398)
			(stroke
				(width 0)
				(type default)
			)
			(fill no)
			(layer "B.CrtYd")
		)
		(fp_rect
			(start 0.508 0.9398)
			(end -0.508 -0.9398)
			(stroke
				(width 0)
				(type default)
			)
			(fill no)
			(layer "B.Fab")
		)
		(pad "1" smd custom
			(at 0 -0.4445 270)
			(size 0.1397 0.1397)
			(layers "B.Cu" "B.Mask" "B.Paste")
			(net "MB0_CM_SENSE_R1_P")
			(options
				(clearance outline)
				(anchor circle)
			)
			(primitives
				(gr_poly
					(pts
						(arc
							(start -0.1778 0.2794)
							(mid -0.249642 0.249642)
							(end -0.2794 0.1778)
						)
						(arc
							(start -0.2794 -0.1778)
							(mid -0.249642 -0.249642)
							(end -0.1778 -0.2794)
						)
						(arc
							(start 0.1778 -0.2794)
							(mid 0.249642 -0.249642)
							(end 0.2794 -0.1778)
						)
						(arc
							(start 0.2794 0.1778)
							(mid 0.249642 0.249642)
							(end 0.1778 0.2794)
						)
					)
					(width 0)
					(fill yes)
				)
			)
		)
		(pad "2" smd custom
			(at 0 0.4445 270)
			(size 0.1397 0.1397)
			(layers "B.Cu" "B.Mask" "B.Paste")
			(net "MB0_HS_SENSE_P")
			(options
				(clearance outline)
				(anchor circle)
			)
			(primitives
				(gr_poly
					(pts
						(arc
							(start -0.1778 0.2794)
							(mid -0.249642 0.249642)
							(end -0.2794 0.1778)
						)
						(arc
							(start -0.2794 -0.1778)
							(mid -0.249642 -0.249642)
							(end -0.1778 -0.2794)
						)
						(arc
							(start 0.1778 -0.2794)
							(mid 0.249642 -0.249642)
							(end 0.2794 -0.1778)
						)
						(arc
							(start 0.2794 0.1778)
							(mid 0.249642 0.249642)
							(end 0.1778 0.2794)
						)
					)
					(width 0)
					(fill yes)
				)
			)
		)
	)
	(footprint ""
		(layer "B.Cu")
		(at 456.733402 -229.54615)
		(property "Reference" "G6"
			(at 0 0 0)
			(layer "B.SilkS")
			(hide yes)
			(effects
				(font
					(size 1.27 1.27)
				)
				(justify mirror)
			)
		)
		(property "Value" "COPPER-CLOSE-GP-U"
			(at -0.0762 -2.8702 0)
			(unlocked yes)
			(layer "B.Fab")
			(hide yes)
			(effects
				(font
					(size 1.016 1.016)
					(thickness 0.1524)
				)
				(justify mirror)
			)
		)
		(property "Device Type" "CON2C-U"
			(at -0.0762 -4.3942 0)
			(unlocked yes)
			(layer "B.Fab")
			(hide yes)
			(effects
				(font
					(size 1.016 1.016)
					(thickness 0.1524)
				)
				(justify mirror)
			)
		)
		(duplicate_pad_numbers_are_jumpers no)
		(fp_rect
			(start 0.9398 0.9652)
			(end -0.9398 -0.9652)
			(stroke
				(width 0)
				(type default)
			)
			(fill no)
			(layer "B.CrtYd")
		)
		(fp_rect
			(start 0.9398 0.9652)
			(end -0.9398 -0.9652)
			(stroke
				(width 0)
				(type default)
			)
			(fill no)
			(layer "B.Fab")
		)
		(pad "1" smd custom
			(at 0 -0.5334 180)
			(size 0.17145 0.17145)
			(layers "B.Cu" "B.Mask" "B.Paste")
			(net "AGND_P5V_B_3")
			(options
				(clearance outline)
				(anchor circle)
			)
			(primitives
				(gr_poly
					(pts
						(xy -0.127 -0.3429) (xy -0.127 -0.1651) (xy -0.635 0.3429) (xy 0.635 0.3429) (xy 0.127 -0.1651)
						(xy 0.127 -0.3429)
					)
					(width 0)
					(fill yes)
				)
			)
		)
		(pad "2" smd custom
			(at 0 0.5334 180)
			(size 0.17145 0.17145)
			(layers "B.Cu" "B.Mask" "B.Paste")
			(net "GND")
			(options
				(clearance outline)
				(anchor circle)
			)
			(primitives
				(gr_poly
					(pts
						(xy -0.635 -0.3429) (xy -0.127 0.1651) (xy -0.127 0.3429) (xy 0.127 0.3429) (xy 0.127 0.1651)
						(xy 0.635 -0.3429)
					)
					(width 0)
					(fill yes)
				)
			)
		)
	)
	(footprint ""
		(layer "B.Cu")
		(at 46.438058 -113.732056 -90)
		(property "Reference" "U32"
			(at 0 0 90)
			(layer "B.SilkS")
			(hide yes)
			(effects
				(font
					(size 1.27 1.27)
				)
				(justify mirror)
			)
		)
		(property "Value" "TPS53319DQPR-GP"
			(at -4.7498 -5.6896 270)
			(unlocked yes)
			(layer "B.Fab")
			(hide yes)
			(effects
				(font
					(size 1.016 1.016)
					(thickness 0.1524)
				)
				(justify mirror)
			)
		)
		(property "Device Type" "QFN22G6050-G6133H60"
			(at -4.7498 -7.2136 270)
			(unlocked yes)
			(layer "B.Fab")
			(hide yes)
			(effects
				(font
					(size 1.016 1.016)
					(thickness 0.1524)
				)
				(justify mirror)
			)
		)
		(duplicate_pad_numbers_are_jumpers no)
		(fp_line
			(start -3.556 3.5179)
			(end -3.556 2.2479)
			(stroke
				(width 0.1524)
				(type default)
			)
			(layer "B.SilkS")
		)
		(fp_line
			(start -2.286 3.5179)
			(end -3.556 3.5179)
			(stroke
				(width 0.1524)
				(type default)
			)
			(layer "B.SilkS")
		)
		(fp_line
			(start 3.556 3.5179)
			(end 2.286 3.5179)
			(stroke
				(width 0.1524)
				(type default)
			)
			(layer "B.SilkS")
		)
		(fp_line
			(start -1.500124 3.262122)
			(end -1.500124 4.024122)
			(stroke
				(width 0.1524)
				(type default)
			)
			(layer "B.SilkS")
		)
		(fp_line
			(start 0.999998 3.262122)
			(end 0.999998 3.770122)
			(stroke
				(width 0.1524)
				(type default)
			)
			(layer "B.SilkS")
		)
		(fp_line
			(start 3.556 2.2479)
			(end 3.556 3.5179)
			(stroke
				(width 0.1524)
				(type default)
			)
			(layer "B.SilkS")
		)
		(fp_line
			(start -0.500126 -3.262122)
			(end -0.500126 -3.770122)
			(stroke
				(width 0.1524)
				(type default)
			)
			(layer "B.SilkS")
		)
		(fp_line
			(start 1.999996 -3.262122)
			(end 1.999996 -4.024122)
			(stroke
				(width 0.1524)
				(type default)
			)
			(layer "B.SilkS")
		)
		(fp_line
			(start 2.286 -3.5179)
			(end 3.556 -3.5179)
			(stroke
				(width 0.1524)
				(type default)
			)
			(layer "B.SilkS")
		)
		(fp_line
			(start 3.556 -3.5179)
			(end 3.556 -2.2479)
			(stroke
				(width 0.1524)
				(type default)
			)
			(layer "B.SilkS")
		)
		(fp_poly
			(pts
				(xy -3.556 -3.5179) (xy -2.5273 -3.5179) (xy -3.556 -2.4892)
			)
			(stroke
				(width 0)
				(type default)
			)
			(fill yes)
			(layer "B.SilkS")
		)
		(fp_rect
			(start 2.9972 2.5019)
			(end -2.9972 -2.5019)
			(stroke
				(width 0)
				(type default)
			)
			(fill no)
			(layer "B.CrtYd")
		)
		(fp_poly
			(pts
				(xy -3.556 -2.5019) (xy 2.9972 -2.5019) (xy 2.9972 2.5019) (xy -2.9972 2.5019) (xy -2.9972 -2.4892)
				(xy -3.556 -2.4892) (xy -3.556 3.5179) (xy 3.556 3.5179) (xy 3.556 -3.5179) (xy -3.556 -3.5179)
			)
			(stroke
				(width 0)
				(type default)
			)
			(fill no)
			(layer "B.CrtYd")
		)
		(fp_rect
			(start 3.556 3.5179)
			(end -3.556 -3.5179)
			(stroke
				(width 0)
				(type default)
			)
			(fill no)
			(layer "B.Fab")
		)
		(pad "1" smd rect
			(at -2.500122 -2.449322 90)
			(size 0.3048 1.1176)
			(layers "B.Cu" "B.Mask" "B.Paste")
			(net "P5V_B_2_VFB")
		)
		(pad "2" smd rect
			(at -1.999996 -2.449322 90)
			(size 0.3048 1.1176)
			(layers "B.Cu" "B.Mask" "B.Paste")
			(net "P5V_B_2_EN_R")
		)
		(pad "3" smd rect
			(at -1.500124 -2.449322 90)
			(size 0.3048 1.1176)
			(layers "B.Cu" "B.Mask" "B.Paste")
			(net "P5V_B_2_PGOOD")
		)
		(pad "4" smd rect
			(at -0.999998 -2.449322 90)
			(size 0.3048 1.1176)
			(layers "B.Cu" "B.Mask" "B.Paste")
			(net "P5V_B_2_VBST")
		)
		(pad "5" smd rect
			(at -0.500126 -2.449322 90)
			(size 0.3048 1.1176)
			(layers "B.Cu" "B.Mask" "B.Paste")
			(net "P5V_B_2_ROVP")
		)
		(pad "6" smd rect
			(at 0 -2.449322 90)
			(size 0.3048 1.1176)
			(layers "B.Cu" "B.Mask" "B.Paste")
			(net "P5V_B_2_LL")
		)
		(pad "7" smd rect
			(at 0.500126 -2.449322 90)
			(size 0.3048 1.1176)
			(layers "B.Cu" "B.Mask" "B.Paste")
			(net "P5V_B_2_LL")
		)
		(pad "8" smd rect
			(at 0.999998 -2.449322 90)
			(size 0.3048 1.1176)
			(layers "B.Cu" "B.Mask" "B.Paste")
			(net "P5V_B_2_LL")
		)
		(pad "9" smd rect
			(at 1.500124 -2.449322 90)
			(size 0.3048 1.1176)
			(layers "B.Cu" "B.Mask" "B.Paste")
			(net "P5V_B_2_LL")
		)
		(pad "10" smd rect
			(at 1.999996 -2.449322 90)
			(size 0.3048 1.1176)
			(layers "B.Cu" "B.Mask" "B.Paste")
			(net "P5V_B_2_LL")
		)
		(pad "11" smd rect
			(at 2.500122 -2.449322 90)
			(size 0.3048 1.1176)
			(layers "B.Cu" "B.Mask" "B.Paste")
			(net "P5V_B_2_LL")
		)
		(pad "12" smd rect
			(at 2.500122 2.449322 90)
			(size 0.3048 1.1176)
			(layers "B.Cu" "B.Mask" "B.Paste")
			(net "P12V_B_2_VIN_U32")
		)
		(pad "13" smd rect
			(at 1.999996 2.449322 90)
			(size 0.3048 1.1176)
			(layers "B.Cu" "B.Mask" "B.Paste")
			(net "P12V_B_2_VIN_U32")
		)
		(pad "14" smd rect
			(at 1.500124 2.449322 90)
			(size 0.3048 1.1176)
			(layers "B.Cu" "B.Mask" "B.Paste")
			(net "P12V_B_2_VIN_U32")
		)
		(pad "15" smd rect
			(at 0.999998 2.449322 90)
			(size 0.3048 1.1176)
			(layers "B.Cu" "B.Mask" "B.Paste")
			(net "P12V_B_2_VIN_U32")
		)
		(pad "16" smd rect
			(at 0.500126 2.449322 90)
			(size 0.3048 1.1176)
			(layers "B.Cu" "B.Mask" "B.Paste")
			(net "P12V_B_2_VIN_U32")
		)
		(pad "17" smd rect
			(at 0 2.449322 90)
			(size 0.3048 1.1176)
			(layers "B.Cu" "B.Mask" "B.Paste")
			(net "P12V_B_2_VIN_U32")
		)
		(pad "18" smd rect
			(at -0.500126 2.449322 90)
			(size 0.3048 1.1176)
			(layers "B.Cu" "B.Mask" "B.Paste")
			(net "P5V_B_2_VREG")
		)
		(pad "19" smd rect
			(at -0.999998 2.449322 90)
			(size 0.3048 1.1176)
			(layers "B.Cu" "B.Mask" "B.Paste")
			(net "P12V_B_2_VDD_U32")
		)
		(pad "20" smd rect
			(at -1.500124 2.449322 90)
			(size 0.3048 1.1176)
			(layers "B.Cu" "B.Mask" "B.Paste")
			(net "P5V_B_2_MODE")
		)
		(pad "21" smd rect
			(at -1.999996 2.449322 90)
			(size 0.3048 1.1176)
			(layers "B.Cu" "B.Mask" "B.Paste")
			(net "P5V_B_2_TRIP")
		)
		(pad "22" smd rect
			(at -2.500122 2.449322 90)
			(size 0.3048 1.1176)
			(layers "B.Cu" "B.Mask" "B.Paste")
			(net "P5V_B_2_RF")
		)
		(pad "23" smd custom
			(at 0 0 90)
			(size 0.83185 0.83185)
			(layers "B.Cu" "B.Mask" "B.Paste")
			(net "GND")
			(options
				(clearance outline)
				(anchor circle)
			)
			(primitives
				(gr_poly
					(pts
						(xy -2.7813 -1.6637) (xy -2.7813 -1.2954) (xy -3.048 -1.2954) (xy -3.048 -0.9525) (xy -2.7813 -0.9525)
						(xy -2.7813 0.9525) (xy -3.048 0.9525) (xy -3.048 1.2954) (xy -2.7813 1.2954) (xy -2.7813 1.6637)
						(xy 2.7813 1.6637) (xy 2.7813 1.2954) (xy 3.048 1.2954) (xy 3.048 0.9525) (xy 2.7813 0.9525) (xy 2.7813 -0.9525)
						(xy 3.048 -0.9525) (xy 3.048 -1.2954) (xy 2.7813 -1.2954) (xy 2.7813 -1.6637)
					)
					(width 0)
					(fill yes)
				)
			)
		)
	)
	(footprint ""
		(layer "B.Cu")
		(at 74.95286 -117.040406 -90)
		(property "Reference" "G3"
			(at 0 0 90)
			(layer "B.SilkS")
			(hide yes)
			(effects
				(font
					(size 1.27 1.27)
				)
				(justify mirror)
			)
		)
		(property "Value" "GAP-CLOSE-PWR-4-GP"
			(at 2.4638 -0.5461 270)
			(unlocked yes)
			(layer "B.Fab")
			(hide yes)
			(effects
				(font
					(size 1.016 1.016)
					(thickness 0.1524)
				)
				(justify mirror)
			)
		)
		(property "Device Type" "GAP-CLOSE-PWR-4"
			(at 2.4638 -2.0701 270)
			(unlocked yes)
			(layer "B.Fab")
			(hide yes)
			(effects
				(font
					(size 1.016 1.016)
					(thickness 0.1524)
				)
				(justify mirror)
			)
		)
		(duplicate_pad_numbers_are_jumpers no)
		(fp_rect
			(start 0.2794 0.254)
			(end -0.2794 -0.254)
			(stroke
				(width 0)
				(type default)
			)
			(fill no)
			(layer "B.CrtYd")
		)
		(fp_rect
			(start 0.2794 0.254)
			(end -0.2794 -0.254)
			(stroke
				(width 0)
				(type default)
			)
			(fill no)
			(layer "B.Fab")
		)
		(pad "1" smd rect
			(at 0.0635 0 90)
			(size 0.1778 0.254)
			(layers "B.Cu" "B.Mask" "B.Paste")
			(net "P5V_B_2")
		)
		(pad "2" smd rect
			(at -0.0635 0 90)
			(size 0.1778 0.254)
			(layers "B.Cu" "B.Mask" "B.Paste")
			(net "P5V_B_2_CC")
		)
	)
	(footprint ""
		(layer "B.Cu")
		(at 443.804802 -222.51035 180)
		(property "Reference" "R1137"
			(at 0 0 0)
			(layer "B.SilkS")
			(hide yes)
			(effects
				(font
					(size 1.27 1.27)
				)
				(justify mirror)
			)
		)
		(property "Value" "2D2R3-1-U-GP"
			(at 0.0254 -2.5146 180)
			(unlocked yes)
			(layer "B.Fab")
			(hide yes)
			(effects
				(font
					(size 1.016 1.016)
					(thickness 0.1524)
				)
				(justify mirror)
			)
		)
		(property "Device Type" "R603H22"
			(at 0.0254 -4.0386 180)
			(unlocked yes)
			(layer "B.Fab")
			(hide yes)
			(effects
				(font
					(size 1.016 1.016)
					(thickness 0.1524)
				)
				(justify mirror)
			)
		)
		(duplicate_pad_numbers_are_jumpers no)
		(fp_line
			(start 0.4826 0)
			(end 0.2032 0)
			(stroke
				(width 0.2032)
				(type default)
			)
			(layer "B.SilkS")
		)
		(fp_line
			(start -0.2032 0)
			(end -0.4826 0)
			(stroke
				(width 0.2032)
				(type default)
			)
			(layer "B.SilkS")
		)
		(fp_rect
			(start 0.5842 1.3335)
			(end -0.5842 -1.3335)
			(stroke
				(width 0)
				(type default)
			)
			(fill no)
			(layer "B.CrtYd")
		)
		(fp_rect
			(start 0.5842 1.3335)
			(end -0.5842 -1.3335)
			(stroke
				(width 0)
				(type default)
			)
			(fill no)
			(layer "B.Fab")
		)
		(pad "1" smd custom
			(at 0 -0.762)
			(size 0.2159 0.2159)
			(layers "B.Cu" "B.Mask" "B.Paste")
			(net "P12V_B")
			(options
				(clearance outline)
				(anchor circle)
			)
			(primitives
				(gr_poly
					(pts
						(arc
							(start -0.3302 0.4318)
							(mid -0.402042 0.402042)
							(end -0.4318 0.3302)
						)
						(arc
							(start -0.4318 -0.3302)
							(mid -0.402042 -0.402042)
							(end -0.3302 -0.4318)
						)
						(arc
							(start 0.3302 -0.4318)
							(mid 0.402042 -0.402042)
							(end 0.4318 -0.3302)
						)
						(arc
							(start 0.4318 0.3302)
							(mid 0.402042 0.402042)
							(end 0.3302 0.4318)
						)
					)
					(width 0)
					(fill yes)
				)
			)
		)
		(pad "2" smd custom
			(at 0 0.762)
			(size 0.2159 0.2159)
			(layers "B.Cu" "B.Mask" "B.Paste")
			(net "P12V_B_3_VDD_U33")
			(options
				(clearance outline)
				(anchor circle)
			)
			(primitives
				(gr_poly
					(pts
						(arc
							(start -0.3302 0.4318)
							(mid -0.402042 0.402042)
							(end -0.4318 0.3302)
						)
						(arc
							(start -0.4318 -0.3302)
							(mid -0.402042 -0.402042)
							(end -0.3302 -0.4318)
						)
						(arc
							(start 0.3302 -0.4318)
							(mid 0.402042 -0.402042)
							(end 0.4318 -0.3302)
						)
						(arc
							(start 0.4318 0.3302)
							(mid 0.402042 0.402042)
							(end 0.3302 0.4318)
						)
					)
					(width 0)
					(fill yes)
				)
			)
		)
	)
	(footprint ""
		(layer "B.Cu")
		(at 432.526186 -112.955578 180)
		(property "Reference" "C674"
			(at 0 0 0)
			(layer "B.SilkS")
			(hide yes)
			(effects
				(font
					(size 1.27 1.27)
				)
				(justify mirror)
			)
		)
		(property "Value" "SCD1U16V2KX-3GP"
			(at -1.1811 -2.7051 180)
			(unlocked yes)
			(layer "B.Fab")
			(hide yes)
			(effects
				(font
					(size 1.016 1.016)
					(thickness 0.1524)
				)
				(justify mirror)
			)
		)
		(property "Device Type" "C402H22"
			(at -1.1811 -4.2291 180)
			(unlocked yes)
			(layer "B.Fab")
			(hide yes)
			(effects
				(font
					(size 1.016 1.016)
					(thickness 0.1524)
				)
				(justify mirror)
			)
		)
		(duplicate_pad_numbers_are_jumpers no)
		(fp_rect
			(start 0.4318 0.9525)
			(end -0.4318 -0.9525)
			(stroke
				(width 0)
				(type default)
			)
			(fill no)
			(layer "B.CrtYd")
		)
		(fp_rect
			(start 0.4318 0.9525)
			(end -0.4318 -0.9525)
			(stroke
				(width 0)
				(type default)
			)
			(fill no)
			(layer "B.Fab")
		)
		(pad "1" smd custom
			(at 0 -0.4445)
			(size 0.1524 0.1524)
			(layers "B.Cu" "B.Mask" "B.Paste")
			(net "P12V_B_4_VIN_U34")
			(options
				(clearance outline)
				(anchor circle)
			)
			(primitives
				(gr_poly
					(pts
						(arc
							(start 0.3048 0.2032)
							(mid 0.275042 0.275042)
							(end 0.2032 0.3048)
						)
						(arc
							(start -0.2032 0.3048)
							(mid -0.275042 0.275042)
							(end -0.3048 0.2032)
						)
						(arc
							(start -0.3048 -0.2032)
							(mid -0.275042 -0.275042)
							(end -0.2032 -0.3048)
						)
						(arc
							(start 0.2032 -0.3048)
							(mid 0.275042 -0.275042)
							(end 0.3048 -0.2032)
						)
					)
					(width 0)
					(fill yes)
				)
			)
		)
		(pad "2" smd custom
			(at 0 0.4445)
			(size 0.1524 0.1524)
			(layers "B.Cu" "B.Mask" "B.Paste")
			(net "GND")
			(options
				(clearance outline)
				(anchor circle)
			)
			(primitives
				(gr_poly
					(pts
						(arc
							(start 0.3048 0.2032)
							(mid 0.275042 0.275042)
							(end 0.2032 0.3048)
						)
						(arc
							(start -0.2032 0.3048)
							(mid -0.275042 0.275042)
							(end -0.3048 0.2032)
						)
						(arc
							(start -0.3048 -0.2032)
							(mid -0.275042 -0.275042)
							(end -0.2032 -0.3048)
						)
						(arc
							(start 0.2032 -0.3048)
							(mid 0.275042 -0.275042)
							(end 0.3048 -0.2032)
						)
					)
					(width 0)
					(fill yes)
				)
			)
		)
	)
	(footprint ""
		(layer "B.Cu")
		(at 35.20186 -111.833406 180)
		(property "Reference" "C637"
			(at 0 0 0)
			(layer "B.SilkS")
			(hide yes)
			(effects
				(font
					(size 1.27 1.27)
				)
				(justify mirror)
			)
		)
		(property "Value" "SC10U16V5KX-7-GP-U"
			(at 0.0762 -6.1214 180)
			(unlocked yes)
			(layer "B.Fab")
			(hide yes)
			(effects
				(font
					(size 1.016 1.016)
					(thickness 0.1524)
				)
				(justify mirror)
			)
		)
		(property "Device Type" "C805H58"
			(at 0.0762 -8.1534 180)
			(unlocked yes)
			(layer "B.Fab")
			(hide yes)
			(effects
				(font
					(size 1.016 1.016)
					(thickness 0.1524)
				)
				(justify mirror)
			)
		)
		(duplicate_pad_numbers_are_jumpers no)
		(fp_line
			(start -0.635 0)
			(end 0.635 0)
			(stroke
				(width 0.508)
				(type default)
			)
			(layer "B.SilkS")
		)
		(fp_rect
			(start 0.9652 1.778)
			(end -0.9652 -1.778)
			(stroke
				(width 0)
				(type default)
			)
			(fill no)
			(layer "B.CrtYd")
		)
		(fp_poly
			(pts
				(xy 0.9652 -1.778) (xy -0.9652 -1.778) (xy -0.9652 1.778) (xy 0.9652 1.778)
			)
			(stroke
				(width 0)
				(type default)
			)
			(fill no)
			(layer "B.Fab")
		)
		(pad "1" smd rect
			(at 0 -0.9652)
			(size 1.397 1.143)
			(layers "B.Cu" "B.Mask" "B.Paste")
			(net "P12V_B_2_VIN_U32")
		)
		(pad "2" smd rect
			(at 0 0.9652)
			(size 1.397 1.143)
			(layers "B.Cu" "B.Mask" "B.Paste")
			(net "GND")
		)
	)
	(footprint ""
		(layer "B.Cu")
		(at 46.675802 -228.35235 180)
		(property "Reference" "C634"
			(at 0 0 0)
			(layer "B.SilkS")
			(hide yes)
			(effects
				(font
					(size 1.27 1.27)
				)
				(justify mirror)
			)
		)
		(property "Value" "SC10U16V5KX-7-GP-U"
			(at 0.0762 -6.1214 180)
			(unlocked yes)
			(layer "B.Fab")
			(hide yes)
			(effects
				(font
					(size 1.016 1.016)
					(thickness 0.1524)
				)
				(justify mirror)
			)
		)
		(property "Device Type" "C805H58"
			(at 0.0762 -8.1534 180)
			(unlocked yes)
			(layer "B.Fab")
			(hide yes)
			(effects
				(font
					(size 1.016 1.016)
					(thickness 0.1524)
				)
				(justify mirror)
			)
		)
		(duplicate_pad_numbers_are_jumpers no)
		(fp_line
			(start -0.635 0)
			(end 0.635 0)
			(stroke
				(width 0.508)
				(type default)
			)
			(layer "B.SilkS")
		)
		(fp_rect
			(start 0.9652 1.778)
			(end -0.9652 -1.778)
			(stroke
				(width 0)
				(type default)
			)
			(fill no)
			(layer "B.CrtYd")
		)
		(fp_poly
			(pts
				(xy 0.9652 -1.778) (xy -0.9652 -1.778) (xy -0.9652 1.778) (xy 0.9652 1.778)
			)
			(stroke
				(width 0)
				(type default)
			)
			(fill no)
			(layer "B.Fab")
		)
		(pad "1" smd rect
			(at 0 -0.9652)
			(size 1.397 1.143)
			(layers "B.Cu" "B.Mask" "B.Paste")
			(net "P5V_B_1")
		)
		(pad "2" smd rect
			(at 0 0.9652)
			(size 1.397 1.143)
			(layers "B.Cu" "B.Mask" "B.Paste")
			(net "GND")
		)
	)
	(footprint ""
		(layer "B.Cu")
		(at 45.97146 -118.361206)
		(property "Reference" "G4"
			(at 0 0 0)
			(layer "B.SilkS")
			(hide yes)
			(effects
				(font
					(size 1.27 1.27)
				)
				(justify mirror)
			)
		)
		(property "Value" "COPPER-CLOSE-GP-U"
			(at -0.0762 -2.8702 0)
			(unlocked yes)
			(layer "B.Fab")
			(hide yes)
			(effects
				(font
					(size 1.016 1.016)
					(thickness 0.1524)
				)
				(justify mirror)
			)
		)
		(property "Device Type" "CON2C-U"
			(at -0.0762 -4.3942 0)
			(unlocked yes)
			(layer "B.Fab")
			(hide yes)
			(effects
				(font
					(size 1.016 1.016)
					(thickness 0.1524)
				)
				(justify mirror)
			)
		)
		(duplicate_pad_numbers_are_jumpers no)
		(fp_rect
			(start 0.9398 0.9652)
			(end -0.9398 -0.9652)
			(stroke
				(width 0)
				(type default)
			)
			(fill no)
			(layer "B.CrtYd")
		)
		(fp_rect
			(start 0.9398 0.9652)
			(end -0.9398 -0.9652)
			(stroke
				(width 0)
				(type default)
			)
			(fill no)
			(layer "B.Fab")
		)
		(pad "1" smd custom
			(at 0 -0.5334 180)
			(size 0.17145 0.17145)
			(layers "B.Cu" "B.Mask" "B.Paste")
			(net "AGND_P5V_B_2")
			(options
				(clearance outline)
				(anchor circle)
			)
			(primitives
				(gr_poly
					(pts
						(xy -0.127 -0.3429) (xy -0.127 -0.1651) (xy -0.635 0.3429) (xy 0.635 0.3429) (xy 0.127 -0.1651)
						(xy 0.127 -0.3429)
					)
					(width 0)
					(fill yes)
				)
			)
		)
		(pad "2" smd custom
			(at 0 0.5334 180)
			(size 0.17145 0.17145)
			(layers "B.Cu" "B.Mask" "B.Paste")
			(net "GND")
			(options
				(clearance outline)
				(anchor circle)
			)
			(primitives
				(gr_poly
					(pts
						(xy -0.635 -0.3429) (xy -0.127 0.1651) (xy -0.127 0.3429) (xy 0.127 0.3429) (xy 0.127 0.1651)
						(xy 0.635 -0.3429)
					)
					(width 0)
					(fill yes)
				)
			)
		)
	)
	(footprint ""
		(layer "B.Cu")
		(at 49.308258 -118.507256 90)
		(property "Reference" "R1127"
			(at 0 0 90)
			(layer "B.SilkS")
			(hide yes)
			(effects
				(font
					(size 1.27 1.27)
				)
				(justify mirror)
			)
		)
		(property "Value" "71K5R2F-GP"
			(at -0.064008 -3.993896 90)
			(unlocked yes)
			(layer "B.Fab")
			(hide yes)
			(effects
				(font
					(size 1.016 1.016)
					(thickness 0.1524)
				)
				(justify mirror)
			)
		)
		(property "Device Type" "R402H16"
			(at -0.064008 -5.517896 90)
			(unlocked yes)
			(layer "B.Fab")
			(hide yes)
			(effects
				(font
					(size 1.016 1.016)
					(thickness 0.1524)
				)
				(justify mirror)
			)
		)
		(duplicate_pad_numbers_are_jumpers no)
		(fp_line
			(start 0.508 -0.9398)
			(end 0.508 0.9398)
			(stroke
				(width 0.1524)
				(type default)
			)
			(layer "B.SilkS")
		)
		(fp_line
			(start -0.508 -0.9398)
			(end 0.508 -0.9398)
			(stroke
				(width 0.1524)
				(type default)
			)
			(layer "B.SilkS")
		)
		(fp_rect
			(start 0.508 0.9398)
			(end -0.508 -0.9398)
			(stroke
				(width 0)
				(type default)
			)
			(fill no)
			(layer "B.CrtYd")
		)
		(fp_rect
			(start 0.508 0.9398)
			(end -0.508 -0.9398)
			(stroke
				(width 0)
				(type default)
			)
			(fill no)
			(layer "B.Fab")
		)
		(pad "1" smd custom
			(at 0 -0.4445 270)
			(size 0.1397 0.1397)
			(layers "B.Cu" "B.Mask" "B.Paste")
			(net "P5V_B_2_VFB")
			(options
				(clearance outline)
				(anchor circle)
			)
			(primitives
				(gr_poly
					(pts
						(arc
							(start -0.1778 0.2794)
							(mid -0.249642 0.249642)
							(end -0.2794 0.1778)
						)
						(arc
							(start -0.2794 -0.1778)
							(mid -0.249642 -0.249642)
							(end -0.1778 -0.2794)
						)
						(arc
							(start 0.1778 -0.2794)
							(mid 0.249642 -0.249642)
							(end 0.2794 -0.1778)
						)
						(arc
							(start 0.2794 0.1778)
							(mid 0.249642 0.249642)
							(end 0.1778 0.2794)
						)
					)
					(width 0)
					(fill yes)
				)
			)
		)
		(pad "2" smd custom
			(at 0 0.4445 270)
			(size 0.1397 0.1397)
			(layers "B.Cu" "B.Mask" "B.Paste")
			(net "P5V_B_2_VFB_R")
			(options
				(clearance outline)
				(anchor circle)
			)
			(primitives
				(gr_poly
					(pts
						(arc
							(start -0.1778 0.2794)
							(mid -0.249642 0.249642)
							(end -0.2794 0.1778)
						)
						(arc
							(start -0.2794 -0.1778)
							(mid -0.249642 -0.249642)
							(end -0.1778 -0.2794)
						)
						(arc
							(start 0.1778 -0.2794)
							(mid 0.249642 -0.249642)
							(end 0.2794 -0.1778)
						)
						(arc
							(start 0.2794 0.1778)
							(mid 0.249642 0.249642)
							(end 0.1778 0.2794)
						)
					)
					(width 0)
					(fill yes)
				)
			)
		)
	)
	(footprint ""
		(layer "B.Cu")
		(at 55.769002 -117.916452 180)
		(property "Reference" "R1122"
			(at 0 0 0)
			(layer "B.SilkS")
			(hide yes)
			(effects
				(font
					(size 1.27 1.27)
				)
				(justify mirror)
			)
		)
		(property "Value" "2K7R2F-GP"
			(at -0.064008 -3.993896 180)
			(unlocked yes)
			(layer "B.Fab")
			(hide yes)
			(effects
				(font
					(size 1.016 1.016)
					(thickness 0.1524)
				)
				(justify mirror)
			)
		)
		(property "Device Type" "R402H16"
			(at -0.064008 -5.517896 180)
			(unlocked yes)
			(layer "B.Fab")
			(hide yes)
			(effects
				(font
					(size 1.016 1.016)
					(thickness 0.1524)
				)
				(justify mirror)
			)
		)
		(duplicate_pad_numbers_are_jumpers no)
		(fp_line
			(start 0.508 -0.9398)
			(end 0.508 0.9398)
			(stroke
				(width 0.1524)
				(type default)
			)
			(layer "B.SilkS")
		)
		(fp_line
			(start -0.508 -0.9398)
			(end 0.508 -0.9398)
			(stroke
				(width 0.1524)
				(type default)
			)
			(layer "B.SilkS")
		)
		(fp_rect
			(start 0.508 0.9398)
			(end -0.508 -0.9398)
			(stroke
				(width 0)
				(type default)
			)
			(fill no)
			(layer "B.CrtYd")
		)
		(fp_rect
			(start 0.508 0.9398)
			(end -0.508 -0.9398)
			(stroke
				(width 0)
				(type default)
			)
			(fill no)
			(layer "B.Fab")
		)
		(pad "1" smd custom
			(at 0 -0.4445)
			(size 0.1397 0.1397)
			(layers "B.Cu" "B.Mask" "B.Paste")
			(net "P5V_B_2_LL")
			(options
				(clearance outline)
				(anchor circle)
			)
			(primitives
				(gr_poly
					(pts
						(arc
							(start -0.1778 0.2794)
							(mid -0.249642 0.249642)
							(end -0.2794 0.1778)
						)
						(arc
							(start -0.2794 -0.1778)
							(mid -0.249642 -0.249642)
							(end -0.1778 -0.2794)
						)
						(arc
							(start 0.1778 -0.2794)
							(mid 0.249642 -0.249642)
							(end 0.2794 -0.1778)
						)
						(arc
							(start 0.2794 0.1778)
							(mid 0.249642 0.249642)
							(end 0.1778 0.2794)
						)
					)
					(width 0)
					(fill yes)
				)
			)
		)
		(pad "2" smd custom
			(at 0 0.4445)
			(size 0.1397 0.1397)
			(layers "B.Cu" "B.Mask" "B.Paste")
			(net "P5V_B_2_LL_R")
			(options
				(clearance outline)
				(anchor circle)
			)
			(primitives
				(gr_poly
					(pts
						(arc
							(start -0.1778 0.2794)
							(mid -0.249642 0.249642)
							(end -0.2794 0.1778)
						)
						(arc
							(start -0.2794 -0.1778)
							(mid -0.249642 -0.249642)
							(end -0.1778 -0.2794)
						)
						(arc
							(start 0.1778 -0.2794)
							(mid 0.249642 -0.249642)
							(end 0.2794 -0.1778)
						)
						(arc
							(start 0.2794 0.1778)
							(mid 0.249642 0.249642)
							(end 0.1778 0.2794)
						)
					)
					(width 0)
					(fill yes)
				)
			)
		)
	)
	(footprint ""
		(layer "B.Cu")
		(at 451.551802 -225.43135 90)
		(property "Reference" "C663"
			(at 0 0 90)
			(layer "B.SilkS")
			(hide yes)
			(effects
				(font
					(size 1.27 1.27)
				)
				(justify mirror)
			)
		)
		(property "Value" "SC1U16V3KX-5GP"
			(at 0 -2.8194 90)
			(unlocked yes)
			(layer "B.Fab")
			(hide yes)
			(effects
				(font
					(size 1.016 1.016)
					(thickness 0.1524)
				)
				(justify mirror)
			)
		)
		(property "Device Type" "C603H36"
			(at 0 -4.3434 90)
			(unlocked yes)
			(layer "B.Fab")
			(hide yes)
			(effects
				(font
					(size 1.016 1.016)
					(thickness 0.1524)
				)
				(justify mirror)
			)
		)
		(duplicate_pad_numbers_are_jumpers no)
		(fp_line
			(start -0.508 0)
			(end 0.508 0)
			(stroke
				(width 0.2032)
				(type default)
			)
			(layer "B.SilkS")
		)
		(fp_rect
			(start 0.5842 1.3335)
			(end -0.5842 -1.3335)
			(stroke
				(width 0)
				(type default)
			)
			(fill no)
			(layer "B.CrtYd")
		)
		(fp_rect
			(start 0.5842 1.3335)
			(end -0.5842 -1.3335)
			(stroke
				(width 0)
				(type default)
			)
			(fill no)
			(layer "B.Fab")
		)
		(pad "1" smd custom
			(at 0 -0.762 270)
			(size 0.2159 0.2159)
			(layers "B.Cu" "B.Mask" "B.Paste")
			(net "GND")
			(options
				(clearance outline)
				(anchor circle)
			)
			(primitives
				(gr_poly
					(pts
						(arc
							(start -0.3302 0.4318)
							(mid -0.402042 0.402042)
							(end -0.4318 0.3302)
						)
						(arc
							(start -0.4318 -0.3302)
							(mid -0.402042 -0.402042)
							(end -0.3302 -0.4318)
						)
						(arc
							(start 0.3302 -0.4318)
							(mid 0.402042 -0.402042)
							(end 0.4318 -0.3302)
						)
						(arc
							(start 0.4318 0.3302)
							(mid 0.402042 0.402042)
							(end 0.3302 0.4318)
						)
					)
					(width 0)
					(fill yes)
				)
			)
		)
		(pad "2" smd custom
			(at 0 0.762 270)
			(size 0.2159 0.2159)
			(layers "B.Cu" "B.Mask" "B.Paste")
			(net "P5V_B_3_VREG")
			(options
				(clearance outline)
				(anchor circle)
			)
			(primitives
				(gr_poly
					(pts
						(arc
							(start -0.3302 0.4318)
							(mid -0.402042 0.402042)
							(end -0.4318 0.3302)
						)
						(arc
							(start -0.4318 -0.3302)
							(mid -0.402042 -0.402042)
							(end -0.3302 -0.4318)
						)
						(arc
							(start 0.3302 -0.4318)
							(mid 0.402042 -0.402042)
							(end 0.4318 -0.3302)
						)
						(arc
							(start 0.4318 0.3302)
							(mid 0.402042 0.402042)
							(end 0.3302 0.4318)
						)
					)
					(width 0)
					(fill yes)
				)
			)
		)
	)
	(footprint ""
		(layer "B.Cu")
		(at 239.903 -286.004 180)
		(property "Reference" "C704"
			(at 0 0 0)
			(layer "B.SilkS")
			(hide yes)
			(effects
				(font
					(size 1.27 1.27)
				)
				(justify mirror)
			)
		)
		(property "Value" "SC10U6D3V5KX-4GP"
			(at 0.0762 -6.1214 180)
			(unlocked yes)
			(layer "B.Fab")
			(hide yes)
			(effects
				(font
					(size 1.016 1.016)
					(thickness 0.1524)
				)
				(justify mirror)
			)
		)
		(property "Device Type" "C805H58"
			(at 0.0762 -8.1534 180)
			(unlocked yes)
			(layer "B.Fab")
			(hide yes)
			(effects
				(font
					(size 1.016 1.016)
					(thickness 0.1524)
				)
				(justify mirror)
			)
		)
		(duplicate_pad_numbers_are_jumpers no)
		(fp_line
			(start -0.635 0)
			(end 0.635 0)
			(stroke
				(width 0.508)
				(type default)
			)
			(layer "B.SilkS")
		)
		(fp_rect
			(start 0.9652 1.778)
			(end -0.9652 -1.778)
			(stroke
				(width 0)
				(type default)
			)
			(fill no)
			(layer "B.CrtYd")
		)
		(fp_poly
			(pts
				(xy 0.9652 -1.778) (xy -0.9652 -1.778) (xy -0.9652 1.778) (xy 0.9652 1.778)
			)
			(stroke
				(width 0)
				(type default)
			)
			(fill no)
			(layer "B.Fab")
		)
		(pad "1" smd rect
			(at 0 -0.9652)
			(size 1.397 1.143)
			(layers "B.Cu" "B.Mask" "B.Paste")
			(net "P3V3_STBY_B")
		)
		(pad "2" smd rect
			(at 0 0.9652)
			(size 1.397 1.143)
			(layers "B.Cu" "B.Mask" "B.Paste")
			(net "GND")
		)
	)
	(footprint ""
		(layer "B.Cu")
		(at 257.360674 -278.478234)
		(property "Reference" "R1183"
			(at 0 0 0)
			(layer "B.SilkS")
			(hide yes)
			(effects
				(font
					(size 1.27 1.27)
				)
				(justify mirror)
			)
		)
		(property "Value" "15KR2F-GP"
			(at -0.064008 -3.993896 0)
			(unlocked yes)
			(layer "B.Fab")
			(hide yes)
			(effects
				(font
					(size 1.016 1.016)
					(thickness 0.1524)
				)
				(justify mirror)
			)
		)
		(property "Device Type" "R402H16"
			(at -0.064008 -5.517896 0)
			(unlocked yes)
			(layer "B.Fab")
			(hide yes)
			(effects
				(font
					(size 1.016 1.016)
					(thickness 0.1524)
				)
				(justify mirror)
			)
		)
		(duplicate_pad_numbers_are_jumpers no)
		(fp_line
			(start -0.508 -0.9398)
			(end 0.508 -0.9398)
			(stroke
				(width 0.1524)
				(type default)
			)
			(layer "B.SilkS")
		)
		(fp_line
			(start 0.508 -0.9398)
			(end 0.508 0.9398)
			(stroke
				(width 0.1524)
				(type default)
			)
			(layer "B.SilkS")
		)
		(fp_rect
			(start 0.508 0.9398)
			(end -0.508 -0.9398)
			(stroke
				(width 0)
				(type default)
			)
			(fill no)
			(layer "B.CrtYd")
		)
		(fp_rect
			(start 0.508 0.9398)
			(end -0.508 -0.9398)
			(stroke
				(width 0)
				(type default)
			)
			(fill no)
			(layer "B.Fab")
		)
		(pad "1" smd custom
			(at 0 -0.4445 180)
			(size 0.1397 0.1397)
			(layers "B.Cu" "B.Mask" "B.Paste")
			(net "PWRGD_P3V3_STBY")
			(options
				(clearance outline)
				(anchor circle)
			)
			(primitives
				(gr_poly
					(pts
						(arc
							(start -0.1778 0.2794)
							(mid -0.249642 0.249642)
							(end -0.2794 0.1778)
						)
						(arc
							(start -0.2794 -0.1778)
							(mid -0.249642 -0.249642)
							(end -0.1778 -0.2794)
						)
						(arc
							(start 0.1778 -0.2794)
							(mid 0.249642 -0.249642)
							(end 0.2794 -0.1778)
						)
						(arc
							(start 0.2794 0.1778)
							(mid 0.249642 0.249642)
							(end 0.1778 0.2794)
						)
					)
					(width 0)
					(fill yes)
				)
			)
		)
		(pad "2" smd custom
			(at 0 0.4445 180)
			(size 0.1397 0.1397)
			(layers "B.Cu" "B.Mask" "B.Paste")
			(net "GND")
			(options
				(clearance outline)
				(anchor circle)
			)
			(primitives
				(gr_poly
					(pts
						(arc
							(start -0.1778 0.2794)
							(mid -0.249642 0.249642)
							(end -0.2794 0.1778)
						)
						(arc
							(start -0.2794 -0.1778)
							(mid -0.249642 -0.249642)
							(end -0.1778 -0.2794)
						)
						(arc
							(start 0.1778 -0.2794)
							(mid 0.249642 -0.249642)
							(end 0.2794 -0.1778)
						)
						(arc
							(start 0.2794 0.1778)
							(mid 0.249642 0.249642)
							(end 0.1778 0.2794)
						)
					)
					(width 0)
					(fill yes)
				)
			)
		)
	)
	(footprint ""
		(layer "B.Cu")
		(at 450.027802 -223.01835 180)
		(property "Reference" "C653"
			(at 0 0 0)
			(layer "B.SilkS")
			(hide yes)
			(effects
				(font
					(size 1.27 1.27)
				)
				(justify mirror)
			)
		)
		(property "Value" "SC10U16V5KX-7-GP-U"
			(at 0.0762 -6.1214 180)
			(unlocked yes)
			(layer "B.Fab")
			(hide yes)
			(effects
				(font
					(size 1.016 1.016)
					(thickness 0.1524)
				)
				(justify mirror)
			)
		)
		(property "Device Type" "C805H58"
			(at 0.0762 -8.1534 180)
			(unlocked yes)
			(layer "B.Fab")
			(hide yes)
			(effects
				(font
					(size 1.016 1.016)
					(thickness 0.1524)
				)
				(justify mirror)
			)
		)
		(duplicate_pad_numbers_are_jumpers no)
		(fp_line
			(start -0.635 0)
			(end 0.635 0)
			(stroke
				(width 0.508)
				(type default)
			)
			(layer "B.SilkS")
		)
		(fp_rect
			(start 0.9652 1.778)
			(end -0.9652 -1.778)
			(stroke
				(width 0)
				(type default)
			)
			(fill no)
			(layer "B.CrtYd")
		)
		(fp_poly
			(pts
				(xy 0.9652 -1.778) (xy -0.9652 -1.778) (xy -0.9652 1.778) (xy 0.9652 1.778)
			)
			(stroke
				(width 0)
				(type default)
			)
			(fill no)
			(layer "B.Fab")
		)
		(pad "1" smd rect
			(at 0 -0.9652)
			(size 1.397 1.143)
			(layers "B.Cu" "B.Mask" "B.Paste")
			(net "P12V_B_3_VIN_U33")
		)
		(pad "2" smd rect
			(at 0 0.9652)
			(size 1.397 1.143)
			(layers "B.Cu" "B.Mask" "B.Paste")
			(net "GND")
		)
	)
	(footprint ""
		(layer "B.Cu")
		(at 240.6904 -281.8384 -90)
		(property "Reference" "C703"
			(at 0 0 90)
			(layer "B.SilkS")
			(hide yes)
			(effects
				(font
					(size 1.27 1.27)
				)
				(justify mirror)
			)
		)
		(property "Value" "SC10U6D3V5KX-4GP"
			(at 0.0762 -6.1214 270)
			(unlocked yes)
			(layer "B.Fab")
			(hide yes)
			(effects
				(font
					(size 1.016 1.016)
					(thickness 0.1524)
				)
				(justify mirror)
			)
		)
		(property "Device Type" "C805H58"
			(at 0.0762 -8.1534 270)
			(unlocked yes)
			(layer "B.Fab")
			(hide yes)
			(effects
				(font
					(size 1.016 1.016)
					(thickness 0.1524)
				)
				(justify mirror)
			)
		)
		(duplicate_pad_numbers_are_jumpers no)
		(fp_line
			(start -0.635 0)
			(end 0.635 0)
			(stroke
				(width 0.508)
				(type default)
			)
			(layer "B.SilkS")
		)
		(fp_rect
			(start 0.9652 1.778)
			(end -0.9652 -1.778)
			(stroke
				(width 0)
				(type default)
			)
			(fill no)
			(layer "B.CrtYd")
		)
		(fp_poly
			(pts
				(xy 0.9652 -1.778) (xy -0.9652 -1.778) (xy -0.9652 1.778) (xy 0.9652 1.778)
			)
			(stroke
				(width 0)
				(type default)
			)
			(fill no)
			(layer "B.Fab")
		)
		(pad "1" smd rect
			(at 0 -0.9652 90)
			(size 1.397 1.143)
			(layers "B.Cu" "B.Mask" "B.Paste")
			(net "P3V3_STBY_B")
		)
		(pad "2" smd rect
			(at 0 0.9652 90)
			(size 1.397 1.143)
			(layers "B.Cu" "B.Mask" "B.Paste")
			(net "GND")
		)
	)
	(footprint ""
		(layer "B.Cu")
		(at 251.968 -287.274 -90)
		(property "Reference" "C690"
			(at 0 0 90)
			(layer "B.SilkS")
			(hide yes)
			(effects
				(font
					(size 1.27 1.27)
				)
				(justify mirror)
			)
		)
		(property "Value" "SCD1U16V2KX-3GP"
			(at -1.1811 -2.7051 270)
			(unlocked yes)
			(layer "B.Fab")
			(hide yes)
			(effects
				(font
					(size 1.016 1.016)
					(thickness 0.1524)
				)
				(justify mirror)
			)
		)
		(property "Device Type" "C402H22"
			(at -1.1811 -4.2291 270)
			(unlocked yes)
			(layer "B.Fab")
			(hide yes)
			(effects
				(font
					(size 1.016 1.016)
					(thickness 0.1524)
				)
				(justify mirror)
			)
		)
		(duplicate_pad_numbers_are_jumpers no)
		(fp_rect
			(start 0.4318 0.9525)
			(end -0.4318 -0.9525)
			(stroke
				(width 0)
				(type default)
			)
			(fill no)
			(layer "B.CrtYd")
		)
		(fp_rect
			(start 0.4318 0.9525)
			(end -0.4318 -0.9525)
			(stroke
				(width 0)
				(type default)
			)
			(fill no)
			(layer "B.Fab")
		)
		(pad "1" smd custom
			(at 0 -0.4445 90)
			(size 0.1524 0.1524)
			(layers "B.Cu" "B.Mask" "B.Paste")
			(net "P3V3_STBY_VIN")
			(options
				(clearance outline)
				(anchor circle)
			)
			(primitives
				(gr_poly
					(pts
						(arc
							(start 0.3048 0.2032)
							(mid 0.275042 0.275042)
							(end 0.2032 0.3048)
						)
						(arc
							(start -0.2032 0.3048)
							(mid -0.275042 0.275042)
							(end -0.3048 0.2032)
						)
						(arc
							(start -0.3048 -0.2032)
							(mid -0.275042 -0.275042)
							(end -0.2032 -0.3048)
						)
						(arc
							(start 0.2032 -0.3048)
							(mid 0.275042 -0.275042)
							(end 0.3048 -0.2032)
						)
					)
					(width 0)
					(fill yes)
				)
			)
		)
		(pad "2" smd custom
			(at 0 0.4445 90)
			(size 0.1524 0.1524)
			(layers "B.Cu" "B.Mask" "B.Paste")
			(net "GND")
			(options
				(clearance outline)
				(anchor circle)
			)
			(primitives
				(gr_poly
					(pts
						(arc
							(start 0.3048 0.2032)
							(mid 0.275042 0.275042)
							(end 0.2032 0.3048)
						)
						(arc
							(start -0.2032 0.3048)
							(mid -0.275042 0.275042)
							(end -0.3048 0.2032)
						)
						(arc
							(start -0.3048 -0.2032)
							(mid -0.275042 -0.275042)
							(end -0.2032 -0.3048)
						)
						(arc
							(start 0.2032 -0.3048)
							(mid 0.275042 -0.275042)
							(end 0.3048 -0.2032)
						)
					)
					(width 0)
					(fill yes)
				)
			)
		)
	)
	(footprint ""
		(layer "B.Cu")
		(at 260.600698 -281.888946 90)
		(property "Reference" "R1180"
			(at 0 0 90)
			(layer "B.SilkS")
			(hide yes)
			(effects
				(font
					(size 1.27 1.27)
				)
				(justify mirror)
			)
		)
		(property "Value" "10KR2F-2-GP"
			(at -0.064008 -3.993896 90)
			(unlocked yes)
			(layer "B.Fab")
			(hide yes)
			(effects
				(font
					(size 1.016 1.016)
					(thickness 0.1524)
				)
				(justify mirror)
			)
		)
		(property "Device Type" "R402H16"
			(at -0.064008 -5.517896 90)
			(unlocked yes)
			(layer "B.Fab")
			(hide yes)
			(effects
				(font
					(size 1.016 1.016)
					(thickness 0.1524)
				)
				(justify mirror)
			)
		)
		(duplicate_pad_numbers_are_jumpers no)
		(fp_line
			(start 0.508 -0.9398)
			(end 0.508 0.9398)
			(stroke
				(width 0.1524)
				(type default)
			)
			(layer "B.SilkS")
		)
		(fp_line
			(start -0.508 -0.9398)
			(end 0.508 -0.9398)
			(stroke
				(width 0.1524)
				(type default)
			)
			(layer "B.SilkS")
		)
		(fp_rect
			(start 0.508 0.9398)
			(end -0.508 -0.9398)
			(stroke
				(width 0)
				(type default)
			)
			(fill no)
			(layer "B.CrtYd")
		)
		(fp_rect
			(start 0.508 0.9398)
			(end -0.508 -0.9398)
			(stroke
				(width 0)
				(type default)
			)
			(fill no)
			(layer "B.Fab")
		)
		(pad "1" smd custom
			(at 0 -0.4445 270)
			(size 0.1397 0.1397)
			(layers "B.Cu" "B.Mask" "B.Paste")
			(net "P3V3_STBY_VRG5")
			(options
				(clearance outline)
				(anchor circle)
			)
			(primitives
				(gr_poly
					(pts
						(arc
							(start -0.1778 0.2794)
							(mid -0.249642 0.249642)
							(end -0.2794 0.1778)
						)
						(arc
							(start -0.2794 -0.1778)
							(mid -0.249642 -0.249642)
							(end -0.1778 -0.2794)
						)
						(arc
							(start 0.1778 -0.2794)
							(mid 0.249642 -0.249642)
							(end 0.2794 -0.1778)
						)
						(arc
							(start 0.2794 0.1778)
							(mid 0.249642 0.249642)
							(end 0.1778 0.2794)
						)
					)
					(width 0)
					(fill yes)
				)
			)
		)
		(pad "2" smd custom
			(at 0 0.4445 270)
			(size 0.1397 0.1397)
			(layers "B.Cu" "B.Mask" "B.Paste")
			(net "PWRGD_P3V3_STBY")
			(options
				(clearance outline)
				(anchor circle)
			)
			(primitives
				(gr_poly
					(pts
						(arc
							(start -0.1778 0.2794)
							(mid -0.249642 0.249642)
							(end -0.2794 0.1778)
						)
						(arc
							(start -0.2794 -0.1778)
							(mid -0.249642 -0.249642)
							(end -0.1778 -0.2794)
						)
						(arc
							(start 0.1778 -0.2794)
							(mid 0.249642 -0.249642)
							(end 0.2794 -0.1778)
						)
						(arc
							(start 0.2794 0.1778)
							(mid 0.249642 0.249642)
							(end 0.1778 0.2794)
						)
					)
					(width 0)
					(fill yes)
				)
			)
		)
	)
	(footprint ""
		(layer "B.Cu")
		(at 466.917024 -230.911654 -90)
		(property "Reference" "C665"
			(at 0 0 90)
			(layer "B.SilkS")
			(hide yes)
			(effects
				(font
					(size 1.27 1.27)
				)
				(justify mirror)
			)
		)
		(property "Value" "SC470P50V2KX-3GP"
			(at -1.1811 -2.7051 270)
			(unlocked yes)
			(layer "B.Fab")
			(hide yes)
			(effects
				(font
					(size 1.016 1.016)
					(thickness 0.1524)
				)
				(justify mirror)
			)
		)
		(property "Device Type" "C402H22"
			(at -1.1811 -4.2291 270)
			(unlocked yes)
			(layer "B.Fab")
			(hide yes)
			(effects
				(font
					(size 1.016 1.016)
					(thickness 0.1524)
				)
				(justify mirror)
			)
		)
		(duplicate_pad_numbers_are_jumpers no)
		(fp_rect
			(start 0.4318 0.9525)
			(end -0.4318 -0.9525)
			(stroke
				(width 0)
				(type default)
			)
			(fill no)
			(layer "B.CrtYd")
		)
		(fp_rect
			(start 0.4318 0.9525)
			(end -0.4318 -0.9525)
			(stroke
				(width 0)
				(type default)
			)
			(fill no)
			(layer "B.Fab")
		)
		(pad "1" smd custom
			(at 0 -0.4445 90)
			(size 0.1524 0.1524)
			(layers "B.Cu" "B.Mask" "B.Paste")
			(net "P5V_B_3_LL_R")
			(options
				(clearance outline)
				(anchor circle)
			)
			(primitives
				(gr_poly
					(pts
						(arc
							(start 0.3048 0.2032)
							(mid 0.275042 0.275042)
							(end 0.2032 0.3048)
						)
						(arc
							(start -0.2032 0.3048)
							(mid -0.275042 0.275042)
							(end -0.3048 0.2032)
						)
						(arc
							(start -0.3048 -0.2032)
							(mid -0.275042 -0.275042)
							(end -0.2032 -0.3048)
						)
						(arc
							(start 0.2032 -0.3048)
							(mid 0.275042 -0.275042)
							(end 0.3048 -0.2032)
						)
					)
					(width 0)
					(fill yes)
				)
			)
		)
		(pad "2" smd custom
			(at 0 0.4445 90)
			(size 0.1524 0.1524)
			(layers "B.Cu" "B.Mask" "B.Paste")
			(net "P5V_B_3_VFB")
			(options
				(clearance outline)
				(anchor circle)
			)
			(primitives
				(gr_poly
					(pts
						(arc
							(start 0.3048 0.2032)
							(mid 0.275042 0.275042)
							(end 0.2032 0.3048)
						)
						(arc
							(start -0.2032 0.3048)
							(mid -0.275042 0.275042)
							(end -0.3048 0.2032)
						)
						(arc
							(start -0.3048 -0.2032)
							(mid -0.275042 -0.275042)
							(end -0.2032 -0.3048)
						)
						(arc
							(start 0.2032 -0.3048)
							(mid 0.275042 -0.275042)
							(end 0.3048 -0.2032)
						)
					)
					(width 0)
					(fill yes)
				)
			)
		)
	)
	(footprint ""
		(layer "B.Cu")
		(at 31.9532 -222.0976 90)
		(property "Reference" "L2"
			(at 0 0 90)
			(layer "B.SilkS")
			(hide yes)
			(effects
				(font
					(size 1.27 1.27)
				)
				(justify mirror)
			)
		)
		(property "Value" "IND-1UH-191-GP"
			(at 6.7818 -2.1082 90)
			(unlocked yes)
			(layer "B.Fab")
			(hide yes)
			(effects
				(font
					(size 1.016 1.016)
					(thickness 0.1524)
				)
				(justify mirror)
			)
		)
		(property "Device Type" "L109100-2430-UH119"
			(at 6.7818 -3.6322 90)
			(unlocked yes)
			(layer "B.Fab")
			(hide yes)
			(effects
				(font
					(size 1.016 1.016)
					(thickness 0.1524)
				)
				(justify mirror)
			)
		)
		(duplicate_pad_numbers_are_jumpers no)
		(fp_line
			(start 5.2578 -6.4262)
			(end -5.2578 -6.4262)
			(stroke
				(width 0.1524)
				(type default)
			)
			(layer "B.SilkS")
		)
		(fp_line
			(start -5.2578 -6.4262)
			(end -5.2578 6.4262)
			(stroke
				(width 0.1524)
				(type default)
			)
			(layer "B.SilkS")
		)
		(fp_line
			(start 5.2578 6.4262)
			(end 5.2578 -6.4262)
			(stroke
				(width 0.1524)
				(type default)
			)
			(layer "B.SilkS")
		)
		(fp_line
			(start -5.2578 6.4262)
			(end 5.2578 6.4262)
			(stroke
				(width 0.1524)
				(type default)
			)
			(layer "B.SilkS")
		)
		(fp_rect
			(start 5.0038 5.4229)
			(end -5.0038 -5.4229)
			(stroke
				(width 0)
				(type default)
			)
			(fill no)
			(layer "B.CrtYd")
		)
		(fp_poly
			(pts
				(xy 5.5118 6.5024) (xy 5.5118 -6.5024) (xy -5.5118 -6.5024) (xy -5.5118 -0.8509) (xy -5.0038 -0.8509)
				(xy -5.0038 -5.4229) (xy 5.0038 -5.4229) (xy 5.0038 5.4229) (xy -5.0038 5.4229) (xy -5.0038 -0.8382)
				(xy -5.5118 -0.8382) (xy -5.5118 6.5024)
			)
			(stroke
				(width 0)
				(type default)
			)
			(fill no)
			(layer "B.CrtYd")
		)
		(fp_rect
			(start 5.5118 6.5024)
			(end -5.5118 -6.5024)
			(stroke
				(width 0)
				(type default)
			)
			(fill no)
			(layer "B.Fab")
		)
		(pad "1" smd rect
			(at 0 -4.396994 270)
			(size 3.5052 3.556)
			(layers "B.Cu" "B.Mask" "B.Paste")
			(net "P5V_B_1_LL")
		)
		(pad "2" smd rect
			(at 0 4.396994 270)
			(size 3.5052 3.556)
			(layers "B.Cu" "B.Mask" "B.Paste")
			(net "P5V_B_1")
		)
	)
	(footprint ""
		(layer "B.Cu")
		(at 130.263646 -364.93577 180)
		(property "Reference" "R144"
			(at 0 0 0)
			(layer "B.SilkS")
			(hide yes)
			(effects
				(font
					(size 1.27 1.27)
				)
				(justify mirror)
			)
		)
		(property "Value" "200KR2F-L-GP"
			(at -0.064008 -3.993896 180)
			(unlocked yes)
			(layer "B.Fab")
			(hide yes)
			(effects
				(font
					(size 1.016 1.016)
					(thickness 0.1524)
				)
				(justify mirror)
			)
		)
		(property "Device Type" "R402H16"
			(at -0.064008 -5.517896 180)
			(unlocked yes)
			(layer "B.Fab")
			(hide yes)
			(effects
				(font
					(size 1.016 1.016)
					(thickness 0.1524)
				)
				(justify mirror)
			)
		)
		(duplicate_pad_numbers_are_jumpers no)
		(fp_line
			(start 0.508 -0.9398)
			(end 0.508 0.9398)
			(stroke
				(width 0.1524)
				(type default)
			)
			(layer "B.SilkS")
		)
		(fp_line
			(start -0.508 -0.9398)
			(end 0.508 -0.9398)
			(stroke
				(width 0.1524)
				(type default)
			)
			(layer "B.SilkS")
		)
		(fp_rect
			(start 0.508 0.9398)
			(end -0.508 -0.9398)
			(stroke
				(width 0)
				(type default)
			)
			(fill no)
			(layer "B.CrtYd")
		)
		(fp_rect
			(start 0.508 0.9398)
			(end -0.508 -0.9398)
			(stroke
				(width 0)
				(type default)
			)
			(fill no)
			(layer "B.Fab")
		)
		(pad "1" smd custom
			(at 0 -0.4445)
			(size 0.1397 0.1397)
			(layers "B.Cu" "B.Mask" "B.Paste")
			(net "GATE_FAN1")
			(options
				(clearance outline)
				(anchor circle)
			)
			(primitives
				(gr_poly
					(pts
						(arc
							(start -0.1778 0.2794)
							(mid -0.249642 0.249642)
							(end -0.2794 0.1778)
						)
						(arc
							(start -0.2794 -0.1778)
							(mid -0.249642 -0.249642)
							(end -0.1778 -0.2794)
						)
						(arc
							(start 0.1778 -0.2794)
							(mid 0.249642 -0.249642)
							(end 0.2794 -0.1778)
						)
						(arc
							(start 0.2794 0.1778)
							(mid 0.249642 0.249642)
							(end 0.1778 0.2794)
						)
					)
					(width 0)
					(fill yes)
				)
			)
		)
		(pad "2" smd custom
			(at 0 0.4445)
			(size 0.1397 0.1397)
			(layers "B.Cu" "B.Mask" "B.Paste")
			(net "GATE_FAN1_R")
			(options
				(clearance outline)
				(anchor circle)
			)
			(primitives
				(gr_poly
					(pts
						(arc
							(start -0.1778 0.2794)
							(mid -0.249642 0.249642)
							(end -0.2794 0.1778)
						)
						(arc
							(start -0.2794 -0.1778)
							(mid -0.249642 -0.249642)
							(end -0.1778 -0.2794)
						)
						(arc
							(start 0.1778 -0.2794)
							(mid 0.249642 -0.249642)
							(end 0.2794 -0.1778)
						)
						(arc
							(start 0.2794 0.1778)
							(mid 0.249642 0.249642)
							(end 0.1778 0.2794)
						)
					)
					(width 0)
					(fill yes)
				)
			)
		)
	)
	(footprint ""
		(layer "B.Cu")
		(at 457.2 -224.917 -90)
		(property "Reference" "U33"
			(at 0 0 90)
			(layer "B.SilkS")
			(hide yes)
			(effects
				(font
					(size 1.27 1.27)
				)
				(justify mirror)
			)
		)
		(property "Value" "TPS53319DQPR-GP"
			(at -4.7498 -5.6896 270)
			(unlocked yes)
			(layer "B.Fab")
			(hide yes)
			(effects
				(font
					(size 1.016 1.016)
					(thickness 0.1524)
				)
				(justify mirror)
			)
		)
		(property "Device Type" "QFN22G6050-G6133H60"
			(at -4.7498 -7.2136 270)
			(unlocked yes)
			(layer "B.Fab")
			(hide yes)
			(effects
				(font
					(size 1.016 1.016)
					(thickness 0.1524)
				)
				(justify mirror)
			)
		)
		(duplicate_pad_numbers_are_jumpers no)
		(fp_line
			(start -3.556 3.5179)
			(end -3.556 2.2479)
			(stroke
				(width 0.1524)
				(type default)
			)
			(layer "B.SilkS")
		)
		(fp_line
			(start -2.286 3.5179)
			(end -3.556 3.5179)
			(stroke
				(width 0.1524)
				(type default)
			)
			(layer "B.SilkS")
		)
		(fp_line
			(start 3.556 3.5179)
			(end 2.286 3.5179)
			(stroke
				(width 0.1524)
				(type default)
			)
			(layer "B.SilkS")
		)
		(fp_line
			(start -1.500124 3.262122)
			(end -1.500124 4.024122)
			(stroke
				(width 0.1524)
				(type default)
			)
			(layer "B.SilkS")
		)
		(fp_line
			(start 0.999998 3.262122)
			(end 0.999998 3.770122)
			(stroke
				(width 0.1524)
				(type default)
			)
			(layer "B.SilkS")
		)
		(fp_line
			(start 3.556 2.2479)
			(end 3.556 3.5179)
			(stroke
				(width 0.1524)
				(type default)
			)
			(layer "B.SilkS")
		)
		(fp_line
			(start -0.500126 -3.262122)
			(end -0.500126 -3.770122)
			(stroke
				(width 0.1524)
				(type default)
			)
			(layer "B.SilkS")
		)
		(fp_line
			(start 1.999996 -3.262122)
			(end 1.999996 -4.024122)
			(stroke
				(width 0.1524)
				(type default)
			)
			(layer "B.SilkS")
		)
		(fp_line
			(start 2.286 -3.5179)
			(end 3.556 -3.5179)
			(stroke
				(width 0.1524)
				(type default)
			)
			(layer "B.SilkS")
		)
		(fp_line
			(start 3.556 -3.5179)
			(end 3.556 -2.2479)
			(stroke
				(width 0.1524)
				(type default)
			)
			(layer "B.SilkS")
		)
		(fp_poly
			(pts
				(xy -3.556 -3.5179) (xy -2.5273 -3.5179) (xy -3.556 -2.4892)
			)
			(stroke
				(width 0)
				(type default)
			)
			(fill yes)
			(layer "B.SilkS")
		)
		(fp_rect
			(start 2.9972 2.5019)
			(end -2.9972 -2.5019)
			(stroke
				(width 0)
				(type default)
			)
			(fill no)
			(layer "B.CrtYd")
		)
		(fp_poly
			(pts
				(xy -3.556 -2.5019) (xy 2.9972 -2.5019) (xy 2.9972 2.5019) (xy -2.9972 2.5019) (xy -2.9972 -2.4892)
				(xy -3.556 -2.4892) (xy -3.556 3.5179) (xy 3.556 3.5179) (xy 3.556 -3.5179) (xy -3.556 -3.5179)
			)
			(stroke
				(width 0)
				(type default)
			)
			(fill no)
			(layer "B.CrtYd")
		)
		(fp_rect
			(start 3.556 3.5179)
			(end -3.556 -3.5179)
			(stroke
				(width 0)
				(type default)
			)
			(fill no)
			(layer "B.Fab")
		)
		(pad "1" smd rect
			(at -2.500122 -2.449322 90)
			(size 0.3048 1.1176)
			(layers "B.Cu" "B.Mask" "B.Paste")
			(net "P5V_B_3_VFB")
		)
		(pad "2" smd rect
			(at -1.999996 -2.449322 90)
			(size 0.3048 1.1176)
			(layers "B.Cu" "B.Mask" "B.Paste")
			(net "P5V_B_3_EN_R")
		)
		(pad "3" smd rect
			(at -1.500124 -2.449322 90)
			(size 0.3048 1.1176)
			(layers "B.Cu" "B.Mask" "B.Paste")
			(net "P5V_B_3_PGOOD")
		)
		(pad "4" smd rect
			(at -0.999998 -2.449322 90)
			(size 0.3048 1.1176)
			(layers "B.Cu" "B.Mask" "B.Paste")
			(net "P5V_B_3_VBST")
		)
		(pad "5" smd rect
			(at -0.500126 -2.449322 90)
			(size 0.3048 1.1176)
			(layers "B.Cu" "B.Mask" "B.Paste")
			(net "P5V_B_3_ROVP")
		)
		(pad "6" smd rect
			(at 0 -2.449322 90)
			(size 0.3048 1.1176)
			(layers "B.Cu" "B.Mask" "B.Paste")
			(net "P5V_B_3_LL")
		)
		(pad "7" smd rect
			(at 0.500126 -2.449322 90)
			(size 0.3048 1.1176)
			(layers "B.Cu" "B.Mask" "B.Paste")
			(net "P5V_B_3_LL")
		)
		(pad "8" smd rect
			(at 0.999998 -2.449322 90)
			(size 0.3048 1.1176)
			(layers "B.Cu" "B.Mask" "B.Paste")
			(net "P5V_B_3_LL")
		)
		(pad "9" smd rect
			(at 1.500124 -2.449322 90)
			(size 0.3048 1.1176)
			(layers "B.Cu" "B.Mask" "B.Paste")
			(net "P5V_B_3_LL")
		)
		(pad "10" smd rect
			(at 1.999996 -2.449322 90)
			(size 0.3048 1.1176)
			(layers "B.Cu" "B.Mask" "B.Paste")
			(net "P5V_B_3_LL")
		)
		(pad "11" smd rect
			(at 2.500122 -2.449322 90)
			(size 0.3048 1.1176)
			(layers "B.Cu" "B.Mask" "B.Paste")
			(net "P5V_B_3_LL")
		)
		(pad "12" smd rect
			(at 2.500122 2.449322 90)
			(size 0.3048 1.1176)
			(layers "B.Cu" "B.Mask" "B.Paste")
			(net "P12V_B_3_VIN_U33")
		)
		(pad "13" smd rect
			(at 1.999996 2.449322 90)
			(size 0.3048 1.1176)
			(layers "B.Cu" "B.Mask" "B.Paste")
			(net "P12V_B_3_VIN_U33")
		)
		(pad "14" smd rect
			(at 1.500124 2.449322 90)
			(size 0.3048 1.1176)
			(layers "B.Cu" "B.Mask" "B.Paste")
			(net "P12V_B_3_VIN_U33")
		)
		(pad "15" smd rect
			(at 0.999998 2.449322 90)
			(size 0.3048 1.1176)
			(layers "B.Cu" "B.Mask" "B.Paste")
			(net "P12V_B_3_VIN_U33")
		)
		(pad "16" smd rect
			(at 0.500126 2.449322 90)
			(size 0.3048 1.1176)
			(layers "B.Cu" "B.Mask" "B.Paste")
			(net "P12V_B_3_VIN_U33")
		)
		(pad "17" smd rect
			(at 0 2.449322 90)
			(size 0.3048 1.1176)
			(layers "B.Cu" "B.Mask" "B.Paste")
			(net "P12V_B_3_VIN_U33")
		)
		(pad "18" smd rect
			(at -0.500126 2.449322 90)
			(size 0.3048 1.1176)
			(layers "B.Cu" "B.Mask" "B.Paste")
			(net "P5V_B_3_VREG")
		)
		(pad "19" smd rect
			(at -0.999998 2.449322 90)
			(size 0.3048 1.1176)
			(layers "B.Cu" "B.Mask" "B.Paste")
			(net "P12V_B_3_VDD_U33")
		)
		(pad "20" smd rect
			(at -1.500124 2.449322 90)
			(size 0.3048 1.1176)
			(layers "B.Cu" "B.Mask" "B.Paste")
			(net "P5V_B_3_MODE")
		)
		(pad "21" smd rect
			(at -1.999996 2.449322 90)
			(size 0.3048 1.1176)
			(layers "B.Cu" "B.Mask" "B.Paste")
			(net "P5V_B_3_TRIP")
		)
		(pad "22" smd rect
			(at -2.500122 2.449322 90)
			(size 0.3048 1.1176)
			(layers "B.Cu" "B.Mask" "B.Paste")
			(net "P5V_B_3_RF")
		)
		(pad "23" smd custom
			(at 0 0 90)
			(size 0.83185 0.83185)
			(layers "B.Cu" "B.Mask" "B.Paste")
			(net "GND")
			(options
				(clearance outline)
				(anchor circle)
			)
			(primitives
				(gr_poly
					(pts
						(xy -2.7813 -1.6637) (xy -2.7813 -1.2954) (xy -3.048 -1.2954) (xy -3.048 -0.9525) (xy -2.7813 -0.9525)
						(xy -2.7813 0.9525) (xy -3.048 0.9525) (xy -3.048 1.2954) (xy -2.7813 1.2954) (xy -2.7813 1.6637)
						(xy 2.7813 1.6637) (xy 2.7813 1.2954) (xy 3.048 1.2954) (xy 3.048 0.9525) (xy 2.7813 0.9525) (xy 2.7813 -0.9525)
						(xy 3.048 -0.9525) (xy 3.048 -1.2954) (xy 2.7813 -1.2954) (xy 2.7813 -1.6637)
					)
					(width 0)
					(fill yes)
				)
			)
		)
	)
	(footprint ""
		(layer "B.Cu")
		(at 248.031 -275.463 -90)
		(property "Reference" "C697"
			(at 0 0 90)
			(layer "B.SilkS")
			(hide yes)
			(effects
				(font
					(size 1.27 1.27)
				)
				(justify mirror)
			)
		)
		(property "Value" "SC2200P50V2KX-2GP"
			(at -1.1811 -2.7051 270)
			(unlocked yes)
			(layer "B.Fab")
			(hide yes)
			(effects
				(font
					(size 1.016 1.016)
					(thickness 0.1524)
				)
				(justify mirror)
			)
		)
		(property "Device Type" "C402H22"
			(at -1.1811 -4.2291 270)
			(unlocked yes)
			(layer "B.Fab")
			(hide yes)
			(effects
				(font
					(size 1.016 1.016)
					(thickness 0.1524)
				)
				(justify mirror)
			)
		)
		(duplicate_pad_numbers_are_jumpers no)
		(fp_rect
			(start 0.4318 0.9525)
			(end -0.4318 -0.9525)
			(stroke
				(width 0)
				(type default)
			)
			(fill no)
			(layer "B.CrtYd")
		)
		(fp_rect
			(start 0.4318 0.9525)
			(end -0.4318 -0.9525)
			(stroke
				(width 0)
				(type default)
			)
			(fill no)
			(layer "B.Fab")
		)
		(pad "1" smd custom
			(at 0 -0.4445 90)
			(size 0.1524 0.1524)
			(layers "B.Cu" "B.Mask" "B.Paste")
			(net "P3V3_STBY_SW")
			(options
				(clearance outline)
				(anchor circle)
			)
			(primitives
				(gr_poly
					(pts
						(arc
							(start 0.3048 0.2032)
							(mid 0.275042 0.275042)
							(end 0.2032 0.3048)
						)
						(arc
							(start -0.2032 0.3048)
							(mid -0.275042 0.275042)
							(end -0.3048 0.2032)
						)
						(arc
							(start -0.3048 -0.2032)
							(mid -0.275042 -0.275042)
							(end -0.2032 -0.3048)
						)
						(arc
							(start 0.2032 -0.3048)
							(mid 0.275042 -0.275042)
							(end 0.3048 -0.2032)
						)
					)
					(width 0)
					(fill yes)
				)
			)
		)
		(pad "2" smd custom
			(at 0 0.4445 90)
			(size 0.1524 0.1524)
			(layers "B.Cu" "B.Mask" "B.Paste")
			(net "P3V3_STBY_SNB")
			(options
				(clearance outline)
				(anchor circle)
			)
			(primitives
				(gr_poly
					(pts
						(arc
							(start 0.3048 0.2032)
							(mid 0.275042 0.275042)
							(end 0.2032 0.3048)
						)
						(arc
							(start -0.2032 0.3048)
							(mid -0.275042 0.275042)
							(end -0.3048 0.2032)
						)
						(arc
							(start -0.3048 -0.2032)
							(mid -0.275042 -0.275042)
							(end -0.2032 -0.3048)
						)
						(arc
							(start 0.2032 -0.3048)
							(mid 0.275042 -0.275042)
							(end 0.3048 -0.2032)
						)
					)
					(width 0)
					(fill yes)
				)
			)
		)
	)
	(footprint ""
		(layer "B.Cu")
		(at 65.945258 -118.859046 180)
		(property "Reference" "TC11"
			(at 0 0 0)
			(layer "B.SilkS")
			(hide yes)
			(effects
				(font
					(size 1.27 1.27)
				)
				(justify mirror)
			)
		)
		(property "Value" "ST220U10VDM-LGP"
			(at 0 -9.6012 180)
			(unlocked yes)
			(layer "B.Fab")
			(hide yes)
			(effects
				(font
					(size 1.016 1.016)
					(thickness 0.1524)
				)
				(justify mirror)
			)
		)
		(property "Device Type" "CT7343H119"
			(at 0 -11.1252 180)
			(unlocked yes)
			(layer "B.Fab")
			(hide yes)
			(effects
				(font
					(size 1.016 1.016)
					(thickness 0.1524)
				)
				(justify mirror)
			)
		)
		(duplicate_pad_numbers_are_jumpers no)
		(fp_line
			(start 2.286 4.8768)
			(end 2.286 2.032)
			(stroke
				(width 0.1524)
				(type default)
			)
			(layer "B.SilkS")
		)
		(fp_line
			(start 2.286 -4.8768)
			(end 2.286 -2.032)
			(stroke
				(width 0.1524)
				(type default)
			)
			(layer "B.SilkS")
		)
		(fp_line
			(start -2.1082 -4.699)
			(end 2.1082 -4.699)
			(stroke
				(width 0.508)
				(type default)
			)
			(layer "B.SilkS")
		)
		(fp_line
			(start -2.286 4.8768)
			(end 2.286 4.8768)
			(stroke
				(width 0.1524)
				(type default)
			)
			(layer "B.SilkS")
		)
		(fp_line
			(start -2.286 2.032)
			(end -2.286 4.8768)
			(stroke
				(width 0.1524)
				(type default)
			)
			(layer "B.SilkS")
		)
		(fp_line
			(start -2.286 -2.032)
			(end -2.286 -4.8768)
			(stroke
				(width 0.1524)
				(type default)
			)
			(layer "B.SilkS")
		)
		(fp_line
			(start -2.286 -4.8768)
			(end 2.286 -4.8768)
			(stroke
				(width 0.1524)
				(type default)
			)
			(layer "B.SilkS")
		)
		(fp_rect
			(start 2.1463 3.6449)
			(end -2.1463 -3.6449)
			(stroke
				(width 0)
				(type default)
			)
			(fill no)
			(layer "B.CrtYd")
		)
		(fp_poly
			(pts
				(xy 2.54 4.953) (xy 2.54 4.2926) (xy 3.81 4.2926) (xy 3.81 -4.2926) (xy 2.54 -4.2926) (xy 2.54 -4.953)
				(xy -2.54 -4.953) (xy -2.54 -4.2926) (xy -3.81 -4.2926) (xy -3.81 -1.6256) (xy -2.1463 -1.6256)
				(xy -2.1463 -3.6449) (xy 2.1463 -3.6449) (xy 2.1463 3.6449) (xy -2.1463 3.6449) (xy -2.1463 -1.6129)
				(xy -3.81 -1.6129) (xy -3.81 4.2926) (xy -2.54 4.2926) (xy -2.54 4.953)
			)
			(stroke
				(width 0)
				(type default)
			)
			(fill no)
			(layer "B.CrtYd")
		)
		(fp_rect
			(start 3.81 4.2926)
			(end 2.54 -4.2926)
			(stroke
				(width 0)
				(type default)
			)
			(fill no)
			(layer "B.Fab")
		)
		(fp_rect
			(start 2.54 4.953)
			(end -2.54 -4.953)
			(stroke
				(width 0)
				(type default)
			)
			(fill no)
			(layer "B.Fab")
		)
		(fp_rect
			(start -2.54 4.2926)
			(end -3.81 -4.2926)
			(stroke
				(width 0)
				(type default)
			)
			(fill no)
			(layer "B.Fab")
		)
		(pad "1" smd rect
			(at 0 -3.1496)
			(size 2.413 2.286)
			(layers "B.Cu" "B.Mask" "B.Paste")
			(net "P5V_B_2")
		)
		(pad "2" smd rect
			(at 0 3.1496)
			(size 2.413 2.286)
			(layers "B.Cu" "B.Mask" "B.Paste")
			(net "GND")
		)
		(zone
			(layer "B.Cu")
			(hatch none 0.5)
			(connect_pads
				(clearance 0)
			)
			(min_thickness 0.25)
			(keepout
				(tracks allowed)
				(vias not_allowed)
				(pads allowed)
				(copperpour not_allowed)
				(footprints allowed)
			)
			(placement
				(enabled no)
				(sheetname "")
			)
			(fill
				(thermal_gap 0.5)
				(thermal_bridge_width 0.5)
				(island_removal_mode 0)
			)
			(polygon
				(pts
					(xy 64.433958 -123.456446) (xy 67.456558 -123.456446) (xy 67.456558 -120.560846) (xy 67.456558 -120.230646)
					(xy 64.433958 -120.230646) (xy 64.433958 -120.560846)
				)
			)
		)
		(zone
			(layer "B.Cu")
			(hatch none 0.5)
			(connect_pads
				(clearance 0)
			)
			(min_thickness 0.25)
			(keepout
				(tracks allowed)
				(vias not_allowed)
				(pads allowed)
				(copperpour not_allowed)
				(footprints allowed)
			)
			(placement
				(enabled no)
				(sheetname "")
			)
			(fill
				(thermal_gap 0.5)
				(thermal_bridge_width 0.5)
				(island_removal_mode 0)
			)
			(polygon
				(pts
					(xy 67.456558 -117.169946) (xy 67.456558 -114.261646) (xy 64.433958 -114.261646) (xy 64.433958 -117.157246)
					(xy 64.433958 -117.487446) (xy 67.456558 -117.487446)
				)
			)
		)
	)
	(footprint ""
		(layer "B.Cu")
		(at 466.530944 -229.101396 180)
		(property "Reference" "R1141"
			(at 0 0 0)
			(layer "B.SilkS")
			(hide yes)
			(effects
				(font
					(size 1.27 1.27)
				)
				(justify mirror)
			)
		)
		(property "Value" "2K7R2F-GP"
			(at -0.064008 -3.993896 180)
			(unlocked yes)
			(layer "B.Fab")
			(hide yes)
			(effects
				(font
					(size 1.016 1.016)
					(thickness 0.1524)
				)
				(justify mirror)
			)
		)
		(property "Device Type" "R402H16"
			(at -0.064008 -5.517896 180)
			(unlocked yes)
			(layer "B.Fab")
			(hide yes)
			(effects
				(font
					(size 1.016 1.016)
					(thickness 0.1524)
				)
				(justify mirror)
			)
		)
		(duplicate_pad_numbers_are_jumpers no)
		(fp_line
			(start 0.508 -0.9398)
			(end 0.508 0.9398)
			(stroke
				(width 0.1524)
				(type default)
			)
			(layer "B.SilkS")
		)
		(fp_line
			(start -0.508 -0.9398)
			(end 0.508 -0.9398)
			(stroke
				(width 0.1524)
				(type default)
			)
			(layer "B.SilkS")
		)
		(fp_rect
			(start 0.508 0.9398)
			(end -0.508 -0.9398)
			(stroke
				(width 0)
				(type default)
			)
			(fill no)
			(layer "B.CrtYd")
		)
		(fp_rect
			(start 0.508 0.9398)
			(end -0.508 -0.9398)
			(stroke
				(width 0)
				(type default)
			)
			(fill no)
			(layer "B.Fab")
		)
		(pad "1" smd custom
			(at 0 -0.4445)
			(size 0.1397 0.1397)
			(layers "B.Cu" "B.Mask" "B.Paste")
			(net "P5V_B_3_LL")
			(options
				(clearance outline)
				(anchor circle)
			)
			(primitives
				(gr_poly
					(pts
						(arc
							(start -0.1778 0.2794)
							(mid -0.249642 0.249642)
							(end -0.2794 0.1778)
						)
						(arc
							(start -0.2794 -0.1778)
							(mid -0.249642 -0.249642)
							(end -0.1778 -0.2794)
						)
						(arc
							(start 0.1778 -0.2794)
							(mid 0.249642 -0.249642)
							(end 0.2794 -0.1778)
						)
						(arc
							(start 0.2794 0.1778)
							(mid 0.249642 0.249642)
							(end 0.1778 0.2794)
						)
					)
					(width 0)
					(fill yes)
				)
			)
		)
		(pad "2" smd custom
			(at 0 0.4445)
			(size 0.1397 0.1397)
			(layers "B.Cu" "B.Mask" "B.Paste")
			(net "P5V_B_3_LL_R")
			(options
				(clearance outline)
				(anchor circle)
			)
			(primitives
				(gr_poly
					(pts
						(arc
							(start -0.1778 0.2794)
							(mid -0.249642 0.249642)
							(end -0.2794 0.1778)
						)
						(arc
							(start -0.2794 -0.1778)
							(mid -0.249642 -0.249642)
							(end -0.1778 -0.2794)
						)
						(arc
							(start 0.1778 -0.2794)
							(mid 0.249642 -0.249642)
							(end 0.2794 -0.1778)
						)
						(arc
							(start 0.2794 0.1778)
							(mid 0.249642 0.249642)
							(end 0.1778 0.2794)
						)
					)
					(width 0)
					(fill yes)
				)
			)
		)
	)
	(footprint ""
		(layer "B.Cu")
		(at 181.6862 -371.7544 90)
		(property "Reference" "C544"
			(at 0 0 90)
			(layer "B.SilkS")
			(hide yes)
			(effects
				(font
					(size 1.27 1.27)
				)
				(justify mirror)
			)
		)
		(property "Value" "SC2D2U25V5KX-2-GP"
			(at 0.0762 -6.1214 90)
			(unlocked yes)
			(layer "B.Fab")
			(hide yes)
			(effects
				(font
					(size 1.016 1.016)
					(thickness 0.1524)
				)
				(justify mirror)
			)
		)
		(property "Device Type" "C805H54"
			(at 0.0762 -8.1534 90)
			(unlocked yes)
			(layer "B.Fab")
			(hide yes)
			(effects
				(font
					(size 1.016 1.016)
					(thickness 0.1524)
				)
				(justify mirror)
			)
		)
		(duplicate_pad_numbers_are_jumpers no)
		(fp_line
			(start -0.635 0)
			(end 0.635 0)
			(stroke
				(width 0.508)
				(type default)
			)
			(layer "B.SilkS")
		)
		(fp_rect
			(start 0.9652 1.778)
			(end -0.9652 -1.778)
			(stroke
				(width 0)
				(type default)
			)
			(fill no)
			(layer "B.CrtYd")
		)
		(fp_poly
			(pts
				(xy 0.9652 -1.778) (xy -0.9652 -1.778) (xy -0.9652 1.778) (xy 0.9652 1.778)
			)
			(stroke
				(width 0)
				(type default)
			)
			(fill no)
			(layer "B.Fab")
		)
		(pad "1" smd rect
			(at 0 -0.9652 270)
			(size 1.397 1.143)
			(layers "B.Cu" "B.Mask" "B.Paste")
			(net "P12V_IN_PGOOD")
		)
		(pad "2" smd rect
			(at 0 0.9652 270)
			(size 1.397 1.143)
			(layers "B.Cu" "B.Mask" "B.Paste")
			(net "GND")
		)
	)
	(footprint ""
		(layer "B.Cu")
		(at 33.57626 -112.239806 180)
		(property "Reference" "R1118"
			(at 0 0 0)
			(layer "B.SilkS")
			(hide yes)
			(effects
				(font
					(size 1.27 1.27)
				)
				(justify mirror)
			)
		)
		(property "Value" "2D2R3-1-U-GP"
			(at 0.0254 -2.5146 180)
			(unlocked yes)
			(layer "B.Fab")
			(hide yes)
			(effects
				(font
					(size 1.016 1.016)
					(thickness 0.1524)
				)
				(justify mirror)
			)
		)
		(property "Device Type" "R603H22"
			(at 0.0254 -4.0386 180)
			(unlocked yes)
			(layer "B.Fab")
			(hide yes)
			(effects
				(font
					(size 1.016 1.016)
					(thickness 0.1524)
				)
				(justify mirror)
			)
		)
		(duplicate_pad_numbers_are_jumpers no)
		(fp_line
			(start 0.4826 0)
			(end 0.2032 0)
			(stroke
				(width 0.2032)
				(type default)
			)
			(layer "B.SilkS")
		)
		(fp_line
			(start -0.2032 0)
			(end -0.4826 0)
			(stroke
				(width 0.2032)
				(type default)
			)
			(layer "B.SilkS")
		)
		(fp_rect
			(start 0.5842 1.3335)
			(end -0.5842 -1.3335)
			(stroke
				(width 0)
				(type default)
			)
			(fill no)
			(layer "B.CrtYd")
		)
		(fp_rect
			(start 0.5842 1.3335)
			(end -0.5842 -1.3335)
			(stroke
				(width 0)
				(type default)
			)
			(fill no)
			(layer "B.Fab")
		)
		(pad "1" smd custom
			(at 0 -0.762)
			(size 0.2159 0.2159)
			(layers "B.Cu" "B.Mask" "B.Paste")
			(net "P12V_B")
			(options
				(clearance outline)
				(anchor circle)
			)
			(primitives
				(gr_poly
					(pts
						(arc
							(start -0.3302 0.4318)
							(mid -0.402042 0.402042)
							(end -0.4318 0.3302)
						)
						(arc
							(start -0.4318 -0.3302)
							(mid -0.402042 -0.402042)
							(end -0.3302 -0.4318)
						)
						(arc
							(start 0.3302 -0.4318)
							(mid 0.402042 -0.402042)
							(end 0.4318 -0.3302)
						)
						(arc
							(start 0.4318 0.3302)
							(mid 0.402042 0.402042)
							(end 0.3302 0.4318)
						)
					)
					(width 0)
					(fill yes)
				)
			)
		)
		(pad "2" smd custom
			(at 0 0.762)
			(size 0.2159 0.2159)
			(layers "B.Cu" "B.Mask" "B.Paste")
			(net "P12V_B_2_VDD_U32")
			(options
				(clearance outline)
				(anchor circle)
			)
			(primitives
				(gr_poly
					(pts
						(arc
							(start -0.3302 0.4318)
							(mid -0.402042 0.402042)
							(end -0.4318 0.3302)
						)
						(arc
							(start -0.4318 -0.3302)
							(mid -0.402042 -0.402042)
							(end -0.3302 -0.4318)
						)
						(arc
							(start 0.3302 -0.4318)
							(mid 0.402042 -0.402042)
							(end 0.4318 -0.3302)
						)
						(arc
							(start 0.4318 0.3302)
							(mid 0.402042 0.402042)
							(end 0.3302 0.4318)
						)
					)
					(width 0)
					(fill yes)
				)
			)
		)
	)
	(footprint ""
		(layer "B.Cu")
		(at 57.141872 -117.908832 180)
		(property "Reference" "C646"
			(at 0 0 0)
			(layer "B.SilkS")
			(hide yes)
			(effects
				(font
					(size 1.27 1.27)
				)
				(justify mirror)
			)
		)
		(property "Value" "SCD1U50V3KX-GP"
			(at 0 -2.8194 180)
			(unlocked yes)
			(layer "B.Fab")
			(hide yes)
			(effects
				(font
					(size 1.016 1.016)
					(thickness 0.1524)
				)
				(justify mirror)
			)
		)
		(property "Device Type" "C603H36"
			(at 0 -4.3434 180)
			(unlocked yes)
			(layer "B.Fab")
			(hide yes)
			(effects
				(font
					(size 1.016 1.016)
					(thickness 0.1524)
				)
				(justify mirror)
			)
		)
		(duplicate_pad_numbers_are_jumpers no)
		(fp_line
			(start -0.508 0)
			(end 0.508 0)
			(stroke
				(width 0.2032)
				(type default)
			)
			(layer "B.SilkS")
		)
		(fp_rect
			(start 0.5842 1.3335)
			(end -0.5842 -1.3335)
			(stroke
				(width 0)
				(type default)
			)
			(fill no)
			(layer "B.CrtYd")
		)
		(fp_rect
			(start 0.5842 1.3335)
			(end -0.5842 -1.3335)
			(stroke
				(width 0)
				(type default)
			)
			(fill no)
			(layer "B.Fab")
		)
		(pad "1" smd custom
			(at 0 -0.762)
			(size 0.2159 0.2159)
			(layers "B.Cu" "B.Mask" "B.Paste")
			(net "P5V_B_2")
			(options
				(clearance outline)
				(anchor circle)
			)
			(primitives
				(gr_poly
					(pts
						(arc
							(start -0.3302 0.4318)
							(mid -0.402042 0.402042)
							(end -0.4318 0.3302)
						)
						(arc
							(start -0.4318 -0.3302)
							(mid -0.402042 -0.402042)
							(end -0.3302 -0.4318)
						)
						(arc
							(start 0.3302 -0.4318)
							(mid 0.402042 -0.402042)
							(end 0.4318 -0.3302)
						)
						(arc
							(start 0.4318 0.3302)
							(mid 0.402042 0.402042)
							(end 0.3302 0.4318)
						)
					)
					(width 0)
					(fill yes)
				)
			)
		)
		(pad "2" smd custom
			(at 0 0.762)
			(size 0.2159 0.2159)
			(layers "B.Cu" "B.Mask" "B.Paste")
			(net "P5V_B_2_LL_R")
			(options
				(clearance outline)
				(anchor circle)
			)
			(primitives
				(gr_poly
					(pts
						(arc
							(start -0.3302 0.4318)
							(mid -0.402042 0.402042)
							(end -0.4318 0.3302)
						)
						(arc
							(start -0.4318 -0.3302)
							(mid -0.402042 -0.402042)
							(end -0.3302 -0.4318)
						)
						(arc
							(start 0.3302 -0.4318)
							(mid 0.402042 -0.402042)
							(end 0.4318 -0.3302)
						)
						(arc
							(start 0.4318 0.3302)
							(mid 0.402042 0.402042)
							(end 0.3302 0.4318)
						)
					)
					(width 0)
					(fill yes)
				)
			)
		)
	)
	(footprint ""
		(layer "B.Cu")
		(at 37.23386 -111.833406 180)
		(property "Reference" "C636"
			(at 0 0 0)
			(layer "B.SilkS")
			(hide yes)
			(effects
				(font
					(size 1.27 1.27)
				)
				(justify mirror)
			)
		)
		(property "Value" "SC10U16V5KX-7-GP-U"
			(at 0.0762 -6.1214 180)
			(unlocked yes)
			(layer "B.Fab")
			(hide yes)
			(effects
				(font
					(size 1.016 1.016)
					(thickness 0.1524)
				)
				(justify mirror)
			)
		)
		(property "Device Type" "C805H58"
			(at 0.0762 -8.1534 180)
			(unlocked yes)
			(layer "B.Fab")
			(hide yes)
			(effects
				(font
					(size 1.016 1.016)
					(thickness 0.1524)
				)
				(justify mirror)
			)
		)
		(duplicate_pad_numbers_are_jumpers no)
		(fp_line
			(start -0.635 0)
			(end 0.635 0)
			(stroke
				(width 0.508)
				(type default)
			)
			(layer "B.SilkS")
		)
		(fp_rect
			(start 0.9652 1.778)
			(end -0.9652 -1.778)
			(stroke
				(width 0)
				(type default)
			)
			(fill no)
			(layer "B.CrtYd")
		)
		(fp_poly
			(pts
				(xy 0.9652 -1.778) (xy -0.9652 -1.778) (xy -0.9652 1.778) (xy 0.9652 1.778)
			)
			(stroke
				(width 0)
				(type default)
			)
			(fill no)
			(layer "B.Fab")
		)
		(pad "1" smd rect
			(at 0 -0.9652)
			(size 1.397 1.143)
			(layers "B.Cu" "B.Mask" "B.Paste")
			(net "P12V_B_2_VIN_U32")
		)
		(pad "2" smd rect
			(at 0 0.9652)
			(size 1.397 1.143)
			(layers "B.Cu" "B.Mask" "B.Paste")
			(net "GND")
		)
	)
	(footprint ""
		(layer "B.Cu")
		(at 24.450802 -230.63835 90)
		(property "Reference" "C630"
			(at 0 0 90)
			(layer "B.SilkS")
			(hide yes)
			(effects
				(font
					(size 1.27 1.27)
				)
				(justify mirror)
			)
		)
		(property "Value" "SC68P50V2JN-2-GP"
			(at -1.1811 -2.7051 90)
			(unlocked yes)
			(layer "B.Fab")
			(hide yes)
			(effects
				(font
					(size 1.016 1.016)
					(thickness 0.1524)
				)
				(justify mirror)
			)
		)
		(property "Device Type" "C402H22"
			(at -1.1811 -4.2291 90)
			(unlocked yes)
			(layer "B.Fab")
			(hide yes)
			(effects
				(font
					(size 1.016 1.016)
					(thickness 0.1524)
				)
				(justify mirror)
			)
		)
		(duplicate_pad_numbers_are_jumpers no)
		(fp_rect
			(start 0.4318 0.9525)
			(end -0.4318 -0.9525)
			(stroke
				(width 0)
				(type default)
			)
			(fill no)
			(layer "B.CrtYd")
		)
		(fp_rect
			(start 0.4318 0.9525)
			(end -0.4318 -0.9525)
			(stroke
				(width 0)
				(type default)
			)
			(fill no)
			(layer "B.Fab")
		)
		(pad "1" smd custom
			(at 0 -0.4445 270)
			(size 0.1524 0.1524)
			(layers "B.Cu" "B.Mask" "B.Paste")
			(net "P5V_B_1_VFB")
			(options
				(clearance outline)
				(anchor circle)
			)
			(primitives
				(gr_poly
					(pts
						(arc
							(start 0.3048 0.2032)
							(mid 0.275042 0.275042)
							(end 0.2032 0.3048)
						)
						(arc
							(start -0.2032 0.3048)
							(mid -0.275042 0.275042)
							(end -0.3048 0.2032)
						)
						(arc
							(start -0.3048 -0.2032)
							(mid -0.275042 -0.275042)
							(end -0.2032 -0.3048)
						)
						(arc
							(start 0.2032 -0.3048)
							(mid 0.275042 -0.275042)
							(end 0.3048 -0.2032)
						)
					)
					(width 0)
					(fill yes)
				)
			)
		)
		(pad "2" smd custom
			(at 0 0.4445 270)
			(size 0.1524 0.1524)
			(layers "B.Cu" "B.Mask" "B.Paste")
			(net "P5V_B_1_VFB_R")
			(options
				(clearance outline)
				(anchor circle)
			)
			(primitives
				(gr_poly
					(pts
						(arc
							(start 0.3048 0.2032)
							(mid 0.275042 0.275042)
							(end 0.2032 0.3048)
						)
						(arc
							(start -0.2032 0.3048)
							(mid -0.275042 0.275042)
							(end -0.3048 0.2032)
						)
						(arc
							(start -0.3048 -0.2032)
							(mid -0.275042 -0.275042)
							(end -0.2032 -0.3048)
						)
						(arc
							(start 0.2032 -0.3048)
							(mid 0.275042 -0.275042)
							(end 0.3048 -0.2032)
						)
					)
					(width 0)
					(fill yes)
				)
			)
		)
	)
	(footprint ""
		(layer "B.Cu")
		(at 73.55586 -117.167406 180)
		(property "Reference" "C651"
			(at 0 0 0)
			(layer "B.SilkS")
			(hide yes)
			(effects
				(font
					(size 1.27 1.27)
				)
				(justify mirror)
			)
		)
		(property "Value" "SC10U16V5KX-7-GP-U"
			(at 0.0762 -6.1214 180)
			(unlocked yes)
			(layer "B.Fab")
			(hide yes)
			(effects
				(font
					(size 1.016 1.016)
					(thickness 0.1524)
				)
				(justify mirror)
			)
		)
		(property "Device Type" "C805H58"
			(at 0.0762 -8.1534 180)
			(unlocked yes)
			(layer "B.Fab")
			(hide yes)
			(effects
				(font
					(size 1.016 1.016)
					(thickness 0.1524)
				)
				(justify mirror)
			)
		)
		(duplicate_pad_numbers_are_jumpers no)
		(fp_line
			(start -0.635 0)
			(end 0.635 0)
			(stroke
				(width 0.508)
				(type default)
			)
			(layer "B.SilkS")
		)
		(fp_rect
			(start 0.9652 1.778)
			(end -0.9652 -1.778)
			(stroke
				(width 0)
				(type default)
			)
			(fill no)
			(layer "B.CrtYd")
		)
		(fp_poly
			(pts
				(xy 0.9652 -1.778) (xy -0.9652 -1.778) (xy -0.9652 1.778) (xy 0.9652 1.778)
			)
			(stroke
				(width 0)
				(type default)
			)
			(fill no)
			(layer "B.Fab")
		)
		(pad "1" smd rect
			(at 0 -0.9652)
			(size 1.397 1.143)
			(layers "B.Cu" "B.Mask" "B.Paste")
			(net "P5V_B_2")
		)
		(pad "2" smd rect
			(at 0 0.9652)
			(size 1.397 1.143)
			(layers "B.Cu" "B.Mask" "B.Paste")
			(net "GND")
		)
	)
	(footprint ""
		(layer "B.Cu")
		(at 250.571 -284.607)
		(property "Reference" "R1179"
			(at 0 0 0)
			(layer "B.SilkS")
			(hide yes)
			(effects
				(font
					(size 1.27 1.27)
				)
				(justify mirror)
			)
		)
		(property "Value" "0R2J-2-GP"
			(at -0.064008 -3.993896 0)
			(unlocked yes)
			(layer "B.Fab")
			(hide yes)
			(effects
				(font
					(size 1.016 1.016)
					(thickness 0.1524)
				)
				(justify mirror)
			)
		)
		(property "Device Type" "R402H16"
			(at -0.064008 -5.517896 0)
			(unlocked yes)
			(layer "B.Fab")
			(hide yes)
			(effects
				(font
					(size 1.016 1.016)
					(thickness 0.1524)
				)
				(justify mirror)
			)
		)
		(duplicate_pad_numbers_are_jumpers no)
		(fp_line
			(start -0.508 -0.9398)
			(end 0.508 -0.9398)
			(stroke
				(width 0.1524)
				(type default)
			)
			(layer "B.SilkS")
		)
		(fp_line
			(start 0.508 -0.9398)
			(end 0.508 0.9398)
			(stroke
				(width 0.1524)
				(type default)
			)
			(layer "B.SilkS")
		)
		(fp_rect
			(start 0.508 0.9398)
			(end -0.508 -0.9398)
			(stroke
				(width 0)
				(type default)
			)
			(fill no)
			(layer "B.CrtYd")
		)
		(fp_rect
			(start 0.508 0.9398)
			(end -0.508 -0.9398)
			(stroke
				(width 0)
				(type default)
			)
			(fill no)
			(layer "B.Fab")
		)
		(pad "1" smd custom
			(at 0 -0.4445 180)
			(size 0.1397 0.1397)
			(layers "B.Cu" "B.Mask" "B.Paste")
			(net "P3V3_STBY_VBST_RR")
			(options
				(clearance outline)
				(anchor circle)
			)
			(primitives
				(gr_poly
					(pts
						(arc
							(start -0.1778 0.2794)
							(mid -0.249642 0.249642)
							(end -0.2794 0.1778)
						)
						(arc
							(start -0.2794 -0.1778)
							(mid -0.249642 -0.249642)
							(end -0.1778 -0.2794)
						)
						(arc
							(start 0.1778 -0.2794)
							(mid 0.249642 -0.249642)
							(end 0.2794 -0.1778)
						)
						(arc
							(start 0.2794 0.1778)
							(mid 0.249642 0.249642)
							(end 0.1778 0.2794)
						)
					)
					(width 0)
					(fill yes)
				)
			)
		)
		(pad "2" smd custom
			(at 0 0.4445 180)
			(size 0.1397 0.1397)
			(layers "B.Cu" "B.Mask" "B.Paste")
			(net "P3V3_STBY_VBST")
			(options
				(clearance outline)
				(anchor circle)
			)
			(primitives
				(gr_poly
					(pts
						(arc
							(start -0.1778 0.2794)
							(mid -0.249642 0.249642)
							(end -0.2794 0.1778)
						)
						(arc
							(start -0.2794 -0.1778)
							(mid -0.249642 -0.249642)
							(end -0.1778 -0.2794)
						)
						(arc
							(start 0.1778 -0.2794)
							(mid 0.249642 -0.249642)
							(end 0.2794 -0.1778)
						)
						(arc
							(start 0.2794 0.1778)
							(mid 0.249642 0.249642)
							(end 0.1778 0.2794)
						)
					)
					(width 0)
					(fill yes)
				)
			)
		)
	)
	(footprint ""
		(layer "B.Cu")
		(at 15.941802 -225.43135 90)
		(property "Reference" "C628"
			(at 0 0 90)
			(layer "B.SilkS")
			(hide yes)
			(effects
				(font
					(size 1.27 1.27)
				)
				(justify mirror)
			)
		)
		(property "Value" "SC1U16V3KX-5GP"
			(at 0 -2.8194 90)
			(unlocked yes)
			(layer "B.Fab")
			(hide yes)
			(effects
				(font
					(size 1.016 1.016)
					(thickness 0.1524)
				)
				(justify mirror)
			)
		)
		(property "Device Type" "C603H36"
			(at 0 -4.3434 90)
			(unlocked yes)
			(layer "B.Fab")
			(hide yes)
			(effects
				(font
					(size 1.016 1.016)
					(thickness 0.1524)
				)
				(justify mirror)
			)
		)
		(duplicate_pad_numbers_are_jumpers no)
		(fp_line
			(start -0.508 0)
			(end 0.508 0)
			(stroke
				(width 0.2032)
				(type default)
			)
			(layer "B.SilkS")
		)
		(fp_rect
			(start 0.5842 1.3335)
			(end -0.5842 -1.3335)
			(stroke
				(width 0)
				(type default)
			)
			(fill no)
			(layer "B.CrtYd")
		)
		(fp_rect
			(start 0.5842 1.3335)
			(end -0.5842 -1.3335)
			(stroke
				(width 0)
				(type default)
			)
			(fill no)
			(layer "B.Fab")
		)
		(pad "1" smd custom
			(at 0 -0.762 270)
			(size 0.2159 0.2159)
			(layers "B.Cu" "B.Mask" "B.Paste")
			(net "GND")
			(options
				(clearance outline)
				(anchor circle)
			)
			(primitives
				(gr_poly
					(pts
						(arc
							(start -0.3302 0.4318)
							(mid -0.402042 0.402042)
							(end -0.4318 0.3302)
						)
						(arc
							(start -0.4318 -0.3302)
							(mid -0.402042 -0.402042)
							(end -0.3302 -0.4318)
						)
						(arc
							(start 0.3302 -0.4318)
							(mid 0.402042 -0.402042)
							(end 0.4318 -0.3302)
						)
						(arc
							(start 0.4318 0.3302)
							(mid 0.402042 0.402042)
							(end 0.3302 0.4318)
						)
					)
					(width 0)
					(fill yes)
				)
			)
		)
		(pad "2" smd custom
			(at 0 0.762 270)
			(size 0.2159 0.2159)
			(layers "B.Cu" "B.Mask" "B.Paste")
			(net "P5V_B_1_VREG")
			(options
				(clearance outline)
				(anchor circle)
			)
			(primitives
				(gr_poly
					(pts
						(arc
							(start -0.3302 0.4318)
							(mid -0.402042 0.402042)
							(end -0.4318 0.3302)
						)
						(arc
							(start -0.4318 -0.3302)
							(mid -0.402042 -0.402042)
							(end -0.3302 -0.4318)
						)
						(arc
							(start 0.3302 -0.4318)
							(mid 0.402042 -0.402042)
							(end 0.4318 -0.3302)
						)
						(arc
							(start 0.4318 0.3302)
							(mid 0.402042 0.402042)
							(end 0.3302 0.4318)
						)
					)
					(width 0)
					(fill yes)
				)
			)
		)
	)
	(footprint ""
		(layer "B.Cu")
		(at 39.26586 -111.833406 180)
		(property "Reference" "C635"
			(at 0 0 0)
			(layer "B.SilkS")
			(hide yes)
			(effects
				(font
					(size 1.27 1.27)
				)
				(justify mirror)
			)
		)
		(property "Value" "SC10U16V5KX-7-GP-U"
			(at 0.0762 -6.1214 180)
			(unlocked yes)
			(layer "B.Fab")
			(hide yes)
			(effects
				(font
					(size 1.016 1.016)
					(thickness 0.1524)
				)
				(justify mirror)
			)
		)
		(property "Device Type" "C805H58"
			(at 0.0762 -8.1534 180)
			(unlocked yes)
			(layer "B.Fab")
			(hide yes)
			(effects
				(font
					(size 1.016 1.016)
					(thickness 0.1524)
				)
				(justify mirror)
			)
		)
		(duplicate_pad_numbers_are_jumpers no)
		(fp_line
			(start -0.635 0)
			(end 0.635 0)
			(stroke
				(width 0.508)
				(type default)
			)
			(layer "B.SilkS")
		)
		(fp_rect
			(start 0.9652 1.778)
			(end -0.9652 -1.778)
			(stroke
				(width 0)
				(type default)
			)
			(fill no)
			(layer "B.CrtYd")
		)
		(fp_poly
			(pts
				(xy 0.9652 -1.778) (xy -0.9652 -1.778) (xy -0.9652 1.778) (xy 0.9652 1.778)
			)
			(stroke
				(width 0)
				(type default)
			)
			(fill no)
			(layer "B.Fab")
		)
		(pad "1" smd rect
			(at 0 -0.9652)
			(size 1.397 1.143)
			(layers "B.Cu" "B.Mask" "B.Paste")
			(net "P12V_B_2_VIN_U32")
		)
		(pad "2" smd rect
			(at 0 0.9652)
			(size 1.397 1.143)
			(layers "B.Cu" "B.Mask" "B.Paste")
			(net "GND")
		)
	)
	(footprint ""
		(layer "B.Cu")
		(at 451.043802 -227.08235 -90)
		(property "Reference" "C660"
			(at 0 0 90)
			(layer "B.SilkS")
			(hide yes)
			(effects
				(font
					(size 1.27 1.27)
				)
				(justify mirror)
			)
		)
		(property "Value" "SC4D7U25V5KX-1-GP"
			(at 0.0762 -6.1214 270)
			(unlocked yes)
			(layer "B.Fab")
			(hide yes)
			(effects
				(font
					(size 1.016 1.016)
					(thickness 0.1524)
				)
				(justify mirror)
			)
		)
		(property "Device Type" "C805H58"
			(at 0.0762 -8.1534 270)
			(unlocked yes)
			(layer "B.Fab")
			(hide yes)
			(effects
				(font
					(size 1.016 1.016)
					(thickness 0.1524)
				)
				(justify mirror)
			)
		)
		(duplicate_pad_numbers_are_jumpers no)
		(fp_line
			(start -0.635 0)
			(end 0.635 0)
			(stroke
				(width 0.508)
				(type default)
			)
			(layer "B.SilkS")
		)
		(fp_rect
			(start 0.9652 1.778)
			(end -0.9652 -1.778)
			(stroke
				(width 0)
				(type default)
			)
			(fill no)
			(layer "B.CrtYd")
		)
		(fp_poly
			(pts
				(xy 0.9652 -1.778) (xy -0.9652 -1.778) (xy -0.9652 1.778) (xy 0.9652 1.778)
			)
			(stroke
				(width 0)
				(type default)
			)
			(fill no)
			(layer "B.Fab")
		)
		(pad "1" smd rect
			(at 0 -0.9652 90)
			(size 1.397 1.143)
			(layers "B.Cu" "B.Mask" "B.Paste")
			(net "P12V_B_3_VDD_U33")
		)
		(pad "2" smd rect
			(at 0 0.9652 90)
			(size 1.397 1.143)
			(layers "B.Cu" "B.Mask" "B.Paste")
			(net "GND")
		)
	)
	(footprint ""
		(layer "B.Cu")
		(at 445.963802 -223.01835 180)
		(property "Reference" "C655"
			(at 0 0 0)
			(layer "B.SilkS")
			(hide yes)
			(effects
				(font
					(size 1.27 1.27)
				)
				(justify mirror)
			)
		)
		(property "Value" "SC10U16V5KX-7-GP-U"
			(at 0.0762 -6.1214 180)
			(unlocked yes)
			(layer "B.Fab")
			(hide yes)
			(effects
				(font
					(size 1.016 1.016)
					(thickness 0.1524)
				)
				(justify mirror)
			)
		)
		(property "Device Type" "C805H58"
			(at 0.0762 -8.1534 180)
			(unlocked yes)
			(layer "B.Fab")
			(hide yes)
			(effects
				(font
					(size 1.016 1.016)
					(thickness 0.1524)
				)
				(justify mirror)
			)
		)
		(duplicate_pad_numbers_are_jumpers no)
		(fp_line
			(start -0.635 0)
			(end 0.635 0)
			(stroke
				(width 0.508)
				(type default)
			)
			(layer "B.SilkS")
		)
		(fp_rect
			(start 0.9652 1.778)
			(end -0.9652 -1.778)
			(stroke
				(width 0)
				(type default)
			)
			(fill no)
			(layer "B.CrtYd")
		)
		(fp_poly
			(pts
				(xy 0.9652 -1.778) (xy -0.9652 -1.778) (xy -0.9652 1.778) (xy 0.9652 1.778)
			)
			(stroke
				(width 0)
				(type default)
			)
			(fill no)
			(layer "B.Fab")
		)
		(pad "1" smd rect
			(at 0 -0.9652)
			(size 1.397 1.143)
			(layers "B.Cu" "B.Mask" "B.Paste")
			(net "P12V_B_3_VIN_U33")
		)
		(pad "2" smd rect
			(at 0 0.9652)
			(size 1.397 1.143)
			(layers "B.Cu" "B.Mask" "B.Paste")
			(net "GND")
		)
	)
	(footprint ""
		(layer "B.Cu")
		(at 447.995802 -223.01835 180)
		(property "Reference" "C654"
			(at 0 0 0)
			(layer "B.SilkS")
			(hide yes)
			(effects
				(font
					(size 1.27 1.27)
				)
				(justify mirror)
			)
		)
		(property "Value" "SC10U16V5KX-7-GP-U"
			(at 0.0762 -6.1214 180)
			(unlocked yes)
			(layer "B.Fab")
			(hide yes)
			(effects
				(font
					(size 1.016 1.016)
					(thickness 0.1524)
				)
				(justify mirror)
			)
		)
		(property "Device Type" "C805H58"
			(at 0.0762 -8.1534 180)
			(unlocked yes)
			(layer "B.Fab")
			(hide yes)
			(effects
				(font
					(size 1.016 1.016)
					(thickness 0.1524)
				)
				(justify mirror)
			)
		)
		(duplicate_pad_numbers_are_jumpers no)
		(fp_line
			(start -0.635 0)
			(end 0.635 0)
			(stroke
				(width 0.508)
				(type default)
			)
			(layer "B.SilkS")
		)
		(fp_rect
			(start 0.9652 1.778)
			(end -0.9652 -1.778)
			(stroke
				(width 0)
				(type default)
			)
			(fill no)
			(layer "B.CrtYd")
		)
		(fp_poly
			(pts
				(xy 0.9652 -1.778) (xy -0.9652 -1.778) (xy -0.9652 1.778) (xy 0.9652 1.778)
			)
			(stroke
				(width 0)
				(type default)
			)
			(fill no)
			(layer "B.Fab")
		)
		(pad "1" smd rect
			(at 0 -0.9652)
			(size 1.397 1.143)
			(layers "B.Cu" "B.Mask" "B.Paste")
			(net "P12V_B_3_VIN_U33")
		)
		(pad "2" smd rect
			(at 0 0.9652)
			(size 1.397 1.143)
			(layers "B.Cu" "B.Mask" "B.Paste")
			(net "GND")
		)
	)
	(footprint ""
		(layer "B.Cu")
		(at 463.292698 -118.013226 180)
		(property "Reference" "C688"
			(at 0 0 0)
			(layer "B.SilkS")
			(hide yes)
			(effects
				(font
					(size 1.27 1.27)
				)
				(justify mirror)
			)
		)
		(property "Value" "SC10U16V5KX-7-GP-U"
			(at 0.0762 -6.1214 180)
			(unlocked yes)
			(layer "B.Fab")
			(hide yes)
			(effects
				(font
					(size 1.016 1.016)
					(thickness 0.1524)
				)
				(justify mirror)
			)
		)
		(property "Device Type" "C805H58"
			(at 0.0762 -8.1534 180)
			(unlocked yes)
			(layer "B.Fab")
			(hide yes)
			(effects
				(font
					(size 1.016 1.016)
					(thickness 0.1524)
				)
				(justify mirror)
			)
		)
		(duplicate_pad_numbers_are_jumpers no)
		(fp_line
			(start -0.635 0)
			(end 0.635 0)
			(stroke
				(width 0.508)
				(type default)
			)
			(layer "B.SilkS")
		)
		(fp_rect
			(start 0.9652 1.778)
			(end -0.9652 -1.778)
			(stroke
				(width 0)
				(type default)
			)
			(fill no)
			(layer "B.CrtYd")
		)
		(fp_poly
			(pts
				(xy 0.9652 -1.778) (xy -0.9652 -1.778) (xy -0.9652 1.778) (xy 0.9652 1.778)
			)
			(stroke
				(width 0)
				(type default)
			)
			(fill no)
			(layer "B.Fab")
		)
		(pad "1" smd rect
			(at 0 -0.9652)
			(size 1.397 1.143)
			(layers "B.Cu" "B.Mask" "B.Paste")
			(net "P5V_B_4")
		)
		(pad "2" smd rect
			(at 0 0.9652)
			(size 1.397 1.143)
			(layers "B.Cu" "B.Mask" "B.Paste")
			(net "GND")
		)
	)
	(footprint ""
		(layer "B.Cu")
		(at 447.632328 -118.784624 180)
		(property "Reference" "R1160"
			(at 0 0 0)
			(layer "B.SilkS")
			(hide yes)
			(effects
				(font
					(size 1.27 1.27)
				)
				(justify mirror)
			)
		)
		(property "Value" "2K7R2F-GP"
			(at -0.064008 -3.993896 180)
			(unlocked yes)
			(layer "B.Fab")
			(hide yes)
			(effects
				(font
					(size 1.016 1.016)
					(thickness 0.1524)
				)
				(justify mirror)
			)
		)
		(property "Device Type" "R402H16"
			(at -0.064008 -5.517896 180)
			(unlocked yes)
			(layer "B.Fab")
			(hide yes)
			(effects
				(font
					(size 1.016 1.016)
					(thickness 0.1524)
				)
				(justify mirror)
			)
		)
		(duplicate_pad_numbers_are_jumpers no)
		(fp_line
			(start 0.508 -0.9398)
			(end 0.508 0.9398)
			(stroke
				(width 0.1524)
				(type default)
			)
			(layer "B.SilkS")
		)
		(fp_line
			(start -0.508 -0.9398)
			(end 0.508 -0.9398)
			(stroke
				(width 0.1524)
				(type default)
			)
			(layer "B.SilkS")
		)
		(fp_rect
			(start 0.508 0.9398)
			(end -0.508 -0.9398)
			(stroke
				(width 0)
				(type default)
			)
			(fill no)
			(layer "B.CrtYd")
		)
		(fp_rect
			(start 0.508 0.9398)
			(end -0.508 -0.9398)
			(stroke
				(width 0)
				(type default)
			)
			(fill no)
			(layer "B.Fab")
		)
		(pad "1" smd custom
			(at 0 -0.4445)
			(size 0.1397 0.1397)
			(layers "B.Cu" "B.Mask" "B.Paste")
			(net "P5V_B_4_LL")
			(options
				(clearance outline)
				(anchor circle)
			)
			(primitives
				(gr_poly
					(pts
						(arc
							(start -0.1778 0.2794)
							(mid -0.249642 0.249642)
							(end -0.2794 0.1778)
						)
						(arc
							(start -0.2794 -0.1778)
							(mid -0.249642 -0.249642)
							(end -0.1778 -0.2794)
						)
						(arc
							(start 0.1778 -0.2794)
							(mid 0.249642 -0.249642)
							(end 0.2794 -0.1778)
						)
						(arc
							(start 0.2794 0.1778)
							(mid 0.249642 0.249642)
							(end 0.1778 0.2794)
						)
					)
					(width 0)
					(fill yes)
				)
			)
		)
		(pad "2" smd custom
			(at 0 0.4445)
			(size 0.1397 0.1397)
			(layers "B.Cu" "B.Mask" "B.Paste")
			(net "P5V_B_4_LL_R")
			(options
				(clearance outline)
				(anchor circle)
			)
			(primitives
				(gr_poly
					(pts
						(arc
							(start -0.1778 0.2794)
							(mid -0.249642 0.249642)
							(end -0.2794 0.1778)
						)
						(arc
							(start -0.2794 -0.1778)
							(mid -0.249642 -0.249642)
							(end -0.1778 -0.2794)
						)
						(arc
							(start 0.1778 -0.2794)
							(mid 0.249642 -0.249642)
							(end 0.2794 -0.1778)
						)
						(arc
							(start 0.2794 0.1778)
							(mid 0.249642 0.249642)
							(end 0.1778 0.2794)
						)
					)
					(width 0)
					(fill yes)
				)
			)
		)
	)
	(footprint ""
		(layer "B.Cu")
		(at 40.66286 -112.087406 180)
		(property "Reference" "C638"
			(at 0 0 0)
			(layer "B.SilkS")
			(hide yes)
			(effects
				(font
					(size 1.27 1.27)
				)
				(justify mirror)
			)
		)
		(property "Value" "SCD1U16V2KX-3GP"
			(at -1.1811 -2.7051 180)
			(unlocked yes)
			(layer "B.Fab")
			(hide yes)
			(effects
				(font
					(size 1.016 1.016)
					(thickness 0.1524)
				)
				(justify mirror)
			)
		)
		(property "Device Type" "C402H22"
			(at -1.1811 -4.2291 180)
			(unlocked yes)
			(layer "B.Fab")
			(hide yes)
			(effects
				(font
					(size 1.016 1.016)
					(thickness 0.1524)
				)
				(justify mirror)
			)
		)
		(duplicate_pad_numbers_are_jumpers no)
		(fp_rect
			(start 0.4318 0.9525)
			(end -0.4318 -0.9525)
			(stroke
				(width 0)
				(type default)
			)
			(fill no)
			(layer "B.CrtYd")
		)
		(fp_rect
			(start 0.4318 0.9525)
			(end -0.4318 -0.9525)
			(stroke
				(width 0)
				(type default)
			)
			(fill no)
			(layer "B.Fab")
		)
		(pad "1" smd custom
			(at 0 -0.4445)
			(size 0.1524 0.1524)
			(layers "B.Cu" "B.Mask" "B.Paste")
			(net "P12V_B_2_VIN_U32")
			(options
				(clearance outline)
				(anchor circle)
			)
			(primitives
				(gr_poly
					(pts
						(arc
							(start 0.3048 0.2032)
							(mid 0.275042 0.275042)
							(end 0.2032 0.3048)
						)
						(arc
							(start -0.2032 0.3048)
							(mid -0.275042 0.275042)
							(end -0.3048 0.2032)
						)
						(arc
							(start -0.3048 -0.2032)
							(mid -0.275042 -0.275042)
							(end -0.2032 -0.3048)
						)
						(arc
							(start 0.2032 -0.3048)
							(mid 0.275042 -0.275042)
							(end 0.3048 -0.2032)
						)
					)
					(width 0)
					(fill yes)
				)
			)
		)
		(pad "2" smd custom
			(at 0 0.4445)
			(size 0.1524 0.1524)
			(layers "B.Cu" "B.Mask" "B.Paste")
			(net "GND")
			(options
				(clearance outline)
				(anchor circle)
			)
			(primitives
				(gr_poly
					(pts
						(arc
							(start 0.3048 0.2032)
							(mid 0.275042 0.275042)
							(end 0.2032 0.3048)
						)
						(arc
							(start -0.2032 0.3048)
							(mid -0.275042 0.275042)
							(end -0.3048 0.2032)
						)
						(arc
							(start -0.3048 -0.2032)
							(mid -0.275042 -0.275042)
							(end -0.2032 -0.3048)
						)
						(arc
							(start 0.2032 -0.3048)
							(mid 0.275042 -0.275042)
							(end 0.3048 -0.2032)
						)
					)
					(width 0)
					(fill yes)
				)
			)
		)
	)
	(footprint ""
		(layer "B.Cu")
		(at 476.6564 -230.09479 180)
		(property "Reference" "TC9"
			(at 0 0 0)
			(layer "B.SilkS")
			(hide yes)
			(effects
				(font
					(size 1.27 1.27)
				)
				(justify mirror)
			)
		)
		(property "Value" "ST220U10VDM-LGP"
			(at 0 -9.6012 180)
			(unlocked yes)
			(layer "B.Fab")
			(hide yes)
			(effects
				(font
					(size 1.016 1.016)
					(thickness 0.1524)
				)
				(justify mirror)
			)
		)
		(property "Device Type" "CT7343H119"
			(at 0 -11.1252 180)
			(unlocked yes)
			(layer "B.Fab")
			(hide yes)
			(effects
				(font
					(size 1.016 1.016)
					(thickness 0.1524)
				)
				(justify mirror)
			)
		)
		(duplicate_pad_numbers_are_jumpers no)
		(fp_line
			(start 2.286 4.8768)
			(end 2.286 2.032)
			(stroke
				(width 0.1524)
				(type default)
			)
			(layer "B.SilkS")
		)
		(fp_line
			(start 2.286 -4.8768)
			(end 2.286 -2.032)
			(stroke
				(width 0.1524)
				(type default)
			)
			(layer "B.SilkS")
		)
		(fp_line
			(start -2.1082 -4.699)
			(end 2.1082 -4.699)
			(stroke
				(width 0.508)
				(type default)
			)
			(layer "B.SilkS")
		)
		(fp_line
			(start -2.286 4.8768)
			(end 2.286 4.8768)
			(stroke
				(width 0.1524)
				(type default)
			)
			(layer "B.SilkS")
		)
		(fp_line
			(start -2.286 2.032)
			(end -2.286 4.8768)
			(stroke
				(width 0.1524)
				(type default)
			)
			(layer "B.SilkS")
		)
		(fp_line
			(start -2.286 -2.032)
			(end -2.286 -4.8768)
			(stroke
				(width 0.1524)
				(type default)
			)
			(layer "B.SilkS")
		)
		(fp_line
			(start -2.286 -4.8768)
			(end 2.286 -4.8768)
			(stroke
				(width 0.1524)
				(type default)
			)
			(layer "B.SilkS")
		)
		(fp_rect
			(start 2.1463 3.6449)
			(end -2.1463 -3.6449)
			(stroke
				(width 0)
				(type default)
			)
			(fill no)
			(layer "B.CrtYd")
		)
		(fp_poly
			(pts
				(xy 2.54 4.953) (xy 2.54 4.2926) (xy 3.81 4.2926) (xy 3.81 -4.2926) (xy 2.54 -4.2926) (xy 2.54 -4.953)
				(xy -2.54 -4.953) (xy -2.54 -4.2926) (xy -3.81 -4.2926) (xy -3.81 -1.6256) (xy -2.1463 -1.6256)
				(xy -2.1463 -3.6449) (xy 2.1463 -3.6449) (xy 2.1463 3.6449) (xy -2.1463 3.6449) (xy -2.1463 -1.6129)
				(xy -3.81 -1.6129) (xy -3.81 4.2926) (xy -2.54 4.2926) (xy -2.54 4.953)
			)
			(stroke
				(width 0)
				(type default)
			)
			(fill no)
			(layer "B.CrtYd")
		)
		(fp_rect
			(start 3.81 4.2926)
			(end 2.54 -4.2926)
			(stroke
				(width 0)
				(type default)
			)
			(fill no)
			(layer "B.Fab")
		)
		(fp_rect
			(start 2.54 4.953)
			(end -2.54 -4.953)
			(stroke
				(width 0)
				(type default)
			)
			(fill no)
			(layer "B.Fab")
		)
		(fp_rect
			(start -2.54 4.2926)
			(end -3.81 -4.2926)
			(stroke
				(width 0)
				(type default)
			)
			(fill no)
			(layer "B.Fab")
		)
		(pad "1" smd rect
			(at 0 -3.1496)
			(size 2.413 2.286)
			(layers "B.Cu" "B.Mask" "B.Paste")
			(net "P5V_B_3")
		)
		(pad "2" smd rect
			(at 0 3.1496)
			(size 2.413 2.286)
			(layers "B.Cu" "B.Mask" "B.Paste")
			(net "GND")
		)
		(zone
			(layer "B.Cu")
			(hatch none 0.5)
			(connect_pads
				(clearance 0)
			)
			(min_thickness 0.25)
			(keepout
				(tracks allowed)
				(vias not_allowed)
				(pads allowed)
				(copperpour not_allowed)
				(footprints allowed)
			)
			(placement
				(enabled no)
				(sheetname "")
			)
			(fill
				(thermal_gap 0.5)
				(thermal_bridge_width 0.5)
				(island_removal_mode 0)
			)
			(polygon
				(pts
					(xy 475.1451 -234.69219) (xy 478.1677 -234.69219) (xy 478.1677 -231.79659) (xy 478.1677 -231.46639)
					(xy 475.1451 -231.46639) (xy 475.1451 -231.79659)
				)
			)
		)
		(zone
			(layer "B.Cu")
			(hatch none 0.5)
			(connect_pads
				(clearance 0)
			)
			(min_thickness 0.25)
			(keepout
				(tracks allowed)
				(vias not_allowed)
				(pads allowed)
				(copperpour not_allowed)
				(footprints allowed)
			)
			(placement
				(enabled no)
				(sheetname "")
			)
			(fill
				(thermal_gap 0.5)
				(thermal_bridge_width 0.5)
				(island_removal_mode 0)
			)
			(polygon
				(pts
					(xy 478.1677 -228.40569) (xy 478.1677 -225.49739) (xy 475.1451 -225.49739) (xy 475.1451 -228.39299)
					(xy 475.1451 -228.72319) (xy 478.1677 -228.72319)
				)
			)
		)
	)
	(footprint ""
		(layer "B.Cu")
		(at 465.225892 -118.015258 180)
		(property "Reference" "C687"
			(at 0 0 0)
			(layer "B.SilkS")
			(hide yes)
			(effects
				(font
					(size 1.27 1.27)
				)
				(justify mirror)
			)
		)
		(property "Value" "SC10U16V5KX-7-GP-U"
			(at 0.0762 -6.1214 180)
			(unlocked yes)
			(layer "B.Fab")
			(hide yes)
			(effects
				(font
					(size 1.016 1.016)
					(thickness 0.1524)
				)
				(justify mirror)
			)
		)
		(property "Device Type" "C805H58"
			(at 0.0762 -8.1534 180)
			(unlocked yes)
			(layer "B.Fab")
			(hide yes)
			(effects
				(font
					(size 1.016 1.016)
					(thickness 0.1524)
				)
				(justify mirror)
			)
		)
		(duplicate_pad_numbers_are_jumpers no)
		(fp_line
			(start -0.635 0)
			(end 0.635 0)
			(stroke
				(width 0.508)
				(type default)
			)
			(layer "B.SilkS")
		)
		(fp_rect
			(start 0.9652 1.778)
			(end -0.9652 -1.778)
			(stroke
				(width 0)
				(type default)
			)
			(fill no)
			(layer "B.CrtYd")
		)
		(fp_poly
			(pts
				(xy 0.9652 -1.778) (xy -0.9652 -1.778) (xy -0.9652 1.778) (xy 0.9652 1.778)
			)
			(stroke
				(width 0)
				(type default)
			)
			(fill no)
			(layer "B.Fab")
		)
		(pad "1" smd rect
			(at 0 -0.9652)
			(size 1.397 1.143)
			(layers "B.Cu" "B.Mask" "B.Paste")
			(net "P5V_B_4")
		)
		(pad "2" smd rect
			(at 0 0.9652)
			(size 1.397 1.143)
			(layers "B.Cu" "B.Mask" "B.Paste")
			(net "GND")
		)
	)
	(footprint ""
		(layer "B.Cu")
		(at 127.824992 -181.799992)
		(property "Reference" "SCW1"
			(at 0 0 0)
			(layer "B.SilkS")
			(hide yes)
			(effects
				(font
					(size 1.27 1.27)
				)
				(justify mirror)
			)
		)
		(property "Value" ""
			(at 0 0 0)
			(layer "B.Fab")
			(effects
				(font
					(size 1.27 1.27)
				)
				(justify mirror)
			)
		)
		(duplicate_pad_numbers_are_jumpers no)
		(fp_poly
			(pts
				(arc
					(start 5.4356 0)
					(mid -5.4356 0)
					(end 5.4356 0)
				)
			)
			(stroke
				(width 0)
				(type default)
			)
			(fill no)
			(layer "B.CrtYd")
		)
		(fp_poly
			(pts
				(arc
					(start 5.4356 0)
					(mid -5.4356 0)
					(end 5.4356 0)
				)
			)
			(stroke
				(width 0)
				(type default)
			)
			(fill no)
			(layer "F.CrtYd")
		)
		(fp_poly
			(pts
				(arc
					(start 5.4356 0)
					(mid -5.4356 0)
					(end 5.4356 0)
				)
			)
			(stroke
				(width 0)
				(type default)
			)
			(fill no)
			(layer "B.Fab")
		)
		(fp_poly
			(pts
				(arc
					(start 5.4356 0)
					(mid -5.4356 0)
					(end 5.4356 0)
				)
			)
			(stroke
				(width 0)
				(type default)
			)
			(fill no)
			(layer "F.Fab")
		)
		(pad "" np_thru_hole circle
			(at 0 0 180)
			(size 0.254 0.254)
			(drill 10.2616)
			(layers "*.Cu" "*.Mask")
			(clearance 5.3594)
			(thermal_gap 5.3594)
		)
		(zone
			(layers "F.Cu" "B.Cu" "In1.Cu" "In2.Cu" "In3.Cu" "In4.Cu" "In5.Cu" "In6.Cu")
			(hatch none 0.5)
			(connect_pads
				(clearance 0)
			)
			(min_thickness 0.25)
			(keepout
				(tracks not_allowed)
				(vias allowed)
				(pads allowed)
				(copperpour not_allowed)
				(footprints allowed)
			)
			(placement
				(enabled no)
				(sheetname "")
			)
			(fill
				(thermal_gap 0.5)
				(thermal_bridge_width 0.5)
				(island_removal_mode 0)
			)
			(polygon
				(pts
					(arc
						(start 133.260592 -181.799992)
						(mid 122.389392 -181.799992)
						(end 133.260592 -181.799992)
					)
				)
			)
		)
	)
	(footprint ""
		(layer "B.Cu")
		(at 213.995 -355.473 180)
		(property "Reference" "C511"
			(at 0 0 0)
			(layer "B.SilkS")
			(hide yes)
			(effects
				(font
					(size 1.27 1.27)
				)
				(justify mirror)
			)
		)
		(property "Value" "SC22U25V6KX-2-GP-U"
			(at 2.860802 -5.279644 180)
			(unlocked yes)
			(layer "B.Fab")
			(hide yes)
			(effects
				(font
					(size 1.016 1.016)
					(thickness 0.1524)
				)
				(justify mirror)
			)
		)
		(property "Device Type" "C1206-TO0D3H75"
			(at 2.860802 -6.803644 180)
			(unlocked yes)
			(layer "B.Fab")
			(hide yes)
			(effects
				(font
					(size 1.016 1.016)
					(thickness 0.1524)
				)
				(justify mirror)
			)
		)
		(duplicate_pad_numbers_are_jumpers no)
		(fp_line
			(start 1.3081 2.3749)
			(end 1.3081 -2.3749)
			(stroke
				(width 0.1524)
				(type default)
			)
			(layer "B.SilkS")
		)
		(fp_line
			(start 1.3081 -2.3749)
			(end -1.3081 -2.3749)
			(stroke
				(width 0.1524)
				(type default)
			)
			(layer "B.SilkS")
		)
		(fp_line
			(start -1.3081 2.3749)
			(end 1.3081 2.3749)
			(stroke
				(width 0.1524)
				(type default)
			)
			(layer "B.SilkS")
		)
		(fp_line
			(start -1.3081 -2.3749)
			(end -1.3081 2.3749)
			(stroke
				(width 0.1524)
				(type default)
			)
			(layer "B.SilkS")
		)
		(fp_rect
			(start 0.8001 1.6002)
			(end -0.8001 -1.6002)
			(stroke
				(width 0)
				(type default)
			)
			(fill no)
			(layer "B.CrtYd")
		)
		(fp_poly
			(pts
				(xy 1.5621 2.4511) (xy 1.5621 1.6002) (xy -0.8001 1.6002) (xy -0.8001 -1.6002) (xy 0.8001 -1.6002)
				(xy 0.8001 1.5875) (xy 1.5621 1.5875) (xy 1.5621 -2.4511) (xy -1.5621 -2.4511) (xy -1.5621 2.4511)
			)
			(stroke
				(width 0)
				(type default)
			)
			(fill no)
			(layer "B.CrtYd")
		)
		(fp_rect
			(start 1.5621 2.4511)
			(end -1.5621 -2.4511)
			(stroke
				(width 0)
				(type default)
			)
			(fill no)
			(layer "B.Fab")
		)
		(pad "1" smd rect
			(at 0 -1.392936)
			(size 2.1082 1.4478)
			(layers "B.Cu" "B.Mask" "B.Paste")
			(net "P12V_IN")
		)
		(pad "2" smd rect
			(at 0 1.392936)
			(size 2.1082 1.4478)
			(layers "B.Cu" "B.Mask" "B.Paste")
			(net "GND")
		)
	)
	(footprint ""
		(layer "B.Cu")
		(at 50.104802 -228.22535 -90)
		(property "Reference" "G1"
			(at 0 0 90)
			(layer "B.SilkS")
			(hide yes)
			(effects
				(font
					(size 1.27 1.27)
				)
				(justify mirror)
			)
		)
		(property "Value" "GAP-CLOSE-PWR-4-GP"
			(at 2.4638 -0.5461 270)
			(unlocked yes)
			(layer "B.Fab")
			(hide yes)
			(effects
				(font
					(size 1.016 1.016)
					(thickness 0.1524)
				)
				(justify mirror)
			)
		)
		(property "Device Type" "GAP-CLOSE-PWR-4"
			(at 2.4638 -2.0701 270)
			(unlocked yes)
			(layer "B.Fab")
			(hide yes)
			(effects
				(font
					(size 1.016 1.016)
					(thickness 0.1524)
				)
				(justify mirror)
			)
		)
		(duplicate_pad_numbers_are_jumpers no)
		(fp_rect
			(start 0.2794 0.254)
			(end -0.2794 -0.254)
			(stroke
				(width 0)
				(type default)
			)
			(fill no)
			(layer "B.CrtYd")
		)
		(fp_rect
			(start 0.2794 0.254)
			(end -0.2794 -0.254)
			(stroke
				(width 0)
				(type default)
			)
			(fill no)
			(layer "B.Fab")
		)
		(pad "1" smd rect
			(at 0.0635 0 90)
			(size 0.1778 0.254)
			(layers "B.Cu" "B.Mask" "B.Paste")
			(net "P5V_B_1")
		)
		(pad "2" smd rect
			(at -0.0635 0 90)
			(size 0.1778 0.254)
			(layers "B.Cu" "B.Mask" "B.Paste")
			(net "P5V_B_1_CC")
		)
	)
	(footprint ""
		(layer "B.Cu")
		(at 457.833984 -119.727218 180)
		(property "Reference" "TC8"
			(at 0 0 0)
			(layer "B.SilkS")
			(hide yes)
			(effects
				(font
					(size 1.27 1.27)
				)
				(justify mirror)
			)
		)
		(property "Value" "ST220U10VDM-LGP"
			(at 0 -9.6012 180)
			(unlocked yes)
			(layer "B.Fab")
			(hide yes)
			(effects
				(font
					(size 1.016 1.016)
					(thickness 0.1524)
				)
				(justify mirror)
			)
		)
		(property "Device Type" "CT7343H119"
			(at 0 -11.1252 180)
			(unlocked yes)
			(layer "B.Fab")
			(hide yes)
			(effects
				(font
					(size 1.016 1.016)
					(thickness 0.1524)
				)
				(justify mirror)
			)
		)
		(duplicate_pad_numbers_are_jumpers no)
		(fp_line
			(start 2.286 4.8768)
			(end 2.286 2.032)
			(stroke
				(width 0.1524)
				(type default)
			)
			(layer "B.SilkS")
		)
		(fp_line
			(start 2.286 -4.8768)
			(end 2.286 -2.032)
			(stroke
				(width 0.1524)
				(type default)
			)
			(layer "B.SilkS")
		)
		(fp_line
			(start -2.1082 -4.699)
			(end 2.1082 -4.699)
			(stroke
				(width 0.508)
				(type default)
			)
			(layer "B.SilkS")
		)
		(fp_line
			(start -2.286 4.8768)
			(end 2.286 4.8768)
			(stroke
				(width 0.1524)
				(type default)
			)
			(layer "B.SilkS")
		)
		(fp_line
			(start -2.286 2.032)
			(end -2.286 4.8768)
			(stroke
				(width 0.1524)
				(type default)
			)
			(layer "B.SilkS")
		)
		(fp_line
			(start -2.286 -2.032)
			(end -2.286 -4.8768)
			(stroke
				(width 0.1524)
				(type default)
			)
			(layer "B.SilkS")
		)
		(fp_line
			(start -2.286 -4.8768)
			(end 2.286 -4.8768)
			(stroke
				(width 0.1524)
				(type default)
			)
			(layer "B.SilkS")
		)
		(fp_rect
			(start 2.1463 3.6449)
			(end -2.1463 -3.6449)
			(stroke
				(width 0)
				(type default)
			)
			(fill no)
			(layer "B.CrtYd")
		)
		(fp_poly
			(pts
				(xy 2.54 4.953) (xy 2.54 4.2926) (xy 3.81 4.2926) (xy 3.81 -4.2926) (xy 2.54 -4.2926) (xy 2.54 -4.953)
				(xy -2.54 -4.953) (xy -2.54 -4.2926) (xy -3.81 -4.2926) (xy -3.81 -1.6256) (xy -2.1463 -1.6256)
				(xy -2.1463 -3.6449) (xy 2.1463 -3.6449) (xy 2.1463 3.6449) (xy -2.1463 3.6449) (xy -2.1463 -1.6129)
				(xy -3.81 -1.6129) (xy -3.81 4.2926) (xy -2.54 4.2926) (xy -2.54 4.953)
			)
			(stroke
				(width 0)
				(type default)
			)
			(fill no)
			(layer "B.CrtYd")
		)
		(fp_rect
			(start 3.81 4.2926)
			(end 2.54 -4.2926)
			(stroke
				(width 0)
				(type default)
			)
			(fill no)
			(layer "B.Fab")
		)
		(fp_rect
			(start 2.54 4.953)
			(end -2.54 -4.953)
			(stroke
				(width 0)
				(type default)
			)
			(fill no)
			(layer "B.Fab")
		)
		(fp_rect
			(start -2.54 4.2926)
			(end -3.81 -4.2926)
			(stroke
				(width 0)
				(type default)
			)
			(fill no)
			(layer "B.Fab")
		)
		(pad "1" smd rect
			(at 0 -3.1496)
			(size 2.413 2.286)
			(layers "B.Cu" "B.Mask" "B.Paste")
			(net "P5V_B_4")
		)
		(pad "2" smd rect
			(at 0 3.1496)
			(size 2.413 2.286)
			(layers "B.Cu" "B.Mask" "B.Paste")
			(net "GND")
		)
		(zone
			(layer "B.Cu")
			(hatch none 0.5)
			(connect_pads
				(clearance 0)
			)
			(min_thickness 0.25)
			(keepout
				(tracks allowed)
				(vias not_allowed)
				(pads allowed)
				(copperpour not_allowed)
				(footprints allowed)
			)
			(placement
				(enabled no)
				(sheetname "")
			)
			(fill
				(thermal_gap 0.5)
				(thermal_bridge_width 0.5)
				(island_removal_mode 0)
			)
			(polygon
				(pts
					(xy 456.322684 -124.324618) (xy 459.345284 -124.324618) (xy 459.345284 -121.429018) (xy 459.345284 -121.098818)
					(xy 456.322684 -121.098818) (xy 456.322684 -121.429018)
				)
			)
		)
		(zone
			(layer "B.Cu")
			(hatch none 0.5)
			(connect_pads
				(clearance 0)
			)
			(min_thickness 0.25)
			(keepout
				(tracks allowed)
				(vias not_allowed)
				(pads allowed)
				(copperpour not_allowed)
				(footprints allowed)
			)
			(placement
				(enabled no)
				(sheetname "")
			)
			(fill
				(thermal_gap 0.5)
				(thermal_bridge_width 0.5)
				(island_removal_mode 0)
			)
			(polygon
				(pts
					(xy 459.345284 -118.038118) (xy 459.345284 -115.129818) (xy 456.322684 -115.129818) (xy 456.322684 -118.025418)
					(xy 456.322684 -118.355618) (xy 459.345284 -118.355618)
				)
			)
		)
	)
	(footprint ""
		(layer "B.Cu")
		(at 259.388864 -289.641534)
		(property "Reference" "R1176"
			(at 0 0 0)
			(layer "B.SilkS")
			(hide yes)
			(effects
				(font
					(size 1.27 1.27)
				)
				(justify mirror)
			)
		)
		(property "Value" "10R3F-GP"
			(at 0.0254 -2.5146 0)
			(unlocked yes)
			(layer "B.Fab")
			(hide yes)
			(effects
				(font
					(size 1.016 1.016)
					(thickness 0.1524)
				)
				(justify mirror)
			)
		)
		(property "Device Type" "R603H22"
			(at 0.0254 -4.0386 0)
			(unlocked yes)
			(layer "B.Fab")
			(hide yes)
			(effects
				(font
					(size 1.016 1.016)
					(thickness 0.1524)
				)
				(justify mirror)
			)
		)
		(duplicate_pad_numbers_are_jumpers no)
		(fp_line
			(start -0.2032 0)
			(end -0.4826 0)
			(stroke
				(width 0.2032)
				(type default)
			)
			(layer "B.SilkS")
		)
		(fp_line
			(start 0.4826 0)
			(end 0.2032 0)
			(stroke
				(width 0.2032)
				(type default)
			)
			(layer "B.SilkS")
		)
		(fp_rect
			(start 0.5842 1.3335)
			(end -0.5842 -1.3335)
			(stroke
				(width 0)
				(type default)
			)
			(fill no)
			(layer "B.CrtYd")
		)
		(fp_rect
			(start 0.5842 1.3335)
			(end -0.5842 -1.3335)
			(stroke
				(width 0)
				(type default)
			)
			(fill no)
			(layer "B.Fab")
		)
		(pad "1" smd custom
			(at 0 -0.762 180)
			(size 0.2159 0.2159)
			(layers "B.Cu" "B.Mask" "B.Paste")
			(net "P3V3_STBY_CC")
			(options
				(clearance outline)
				(anchor circle)
			)
			(primitives
				(gr_poly
					(pts
						(arc
							(start -0.3302 0.4318)
							(mid -0.402042 0.402042)
							(end -0.4318 0.3302)
						)
						(arc
							(start -0.4318 -0.3302)
							(mid -0.402042 -0.402042)
							(end -0.3302 -0.4318)
						)
						(arc
							(start 0.3302 -0.4318)
							(mid 0.402042 -0.402042)
							(end 0.4318 -0.3302)
						)
						(arc
							(start 0.4318 0.3302)
							(mid 0.402042 0.402042)
							(end 0.3302 0.4318)
						)
					)
					(width 0)
					(fill yes)
				)
			)
		)
		(pad "2" smd custom
			(at 0 0.762 180)
			(size 0.2159 0.2159)
			(layers "B.Cu" "B.Mask" "B.Paste")
			(net "P3V3_STBY_CC_R")
			(options
				(clearance outline)
				(anchor circle)
			)
			(primitives
				(gr_poly
					(pts
						(arc
							(start -0.3302 0.4318)
							(mid -0.402042 0.402042)
							(end -0.4318 0.3302)
						)
						(arc
							(start -0.4318 -0.3302)
							(mid -0.402042 -0.402042)
							(end -0.3302 -0.4318)
						)
						(arc
							(start 0.3302 -0.4318)
							(mid 0.402042 -0.402042)
							(end 0.4318 -0.3302)
						)
						(arc
							(start 0.4318 0.3302)
							(mid 0.402042 0.402042)
							(end 0.3302 0.4318)
						)
					)
					(width 0)
					(fill yes)
				)
			)
		)
	)
	(footprint ""
		(layer "B.Cu")
		(at 253.873 -279.146 90)
		(property "Reference" "C707"
			(at 0 0 90)
			(layer "B.SilkS")
			(hide yes)
			(effects
				(font
					(size 1.27 1.27)
				)
				(justify mirror)
			)
		)
		(property "Value" "SC1U16V3KX-5GP"
			(at 0 -2.8194 90)
			(unlocked yes)
			(layer "B.Fab")
			(hide yes)
			(effects
				(font
					(size 1.016 1.016)
					(thickness 0.1524)
				)
				(justify mirror)
			)
		)
		(property "Device Type" "C603H36"
			(at 0 -4.3434 90)
			(unlocked yes)
			(layer "B.Fab")
			(hide yes)
			(effects
				(font
					(size 1.016 1.016)
					(thickness 0.1524)
				)
				(justify mirror)
			)
		)
		(duplicate_pad_numbers_are_jumpers no)
		(fp_line
			(start -0.508 0)
			(end 0.508 0)
			(stroke
				(width 0.2032)
				(type default)
			)
			(layer "B.SilkS")
		)
		(fp_rect
			(start 0.5842 1.3335)
			(end -0.5842 -1.3335)
			(stroke
				(width 0)
				(type default)
			)
			(fill no)
			(layer "B.CrtYd")
		)
		(fp_rect
			(start 0.5842 1.3335)
			(end -0.5842 -1.3335)
			(stroke
				(width 0)
				(type default)
			)
			(fill no)
			(layer "B.Fab")
		)
		(pad "1" smd custom
			(at 0 -0.762 270)
			(size 0.2159 0.2159)
			(layers "B.Cu" "B.Mask" "B.Paste")
			(net "GND")
			(options
				(clearance outline)
				(anchor circle)
			)
			(primitives
				(gr_poly
					(pts
						(arc
							(start -0.3302 0.4318)
							(mid -0.402042 0.402042)
							(end -0.4318 0.3302)
						)
						(arc
							(start -0.4318 -0.3302)
							(mid -0.402042 -0.402042)
							(end -0.3302 -0.4318)
						)
						(arc
							(start 0.3302 -0.4318)
							(mid 0.402042 -0.402042)
							(end 0.4318 -0.3302)
						)
						(arc
							(start 0.4318 0.3302)
							(mid 0.402042 0.402042)
							(end 0.3302 0.4318)
						)
					)
					(width 0)
					(fill yes)
				)
			)
		)
		(pad "2" smd custom
			(at 0 0.762 270)
			(size 0.2159 0.2159)
			(layers "B.Cu" "B.Mask" "B.Paste")
			(net "P3V3_STBY_EN_R")
			(options
				(clearance outline)
				(anchor circle)
			)
			(primitives
				(gr_poly
					(pts
						(arc
							(start -0.3302 0.4318)
							(mid -0.402042 0.402042)
							(end -0.4318 0.3302)
						)
						(arc
							(start -0.4318 -0.3302)
							(mid -0.402042 -0.402042)
							(end -0.3302 -0.4318)
						)
						(arc
							(start 0.3302 -0.4318)
							(mid 0.402042 -0.402042)
							(end 0.4318 -0.3302)
						)
						(arc
							(start 0.4318 0.3302)
							(mid 0.402042 0.402042)
							(end 0.3302 0.4318)
						)
					)
					(width 0)
					(fill yes)
				)
			)
		)
	)
	(footprint ""
		(layer "B.Cu")
		(at 251.714 -288.671 -90)
		(property "Reference" "C691"
			(at 0 0 90)
			(layer "B.SilkS")
			(hide yes)
			(effects
				(font
					(size 1.27 1.27)
				)
				(justify mirror)
			)
		)
		(property "Value" "SC10U16V5KX-7-GP-U"
			(at 0.0762 -6.1214 270)
			(unlocked yes)
			(layer "B.Fab")
			(hide yes)
			(effects
				(font
					(size 1.016 1.016)
					(thickness 0.1524)
				)
				(justify mirror)
			)
		)
		(property "Device Type" "C805H58"
			(at 0.0762 -8.1534 270)
			(unlocked yes)
			(layer "B.Fab")
			(hide yes)
			(effects
				(font
					(size 1.016 1.016)
					(thickness 0.1524)
				)
				(justify mirror)
			)
		)
		(duplicate_pad_numbers_are_jumpers no)
		(fp_line
			(start -0.635 0)
			(end 0.635 0)
			(stroke
				(width 0.508)
				(type default)
			)
			(layer "B.SilkS")
		)
		(fp_rect
			(start 0.9652 1.778)
			(end -0.9652 -1.778)
			(stroke
				(width 0)
				(type default)
			)
			(fill no)
			(layer "B.CrtYd")
		)
		(fp_poly
			(pts
				(xy 0.9652 -1.778) (xy -0.9652 -1.778) (xy -0.9652 1.778) (xy 0.9652 1.778)
			)
			(stroke
				(width 0)
				(type default)
			)
			(fill no)
			(layer "B.Fab")
		)
		(pad "1" smd rect
			(at 0 -0.9652 90)
			(size 1.397 1.143)
			(layers "B.Cu" "B.Mask" "B.Paste")
			(net "P3V3_STBY_VIN")
		)
		(pad "2" smd rect
			(at 0 0.9652 90)
			(size 1.397 1.143)
			(layers "B.Cu" "B.Mask" "B.Paste")
			(net "GND")
		)
	)
	(footprint ""
		(layer "B.Cu")
		(at 431.129186 -112.701578 180)
		(property "Reference" "C671"
			(at 0 0 0)
			(layer "B.SilkS")
			(hide yes)
			(effects
				(font
					(size 1.27 1.27)
				)
				(justify mirror)
			)
		)
		(property "Value" "SC10U16V5KX-7-GP-U"
			(at 0.0762 -6.1214 180)
			(unlocked yes)
			(layer "B.Fab")
			(hide yes)
			(effects
				(font
					(size 1.016 1.016)
					(thickness 0.1524)
				)
				(justify mirror)
			)
		)
		(property "Device Type" "C805H58"
			(at 0.0762 -8.1534 180)
			(unlocked yes)
			(layer "B.Fab")
			(hide yes)
			(effects
				(font
					(size 1.016 1.016)
					(thickness 0.1524)
				)
				(justify mirror)
			)
		)
		(duplicate_pad_numbers_are_jumpers no)
		(fp_line
			(start -0.635 0)
			(end 0.635 0)
			(stroke
				(width 0.508)
				(type default)
			)
			(layer "B.SilkS")
		)
		(fp_rect
			(start 0.9652 1.778)
			(end -0.9652 -1.778)
			(stroke
				(width 0)
				(type default)
			)
			(fill no)
			(layer "B.CrtYd")
		)
		(fp_poly
			(pts
				(xy 0.9652 -1.778) (xy -0.9652 -1.778) (xy -0.9652 1.778) (xy 0.9652 1.778)
			)
			(stroke
				(width 0)
				(type default)
			)
			(fill no)
			(layer "B.Fab")
		)
		(pad "1" smd rect
			(at 0 -0.9652)
			(size 1.397 1.143)
			(layers "B.Cu" "B.Mask" "B.Paste")
			(net "P12V_B_4_VIN_U34")
		)
		(pad "2" smd rect
			(at 0 0.9652)
			(size 1.397 1.143)
			(layers "B.Cu" "B.Mask" "B.Paste")
			(net "GND")
		)
	)
	(footprint ""
		(layer "B.Cu")
		(at 27.184604 -229.626414 -90)
		(property "Reference" "R1106"
			(at 0 0 90)
			(layer "B.SilkS")
			(hide yes)
			(effects
				(font
					(size 1.27 1.27)
				)
				(justify mirror)
			)
		)
		(property "Value" "10R3F-GP"
			(at 0.0254 -2.5146 270)
			(unlocked yes)
			(layer "B.Fab")
			(hide yes)
			(effects
				(font
					(size 1.016 1.016)
					(thickness 0.1524)
				)
				(justify mirror)
			)
		)
		(property "Device Type" "R603H22"
			(at 0.0254 -4.0386 270)
			(unlocked yes)
			(layer "B.Fab")
			(hide yes)
			(effects
				(font
					(size 1.016 1.016)
					(thickness 0.1524)
				)
				(justify mirror)
			)
		)
		(duplicate_pad_numbers_are_jumpers no)
		(fp_line
			(start -0.2032 0)
			(end -0.4826 0)
			(stroke
				(width 0.2032)
				(type default)
			)
			(layer "B.SilkS")
		)
		(fp_line
			(start 0.4826 0)
			(end 0.2032 0)
			(stroke
				(width 0.2032)
				(type default)
			)
			(layer "B.SilkS")
		)
		(fp_rect
			(start 0.5842 1.3335)
			(end -0.5842 -1.3335)
			(stroke
				(width 0)
				(type default)
			)
			(fill no)
			(layer "B.CrtYd")
		)
		(fp_rect
			(start 0.5842 1.3335)
			(end -0.5842 -1.3335)
			(stroke
				(width 0)
				(type default)
			)
			(fill no)
			(layer "B.Fab")
		)
		(pad "1" smd custom
			(at 0 -0.762 90)
			(size 0.2159 0.2159)
			(layers "B.Cu" "B.Mask" "B.Paste")
			(net "P5V_B_1_CC")
			(options
				(clearance outline)
				(anchor circle)
			)
			(primitives
				(gr_poly
					(pts
						(arc
							(start -0.3302 0.4318)
							(mid -0.402042 0.402042)
							(end -0.4318 0.3302)
						)
						(arc
							(start -0.4318 -0.3302)
							(mid -0.402042 -0.402042)
							(end -0.3302 -0.4318)
						)
						(arc
							(start 0.3302 -0.4318)
							(mid 0.402042 -0.402042)
							(end 0.4318 -0.3302)
						)
						(arc
							(start 0.4318 0.3302)
							(mid 0.402042 0.402042)
							(end 0.3302 0.4318)
						)
					)
					(width 0)
					(fill yes)
				)
			)
		)
		(pad "2" smd custom
			(at 0 0.762 90)
			(size 0.2159 0.2159)
			(layers "B.Cu" "B.Mask" "B.Paste")
			(net "P5V_B_1_VFB_R")
			(options
				(clearance outline)
				(anchor circle)
			)
			(primitives
				(gr_poly
					(pts
						(arc
							(start -0.3302 0.4318)
							(mid -0.402042 0.402042)
							(end -0.4318 0.3302)
						)
						(arc
							(start -0.4318 -0.3302)
							(mid -0.402042 -0.402042)
							(end -0.3302 -0.4318)
						)
						(arc
							(start 0.3302 -0.4318)
							(mid 0.402042 -0.402042)
							(end 0.4318 -0.3302)
						)
						(arc
							(start 0.4318 0.3302)
							(mid 0.402042 0.402042)
							(end 0.3302 0.4318)
						)
					)
					(width 0)
					(fill yes)
				)
			)
		)
	)
	(footprint ""
		(layer "B.Cu")
		(at 448.664584 -111.780828 90)
		(property "Reference" "L8"
			(at 0 0 90)
			(layer "B.SilkS")
			(hide yes)
			(effects
				(font
					(size 1.27 1.27)
				)
				(justify mirror)
			)
		)
		(property "Value" "IND-1UH-191-GP"
			(at 6.7818 -2.1082 90)
			(unlocked yes)
			(layer "B.Fab")
			(hide yes)
			(effects
				(font
					(size 1.016 1.016)
					(thickness 0.1524)
				)
				(justify mirror)
			)
		)
		(property "Device Type" "L109100-2430-UH119"
			(at 6.7818 -3.6322 90)
			(unlocked yes)
			(layer "B.Fab")
			(hide yes)
			(effects
				(font
					(size 1.016 1.016)
					(thickness 0.1524)
				)
				(justify mirror)
			)
		)
		(duplicate_pad_numbers_are_jumpers no)
		(fp_line
			(start 5.2578 -6.4262)
			(end -5.2578 -6.4262)
			(stroke
				(width 0.1524)
				(type default)
			)
			(layer "B.SilkS")
		)
		(fp_line
			(start -5.2578 -6.4262)
			(end -5.2578 6.4262)
			(stroke
				(width 0.1524)
				(type default)
			)
			(layer "B.SilkS")
		)
		(fp_line
			(start 5.2578 6.4262)
			(end 5.2578 -6.4262)
			(stroke
				(width 0.1524)
				(type default)
			)
			(layer "B.SilkS")
		)
		(fp_line
			(start -5.2578 6.4262)
			(end 5.2578 6.4262)
			(stroke
				(width 0.1524)
				(type default)
			)
			(layer "B.SilkS")
		)
		(fp_rect
			(start 5.0038 5.4229)
			(end -5.0038 -5.4229)
			(stroke
				(width 0)
				(type default)
			)
			(fill no)
			(layer "B.CrtYd")
		)
		(fp_poly
			(pts
				(xy 5.5118 6.5024) (xy 5.5118 -6.5024) (xy -5.5118 -6.5024) (xy -5.5118 -0.8509) (xy -5.0038 -0.8509)
				(xy -5.0038 -5.4229) (xy 5.0038 -5.4229) (xy 5.0038 5.4229) (xy -5.0038 5.4229) (xy -5.0038 -0.8382)
				(xy -5.5118 -0.8382) (xy -5.5118 6.5024)
			)
			(stroke
				(width 0)
				(type default)
			)
			(fill no)
			(layer "B.CrtYd")
		)
		(fp_rect
			(start 5.5118 6.5024)
			(end -5.5118 -6.5024)
			(stroke
				(width 0)
				(type default)
			)
			(fill no)
			(layer "B.Fab")
		)
		(pad "1" smd rect
			(at 0 -4.396994 270)
			(size 3.5052 3.556)
			(layers "B.Cu" "B.Mask" "B.Paste")
			(net "P5V_B_4_LL")
		)
		(pad "2" smd rect
			(at 0 4.396994 270)
			(size 3.5052 3.556)
			(layers "B.Cu" "B.Mask" "B.Paste")
			(net "P5V_B_4")
		)
	)
	(footprint ""
		(layer "B.Cu")
		(at 130.694684 -366.349788 90)
		(property "Reference" "C378"
			(at 0 0 90)
			(layer "B.SilkS")
			(hide yes)
			(effects
				(font
					(size 1.27 1.27)
				)
				(justify mirror)
			)
		)
		(property "Value" "SCD033U25V2KX-GP"
			(at -1.1811 -2.7051 90)
			(unlocked yes)
			(layer "B.Fab")
			(hide yes)
			(effects
				(font
					(size 1.016 1.016)
					(thickness 0.1524)
				)
				(justify mirror)
			)
		)
		(property "Device Type" "C402H22"
			(at -1.1811 -4.2291 90)
			(unlocked yes)
			(layer "B.Fab")
			(hide yes)
			(effects
				(font
					(size 1.016 1.016)
					(thickness 0.1524)
				)
				(justify mirror)
			)
		)
		(duplicate_pad_numbers_are_jumpers no)
		(fp_rect
			(start 0.4318 0.9525)
			(end -0.4318 -0.9525)
			(stroke
				(width 0)
				(type default)
			)
			(fill no)
			(layer "B.CrtYd")
		)
		(fp_rect
			(start 0.4318 0.9525)
			(end -0.4318 -0.9525)
			(stroke
				(width 0)
				(type default)
			)
			(fill no)
			(layer "B.Fab")
		)
		(pad "1" smd custom
			(at 0 -0.4445 270)
			(size 0.1524 0.1524)
			(layers "B.Cu" "B.Mask" "B.Paste")
			(net "GATE_FAN1_R")
			(options
				(clearance outline)
				(anchor circle)
			)
			(primitives
				(gr_poly
					(pts
						(arc
							(start 0.3048 0.2032)
							(mid 0.275042 0.275042)
							(end 0.2032 0.3048)
						)
						(arc
							(start -0.2032 0.3048)
							(mid -0.275042 0.275042)
							(end -0.3048 0.2032)
						)
						(arc
							(start -0.3048 -0.2032)
							(mid -0.275042 -0.275042)
							(end -0.2032 -0.3048)
						)
						(arc
							(start 0.2032 -0.3048)
							(mid 0.275042 -0.275042)
							(end 0.3048 -0.2032)
						)
					)
					(width 0)
					(fill yes)
				)
			)
		)
		(pad "2" smd custom
			(at 0 0.4445 270)
			(size 0.1524 0.1524)
			(layers "B.Cu" "B.Mask" "B.Paste")
			(net "P12V_IN")
			(options
				(clearance outline)
				(anchor circle)
			)
			(primitives
				(gr_poly
					(pts
						(arc
							(start 0.3048 0.2032)
							(mid 0.275042 0.275042)
							(end 0.2032 0.3048)
						)
						(arc
							(start -0.2032 0.3048)
							(mid -0.275042 0.275042)
							(end -0.3048 0.2032)
						)
						(arc
							(start -0.3048 -0.2032)
							(mid -0.275042 -0.275042)
							(end -0.2032 -0.3048)
						)
						(arc
							(start 0.2032 -0.3048)
							(mid 0.275042 -0.275042)
							(end 0.3048 -0.2032)
						)
					)
					(width 0)
					(fill yes)
				)
			)
		)
	)
	(footprint ""
		(layer "B.Cu")
		(at 247.292114 -279.831546 -90)
		(property "Reference" "L9"
			(at 0 0 90)
			(layer "B.SilkS")
			(hide yes)
			(effects
				(font
					(size 1.27 1.27)
				)
				(justify mirror)
			)
		)
		(property "Value" "COIL-4D7UH-33-GP"
			(at 4.699 -4.0132 270)
			(unlocked yes)
			(layer "B.Fab")
			(hide yes)
			(effects
				(font
					(size 1.016 1.016)
					(thickness 0.1524)
				)
				(justify mirror)
			)
		)
		(property "Device Type" "L7066-1830-UH119"
			(at 4.699 -5.5372 270)
			(unlocked yes)
			(layer "B.Fab")
			(hide yes)
			(effects
				(font
					(size 1.016 1.016)
					(thickness 0.1524)
				)
				(justify mirror)
			)
		)
		(duplicate_pad_numbers_are_jumpers no)
		(fp_line
			(start -3.556 4.4958)
			(end 3.556 4.4958)
			(stroke
				(width 0.1524)
				(type default)
			)
			(layer "B.SilkS")
		)
		(fp_line
			(start 3.556 4.4958)
			(end 3.556 -4.4958)
			(stroke
				(width 0.1524)
				(type default)
			)
			(layer "B.SilkS")
		)
		(fp_line
			(start -3.556 -4.4958)
			(end -3.556 4.4958)
			(stroke
				(width 0.1524)
				(type default)
			)
			(layer "B.SilkS")
		)
		(fp_line
			(start 3.556 -4.4958)
			(end -3.556 -4.4958)
			(stroke
				(width 0.1524)
				(type default)
			)
			(layer "B.SilkS")
		)
		(fp_rect
			(start 3.302 3.4798)
			(end -3.302 -3.4798)
			(stroke
				(width 0)
				(type default)
			)
			(fill no)
			(layer "B.CrtYd")
		)
		(fp_poly
			(pts
				(xy 3.81 4.572) (xy 3.81 -4.572) (xy -3.81 -4.572) (xy -3.81 -0.5588) (xy -3.302 -0.5588) (xy -3.302 -3.4798)
				(xy 3.302 -3.4798) (xy 3.302 3.4798) (xy -3.302 3.4798) (xy -3.302 -0.5461) (xy -3.81 -0.5461) (xy -3.81 4.572)
			)
			(stroke
				(width 0)
				(type default)
			)
			(fill no)
			(layer "B.CrtYd")
		)
		(fp_rect
			(start 3.81 4.572)
			(end -3.81 -4.572)
			(stroke
				(width 0)
				(type default)
			)
			(fill no)
			(layer "B.Fab")
		)
		(pad "1" smd rect
			(at 0 -2.779522 90)
			(size 3.5052 2.921)
			(layers "B.Cu" "B.Mask" "B.Paste")
			(net "P3V3_STBY_SW")
		)
		(pad "2" smd rect
			(at 0 2.779522 90)
			(size 3.5052 2.921)
			(layers "B.Cu" "B.Mask" "B.Paste")
			(net "P3V3_STBY_B")
		)
	)
	(footprint ""
		(layer "B.Cu")
		(at 254.428498 -282.320746 -90)
		(property "Reference" "U35"
			(at 0 0 90)
			(layer "B.SilkS")
			(hide yes)
			(effects
				(font
					(size 1.27 1.27)
				)
				(justify mirror)
			)
		)
		(property "Value" "TPS53312RGTR-GP"
			(at -4.9784 -6.9342 270)
			(unlocked yes)
			(layer "B.Fab")
			(hide yes)
			(effects
				(font
					(size 1.016 1.016)
					(thickness 0.1524)
				)
				(justify mirror)
			)
		)
		(property "Device Type" "QFN16G3-G1D7H40"
			(at -4.9784 -8.4582 270)
			(unlocked yes)
			(layer "B.Fab")
			(hide yes)
			(effects
				(font
					(size 1.016 1.016)
					(thickness 0.1524)
				)
				(justify mirror)
			)
		)
		(duplicate_pad_numbers_are_jumpers no)
		(fp_line
			(start -2.5146 2.5146)
			(end -2.5146 1.2446)
			(stroke
				(width 0.1524)
				(type default)
			)
			(layer "B.SilkS")
		)
		(fp_line
			(start -1.2446 2.5146)
			(end -2.5146 2.5146)
			(stroke
				(width 0.1524)
				(type default)
			)
			(layer "B.SilkS")
		)
		(fp_line
			(start 2.5146 2.5146)
			(end 1.2446 2.5146)
			(stroke
				(width 0.1524)
				(type default)
			)
			(layer "B.SilkS")
		)
		(fp_line
			(start 0.249936 2.262124)
			(end 0.249936 3.024124)
			(stroke
				(width 0.1524)
				(type default)
			)
			(layer "B.SilkS")
		)
		(fp_line
			(start 2.5146 1.2446)
			(end 2.5146 2.5146)
			(stroke
				(width 0.1524)
				(type default)
			)
			(layer "B.SilkS")
		)
		(fp_line
			(start -2.262124 -0.249936)
			(end -2.770124 -0.249936)
			(stroke
				(width 0.1524)
				(type default)
			)
			(layer "B.SilkS")
		)
		(fp_line
			(start 2.262124 -0.750062)
			(end 2.770124 -0.750062)
			(stroke
				(width 0.1524)
				(type default)
			)
			(layer "B.SilkS")
		)
		(fp_line
			(start 1.2446 -2.5146)
			(end 2.5146 -2.5146)
			(stroke
				(width 0.1524)
				(type default)
			)
			(layer "B.SilkS")
		)
		(fp_line
			(start 2.5146 -2.5146)
			(end 2.5146 -1.2446)
			(stroke
				(width 0.1524)
				(type default)
			)
			(layer "B.SilkS")
		)
		(fp_poly
			(pts
				(xy -2.5146 -2.5146) (xy -1.2446 -2.5146) (xy -2.5146 -1.2446)
			)
			(stroke
				(width 0)
				(type default)
			)
			(fill yes)
			(layer "B.SilkS")
		)
		(fp_rect
			(start 1.4986 1.4986)
			(end -1.4986 -1.4986)
			(stroke
				(width 0)
				(type default)
			)
			(fill no)
			(layer "B.CrtYd")
		)
		(fp_poly
			(pts
				(xy -2.5146 -1.4986) (xy 1.4986 -1.4986) (xy 1.4986 1.4986) (xy -1.4986 1.4986) (xy -1.4986 -1.4859)
				(xy -2.5146 -1.4859) (xy -2.5146 2.5146) (xy 2.5146 2.5146) (xy 2.5146 -2.5146) (xy -2.5146 -2.5146)
			)
			(stroke
				(width 0)
				(type default)
			)
			(fill no)
			(layer "B.CrtYd")
		)
		(fp_rect
			(start 2.5146 2.5146)
			(end -2.5146 -2.5146)
			(stroke
				(width 0)
				(type default)
			)
			(fill no)
			(layer "B.Fab")
		)
		(pad "1" smd rect
			(at -0.750062 -1.550924 90)
			(size 0.3048 0.9144)
			(layers "B.Cu" "B.Mask" "B.Paste")
			(net "P3V3_STBY_VFB")
		)
		(pad "2" smd rect
			(at -0.249936 -1.538224 90)
			(size 0.3048 0.9398)
			(layers "B.Cu" "B.Mask" "B.Paste")
			(net "P3V3_STBY_VRG5")
		)
		(pad "3" smd rect
			(at 0.249936 -1.538224 90)
			(size 0.3048 0.9398)
			(layers "B.Cu" "B.Mask" "B.Paste")
			(net "P3V3_STBY_SS")
		)
		(pad "4" smd rect
			(at 0.750062 -1.550924 90)
			(size 0.3048 0.9144)
			(layers "B.Cu" "B.Mask" "B.Paste")
			(net "AGND_P3V3_STBY")
		)
		(pad "5" smd rect
			(at 1.550924 -0.750062 90)
			(size 0.9144 0.3048)
			(layers "B.Cu" "B.Mask" "B.Paste")
			(net "PWRGD_P3V3_STBY")
		)
		(pad "6" smd rect
			(at 1.538224 -0.249936 90)
			(size 0.9398 0.3048)
			(layers "B.Cu" "B.Mask" "B.Paste")
			(net "P3V3_STBY_EN_R")
		)
		(pad "7" smd rect
			(at 1.538224 0.249936 90)
			(size 0.9398 0.3048)
			(layers "B.Cu" "B.Mask" "B.Paste")
			(net "GND")
		)
		(pad "8" smd rect
			(at 1.550924 0.750062 90)
			(size 0.9144 0.3048)
			(layers "B.Cu" "B.Mask" "B.Paste")
			(net "GND")
		)
		(pad "9" smd rect
			(at 0.750062 1.550924 90)
			(size 0.3048 0.9144)
			(layers "B.Cu" "B.Mask" "B.Paste")
			(net "P3V3_STBY_SW")
		)
		(pad "10" smd rect
			(at 0.249936 1.538224 90)
			(size 0.3048 0.9398)
			(layers "B.Cu" "B.Mask" "B.Paste")
			(net "P3V3_STBY_SW")
		)
		(pad "11" smd rect
			(at -0.249936 1.538224 90)
			(size 0.3048 0.9398)
			(layers "B.Cu" "B.Mask" "B.Paste")
			(net "P3V3_STBY_SW")
		)
		(pad "12" smd rect
			(at -0.750062 1.550924 90)
			(size 0.3048 0.9144)
			(layers "B.Cu" "B.Mask" "B.Paste")
			(net "P3V3_STBY_VBST")
		)
		(pad "13" smd rect
			(at -1.550924 0.750062 90)
			(size 0.9144 0.3048)
			(layers "B.Cu" "B.Mask" "B.Paste")
			(net "P3V3_STBY_VIN")
		)
		(pad "14" smd rect
			(at -1.538224 0.249936 90)
			(size 0.9398 0.3048)
			(layers "B.Cu" "B.Mask" "B.Paste")
			(net "P3V3_STBY_VIN")
		)
		(pad "15" smd rect
			(at -1.538224 -0.249936 90)
			(size 0.9398 0.3048)
			(layers "B.Cu" "B.Mask" "B.Paste")
			(net "P3V3_STBY_VCC")
		)
		(pad "16" smd rect
			(at -1.550924 -0.750062 90)
			(size 0.9144 0.3048)
			(layers "B.Cu" "B.Mask" "B.Paste")
			(net "P3V3_STBY_VO")
		)
		(pad "17" smd rect
			(at 0 0 90)
			(size 1.6764 1.6764)
			(layers "B.Cu" "B.Mask" "B.Paste")
			(net "GND")
		)
	)
	(footprint ""
		(layer "B.Cu")
		(at 457.833984 -109.745018)
		(property "Reference" "TC7"
			(at 0 0 0)
			(layer "B.SilkS")
			(hide yes)
			(effects
				(font
					(size 1.27 1.27)
				)
				(justify mirror)
			)
		)
		(property "Value" "ST220U10VDM-LGP"
			(at 0 -9.6012 0)
			(unlocked yes)
			(layer "B.Fab")
			(hide yes)
			(effects
				(font
					(size 1.016 1.016)
					(thickness 0.1524)
				)
				(justify mirror)
			)
		)
		(property "Device Type" "CT7343H119"
			(at 0 -11.1252 0)
			(unlocked yes)
			(layer "B.Fab")
			(hide yes)
			(effects
				(font
					(size 1.016 1.016)
					(thickness 0.1524)
				)
				(justify mirror)
			)
		)
		(duplicate_pad_numbers_are_jumpers no)
		(fp_line
			(start -2.286 -4.8768)
			(end 2.286 -4.8768)
			(stroke
				(width 0.1524)
				(type default)
			)
			(layer "B.SilkS")
		)
		(fp_line
			(start -2.286 -2.032)
			(end -2.286 -4.8768)
			(stroke
				(width 0.1524)
				(type default)
			)
			(layer "B.SilkS")
		)
		(fp_line
			(start -2.286 2.032)
			(end -2.286 4.8768)
			(stroke
				(width 0.1524)
				(type default)
			)
			(layer "B.SilkS")
		)
		(fp_line
			(start -2.286 4.8768)
			(end 2.286 4.8768)
			(stroke
				(width 0.1524)
				(type default)
			)
			(layer "B.SilkS")
		)
		(fp_line
			(start -2.1082 -4.699)
			(end 2.1082 -4.699)
			(stroke
				(width 0.508)
				(type default)
			)
			(layer "B.SilkS")
		)
		(fp_line
			(start 2.286 -4.8768)
			(end 2.286 -2.032)
			(stroke
				(width 0.1524)
				(type default)
			)
			(layer "B.SilkS")
		)
		(fp_line
			(start 2.286 4.8768)
			(end 2.286 2.032)
			(stroke
				(width 0.1524)
				(type default)
			)
			(layer "B.SilkS")
		)
		(fp_rect
			(start 2.1463 3.6449)
			(end -2.1463 -3.6449)
			(stroke
				(width 0)
				(type default)
			)
			(fill no)
			(layer "B.CrtYd")
		)
		(fp_poly
			(pts
				(xy 2.54 4.953) (xy 2.54 4.2926) (xy 3.81 4.2926) (xy 3.81 -4.2926) (xy 2.54 -4.2926) (xy 2.54 -4.953)
				(xy -2.54 -4.953) (xy -2.54 -4.2926) (xy -3.81 -4.2926) (xy -3.81 -1.6256) (xy -2.1463 -1.6256)
				(xy -2.1463 -3.6449) (xy 2.1463 -3.6449) (xy 2.1463 3.6449) (xy -2.1463 3.6449) (xy -2.1463 -1.6129)
				(xy -3.81 -1.6129) (xy -3.81 4.2926) (xy -2.54 4.2926) (xy -2.54 4.953)
			)
			(stroke
				(width 0)
				(type default)
			)
			(fill no)
			(layer "B.CrtYd")
		)
		(fp_rect
			(start -2.54 4.2926)
			(end -3.81 -4.2926)
			(stroke
				(width 0)
				(type default)
			)
			(fill no)
			(layer "B.Fab")
		)
		(fp_rect
			(start 2.54 4.953)
			(end -2.54 -4.953)
			(stroke
				(width 0)
				(type default)
			)
			(fill no)
			(layer "B.Fab")
		)
		(fp_rect
			(start 3.81 4.2926)
			(end 2.54 -4.2926)
			(stroke
				(width 0)
				(type default)
			)
			(fill no)
			(layer "B.Fab")
		)
		(pad "1" smd rect
			(at 0 -3.1496 180)
			(size 2.413 2.286)
			(layers "B.Cu" "B.Mask" "B.Paste")
			(net "P5V_B_4")
		)
		(pad "2" smd rect
			(at 0 3.1496 180)
			(size 2.413 2.286)
			(layers "B.Cu" "B.Mask" "B.Paste")
			(net "GND")
		)
		(zone
			(layer "B.Cu")
			(hatch none 0.5)
			(connect_pads
				(clearance 0)
			)
			(min_thickness 0.25)
			(keepout
				(tracks allowed)
				(vias not_allowed)
				(pads allowed)
				(copperpour not_allowed)
				(footprints allowed)
			)
			(placement
				(enabled no)
				(sheetname "")
			)
			(fill
				(thermal_gap 0.5)
				(thermal_bridge_width 0.5)
				(island_removal_mode 0)
			)
			(polygon
				(pts
					(xy 456.322684 -111.434118) (xy 456.322684 -114.342418) (xy 459.345284 -114.342418) (xy 459.345284 -111.446818)
					(xy 459.345284 -111.116618) (xy 456.322684 -111.116618)
				)
			)
		)
		(zone
			(layer "B.Cu")
			(hatch none 0.5)
			(connect_pads
				(clearance 0)
			)
			(min_thickness 0.25)
			(keepout
				(tracks allowed)
				(vias not_allowed)
				(pads allowed)
				(copperpour not_allowed)
				(footprints allowed)
			)
			(placement
				(enabled no)
				(sheetname "")
			)
			(fill
				(thermal_gap 0.5)
				(thermal_bridge_width 0.5)
				(island_removal_mode 0)
			)
			(polygon
				(pts
					(xy 459.345284 -105.147618) (xy 456.322684 -105.147618) (xy 456.322684 -108.043218) (xy 456.322684 -108.373418)
					(xy 459.345284 -108.373418) (xy 459.345284 -108.043218)
				)
			)
		)
	)
	(footprint ""
		(layer "B.Cu")
		(at 438.301384 -114.600228 -90)
		(property "Reference" "U34"
			(at 0 0 90)
			(layer "B.SilkS")
			(hide yes)
			(effects
				(font
					(size 1.27 1.27)
				)
				(justify mirror)
			)
		)
		(property "Value" "TPS53319DQPR-GP"
			(at -4.7498 -5.6896 270)
			(unlocked yes)
			(layer "B.Fab")
			(hide yes)
			(effects
				(font
					(size 1.016 1.016)
					(thickness 0.1524)
				)
				(justify mirror)
			)
		)
		(property "Device Type" "QFN22G6050-G6133H60"
			(at -4.7498 -7.2136 270)
			(unlocked yes)
			(layer "B.Fab")
			(hide yes)
			(effects
				(font
					(size 1.016 1.016)
					(thickness 0.1524)
				)
				(justify mirror)
			)
		)
		(duplicate_pad_numbers_are_jumpers no)
		(fp_line
			(start -3.556 3.5179)
			(end -3.556 2.2479)
			(stroke
				(width 0.1524)
				(type default)
			)
			(layer "B.SilkS")
		)
		(fp_line
			(start -2.286 3.5179)
			(end -3.556 3.5179)
			(stroke
				(width 0.1524)
				(type default)
			)
			(layer "B.SilkS")
		)
		(fp_line
			(start 3.556 3.5179)
			(end 2.286 3.5179)
			(stroke
				(width 0.1524)
				(type default)
			)
			(layer "B.SilkS")
		)
		(fp_line
			(start -1.500124 3.262122)
			(end -1.500124 4.024122)
			(stroke
				(width 0.1524)
				(type default)
			)
			(layer "B.SilkS")
		)
		(fp_line
			(start 0.999998 3.262122)
			(end 0.999998 3.770122)
			(stroke
				(width 0.1524)
				(type default)
			)
			(layer "B.SilkS")
		)
		(fp_line
			(start 3.556 2.2479)
			(end 3.556 3.5179)
			(stroke
				(width 0.1524)
				(type default)
			)
			(layer "B.SilkS")
		)
		(fp_line
			(start -0.500126 -3.262122)
			(end -0.500126 -3.770122)
			(stroke
				(width 0.1524)
				(type default)
			)
			(layer "B.SilkS")
		)
		(fp_line
			(start 1.999996 -3.262122)
			(end 1.999996 -4.024122)
			(stroke
				(width 0.1524)
				(type default)
			)
			(layer "B.SilkS")
		)
		(fp_line
			(start 2.286 -3.5179)
			(end 3.556 -3.5179)
			(stroke
				(width 0.1524)
				(type default)
			)
			(layer "B.SilkS")
		)
		(fp_line
			(start 3.556 -3.5179)
			(end 3.556 -2.2479)
			(stroke
				(width 0.1524)
				(type default)
			)
			(layer "B.SilkS")
		)
		(fp_poly
			(pts
				(xy -3.556 -3.5179) (xy -2.5273 -3.5179) (xy -3.556 -2.4892)
			)
			(stroke
				(width 0)
				(type default)
			)
			(fill yes)
			(layer "B.SilkS")
		)
		(fp_rect
			(start 2.9972 2.5019)
			(end -2.9972 -2.5019)
			(stroke
				(width 0)
				(type default)
			)
			(fill no)
			(layer "B.CrtYd")
		)
		(fp_poly
			(pts
				(xy -3.556 -2.5019) (xy 2.9972 -2.5019) (xy 2.9972 2.5019) (xy -2.9972 2.5019) (xy -2.9972 -2.4892)
				(xy -3.556 -2.4892) (xy -3.556 3.5179) (xy 3.556 3.5179) (xy 3.556 -3.5179) (xy -3.556 -3.5179)
			)
			(stroke
				(width 0)
				(type default)
			)
			(fill no)
			(layer "B.CrtYd")
		)
		(fp_rect
			(start 3.556 3.5179)
			(end -3.556 -3.5179)
			(stroke
				(width 0)
				(type default)
			)
			(fill no)
			(layer "B.Fab")
		)
		(pad "1" smd rect
			(at -2.500122 -2.449322 90)
			(size 0.3048 1.1176)
			(layers "B.Cu" "B.Mask" "B.Paste")
			(net "P5V_B_4_VFB")
		)
		(pad "2" smd rect
			(at -1.999996 -2.449322 90)
			(size 0.3048 1.1176)
			(layers "B.Cu" "B.Mask" "B.Paste")
			(net "P5V_B_4_EN_R")
		)
		(pad "3" smd rect
			(at -1.500124 -2.449322 90)
			(size 0.3048 1.1176)
			(layers "B.Cu" "B.Mask" "B.Paste")
			(net "P5V_B_4_PGOOD")
		)
		(pad "4" smd rect
			(at -0.999998 -2.449322 90)
			(size 0.3048 1.1176)
			(layers "B.Cu" "B.Mask" "B.Paste")
			(net "P5V_B_4_VBST")
		)
		(pad "5" smd rect
			(at -0.500126 -2.449322 90)
			(size 0.3048 1.1176)
			(layers "B.Cu" "B.Mask" "B.Paste")
			(net "P5V_B_4_ROVP")
		)
		(pad "6" smd rect
			(at 0 -2.449322 90)
			(size 0.3048 1.1176)
			(layers "B.Cu" "B.Mask" "B.Paste")
			(net "P5V_B_4_LL")
		)
		(pad "7" smd rect
			(at 0.500126 -2.449322 90)
			(size 0.3048 1.1176)
			(layers "B.Cu" "B.Mask" "B.Paste")
			(net "P5V_B_4_LL")
		)
		(pad "8" smd rect
			(at 0.999998 -2.449322 90)
			(size 0.3048 1.1176)
			(layers "B.Cu" "B.Mask" "B.Paste")
			(net "P5V_B_4_LL")
		)
		(pad "9" smd rect
			(at 1.500124 -2.449322 90)
			(size 0.3048 1.1176)
			(layers "B.Cu" "B.Mask" "B.Paste")
			(net "P5V_B_4_LL")
		)
		(pad "10" smd rect
			(at 1.999996 -2.449322 90)
			(size 0.3048 1.1176)
			(layers "B.Cu" "B.Mask" "B.Paste")
			(net "P5V_B_4_LL")
		)
		(pad "11" smd rect
			(at 2.500122 -2.449322 90)
			(size 0.3048 1.1176)
			(layers "B.Cu" "B.Mask" "B.Paste")
			(net "P5V_B_4_LL")
		)
		(pad "12" smd rect
			(at 2.500122 2.449322 90)
			(size 0.3048 1.1176)
			(layers "B.Cu" "B.Mask" "B.Paste")
			(net "P12V_B_4_VIN_U34")
		)
		(pad "13" smd rect
			(at 1.999996 2.449322 90)
			(size 0.3048 1.1176)
			(layers "B.Cu" "B.Mask" "B.Paste")
			(net "P12V_B_4_VIN_U34")
		)
		(pad "14" smd rect
			(at 1.500124 2.449322 90)
			(size 0.3048 1.1176)
			(layers "B.Cu" "B.Mask" "B.Paste")
			(net "P12V_B_4_VIN_U34")
		)
		(pad "15" smd rect
			(at 0.999998 2.449322 90)
			(size 0.3048 1.1176)
			(layers "B.Cu" "B.Mask" "B.Paste")
			(net "P12V_B_4_VIN_U34")
		)
		(pad "16" smd rect
			(at 0.500126 2.449322 90)
			(size 0.3048 1.1176)
			(layers "B.Cu" "B.Mask" "B.Paste")
			(net "P12V_B_4_VIN_U34")
		)
		(pad "17" smd rect
			(at 0 2.449322 90)
			(size 0.3048 1.1176)
			(layers "B.Cu" "B.Mask" "B.Paste")
			(net "P12V_B_4_VIN_U34")
		)
		(pad "18" smd rect
			(at -0.500126 2.449322 90)
			(size 0.3048 1.1176)
			(layers "B.Cu" "B.Mask" "B.Paste")
			(net "P5V_B_4_VREG")
		)
		(pad "19" smd rect
			(at -0.999998 2.449322 90)
			(size 0.3048 1.1176)
			(layers "B.Cu" "B.Mask" "B.Paste")
			(net "P12V_B_4_VDD_U34")
		)
		(pad "20" smd rect
			(at -1.500124 2.449322 90)
			(size 0.3048 1.1176)
			(layers "B.Cu" "B.Mask" "B.Paste")
			(net "P5V_B_4_MODE")
		)
		(pad "21" smd rect
			(at -1.999996 2.449322 90)
			(size 0.3048 1.1176)
			(layers "B.Cu" "B.Mask" "B.Paste")
			(net "P5V_B_4_TRIP")
		)
		(pad "22" smd rect
			(at -2.500122 2.449322 90)
			(size 0.3048 1.1176)
			(layers "B.Cu" "B.Mask" "B.Paste")
			(net "P5V_B_4_RF")
		)
		(pad "23" smd custom
			(at 0 0 90)
			(size 0.83185 0.83185)
			(layers "B.Cu" "B.Mask" "B.Paste")
			(net "GND")
			(options
				(clearance outline)
				(anchor circle)
			)
			(primitives
				(gr_poly
					(pts
						(xy -2.7813 -1.6637) (xy -2.7813 -1.2954) (xy -3.048 -1.2954) (xy -3.048 -0.9525) (xy -2.7813 -0.9525)
						(xy -2.7813 0.9525) (xy -3.048 0.9525) (xy -3.048 1.2954) (xy -2.7813 1.2954) (xy -2.7813 1.6637)
						(xy 2.7813 1.6637) (xy 2.7813 1.2954) (xy 3.048 1.2954) (xy 3.048 0.9525) (xy 2.7813 0.9525) (xy 2.7813 -0.9525)
						(xy 3.048 -0.9525) (xy 3.048 -1.2954) (xy 2.7813 -1.2954) (xy 2.7813 -1.6637)
					)
					(width 0)
					(fill yes)
				)
			)
		)
	)
	(footprint ""
		(layer "B.Cu")
		(at 48.707802 -228.35235 180)
		(property "Reference" "C633"
			(at 0 0 0)
			(layer "B.SilkS")
			(hide yes)
			(effects
				(font
					(size 1.27 1.27)
				)
				(justify mirror)
			)
		)
		(property "Value" "SC10U16V5KX-7-GP-U"
			(at 0.0762 -6.1214 180)
			(unlocked yes)
			(layer "B.Fab")
			(hide yes)
			(effects
				(font
					(size 1.016 1.016)
					(thickness 0.1524)
				)
				(justify mirror)
			)
		)
		(property "Device Type" "C805H58"
			(at 0.0762 -8.1534 180)
			(unlocked yes)
			(layer "B.Fab")
			(hide yes)
			(effects
				(font
					(size 1.016 1.016)
					(thickness 0.1524)
				)
				(justify mirror)
			)
		)
		(duplicate_pad_numbers_are_jumpers no)
		(fp_line
			(start -0.635 0)
			(end 0.635 0)
			(stroke
				(width 0.508)
				(type default)
			)
			(layer "B.SilkS")
		)
		(fp_rect
			(start 0.9652 1.778)
			(end -0.9652 -1.778)
			(stroke
				(width 0)
				(type default)
			)
			(fill no)
			(layer "B.CrtYd")
		)
		(fp_poly
			(pts
				(xy 0.9652 -1.778) (xy -0.9652 -1.778) (xy -0.9652 1.778) (xy 0.9652 1.778)
			)
			(stroke
				(width 0)
				(type default)
			)
			(fill no)
			(layer "B.Fab")
		)
		(pad "1" smd rect
			(at 0 -0.9652)
			(size 1.397 1.143)
			(layers "B.Cu" "B.Mask" "B.Paste")
			(net "P5V_B_1")
		)
		(pad "2" smd rect
			(at 0 0.9652)
			(size 1.397 1.143)
			(layers "B.Cu" "B.Mask" "B.Paste")
			(net "GND")
		)
	)
	(footprint ""
		(layer "B.Cu")
		(at 258.22783 -280.680668)
		(property "Reference" "C695"
			(at 0 0 0)
			(layer "B.SilkS")
			(hide yes)
			(effects
				(font
					(size 1.27 1.27)
				)
				(justify mirror)
			)
		)
		(property "Value" "SC3300P50V2KX-1GP"
			(at -1.1811 -2.7051 0)
			(unlocked yes)
			(layer "B.Fab")
			(hide yes)
			(effects
				(font
					(size 1.016 1.016)
					(thickness 0.1524)
				)
				(justify mirror)
			)
		)
		(property "Device Type" "C402H22"
			(at -1.1811 -4.2291 0)
			(unlocked yes)
			(layer "B.Fab")
			(hide yes)
			(effects
				(font
					(size 1.016 1.016)
					(thickness 0.1524)
				)
				(justify mirror)
			)
		)
		(duplicate_pad_numbers_are_jumpers no)
		(fp_rect
			(start 0.4318 0.9525)
			(end -0.4318 -0.9525)
			(stroke
				(width 0)
				(type default)
			)
			(fill no)
			(layer "B.CrtYd")
		)
		(fp_rect
			(start 0.4318 0.9525)
			(end -0.4318 -0.9525)
			(stroke
				(width 0)
				(type default)
			)
			(fill no)
			(layer "B.Fab")
		)
		(pad "1" smd custom
			(at 0 -0.4445 180)
			(size 0.1524 0.1524)
			(layers "B.Cu" "B.Mask" "B.Paste")
			(net "P3V3_STBY_SS")
			(options
				(clearance outline)
				(anchor circle)
			)
			(primitives
				(gr_poly
					(pts
						(arc
							(start 0.3048 0.2032)
							(mid 0.275042 0.275042)
							(end 0.2032 0.3048)
						)
						(arc
							(start -0.2032 0.3048)
							(mid -0.275042 0.275042)
							(end -0.3048 0.2032)
						)
						(arc
							(start -0.3048 -0.2032)
							(mid -0.275042 -0.275042)
							(end -0.2032 -0.3048)
						)
						(arc
							(start 0.2032 -0.3048)
							(mid 0.275042 -0.275042)
							(end 0.3048 -0.2032)
						)
					)
					(width 0)
					(fill yes)
				)
			)
		)
		(pad "2" smd custom
			(at 0 0.4445 180)
			(size 0.1524 0.1524)
			(layers "B.Cu" "B.Mask" "B.Paste")
			(net "AGND_P3V3_STBY")
			(options
				(clearance outline)
				(anchor circle)
			)
			(primitives
				(gr_poly
					(pts
						(arc
							(start 0.3048 0.2032)
							(mid 0.275042 0.275042)
							(end 0.2032 0.3048)
						)
						(arc
							(start -0.2032 0.3048)
							(mid -0.275042 0.275042)
							(end -0.3048 0.2032)
						)
						(arc
							(start -0.3048 -0.2032)
							(mid -0.275042 -0.275042)
							(end -0.2032 -0.3048)
						)
						(arc
							(start 0.2032 -0.3048)
							(mid 0.275042 -0.275042)
							(end 0.3048 -0.2032)
						)
					)
					(width 0)
					(fill yes)
				)
			)
		)
	)
	(footprint ""
		(layer "B.Cu")
		(at 432.145186 -116.765578 -90)
		(property "Reference" "C678"
			(at 0 0 90)
			(layer "B.SilkS")
			(hide yes)
			(effects
				(font
					(size 1.27 1.27)
				)
				(justify mirror)
			)
		)
		(property "Value" "SC4D7U25V5KX-1-GP"
			(at 0.0762 -6.1214 270)
			(unlocked yes)
			(layer "B.Fab")
			(hide yes)
			(effects
				(font
					(size 1.016 1.016)
					(thickness 0.1524)
				)
				(justify mirror)
			)
		)
		(property "Device Type" "C805H58"
			(at 0.0762 -8.1534 270)
			(unlocked yes)
			(layer "B.Fab")
			(hide yes)
			(effects
				(font
					(size 1.016 1.016)
					(thickness 0.1524)
				)
				(justify mirror)
			)
		)
		(duplicate_pad_numbers_are_jumpers no)
		(fp_line
			(start -0.635 0)
			(end 0.635 0)
			(stroke
				(width 0.508)
				(type default)
			)
			(layer "B.SilkS")
		)
		(fp_rect
			(start 0.9652 1.778)
			(end -0.9652 -1.778)
			(stroke
				(width 0)
				(type default)
			)
			(fill no)
			(layer "B.CrtYd")
		)
		(fp_poly
			(pts
				(xy 0.9652 -1.778) (xy -0.9652 -1.778) (xy -0.9652 1.778) (xy 0.9652 1.778)
			)
			(stroke
				(width 0)
				(type default)
			)
			(fill no)
			(layer "B.Fab")
		)
		(pad "1" smd rect
			(at 0 -0.9652 90)
			(size 1.397 1.143)
			(layers "B.Cu" "B.Mask" "B.Paste")
			(net "P12V_B_4_VDD_U34")
		)
		(pad "2" smd rect
			(at 0 0.9652 90)
			(size 1.397 1.143)
			(layers "B.Cu" "B.Mask" "B.Paste")
			(net "GND")
		)
	)
	(footprint ""
		(layer "B.Cu")
		(at 259.865622 -284.124654 -90)
		(property "Reference" "R1175"
			(at 0 0 90)
			(layer "B.SilkS")
			(hide yes)
			(effects
				(font
					(size 1.27 1.27)
				)
				(justify mirror)
			)
		)
		(property "Value" "10KR2F-2-GP"
			(at -0.064008 -3.993896 270)
			(unlocked yes)
			(layer "B.Fab")
			(hide yes)
			(effects
				(font
					(size 1.016 1.016)
					(thickness 0.1524)
				)
				(justify mirror)
			)
		)
		(property "Device Type" "R402H16"
			(at -0.064008 -5.517896 270)
			(unlocked yes)
			(layer "B.Fab")
			(hide yes)
			(effects
				(font
					(size 1.016 1.016)
					(thickness 0.1524)
				)
				(justify mirror)
			)
		)
		(duplicate_pad_numbers_are_jumpers no)
		(fp_line
			(start -0.508 -0.9398)
			(end 0.508 -0.9398)
			(stroke
				(width 0.1524)
				(type default)
			)
			(layer "B.SilkS")
		)
		(fp_line
			(start 0.508 -0.9398)
			(end 0.508 0.9398)
			(stroke
				(width 0.1524)
				(type default)
			)
			(layer "B.SilkS")
		)
		(fp_rect
			(start 0.508 0.9398)
			(end -0.508 -0.9398)
			(stroke
				(width 0)
				(type default)
			)
			(fill no)
			(layer "B.CrtYd")
		)
		(fp_rect
			(start 0.508 0.9398)
			(end -0.508 -0.9398)
			(stroke
				(width 0)
				(type default)
			)
			(fill no)
			(layer "B.Fab")
		)
		(pad "1" smd custom
			(at 0 -0.4445 90)
			(size 0.1397 0.1397)
			(layers "B.Cu" "B.Mask" "B.Paste")
			(net "AGND_P3V3_STBY")
			(options
				(clearance outline)
				(anchor circle)
			)
			(primitives
				(gr_poly
					(pts
						(arc
							(start -0.1778 0.2794)
							(mid -0.249642 0.249642)
							(end -0.2794 0.1778)
						)
						(arc
							(start -0.2794 -0.1778)
							(mid -0.249642 -0.249642)
							(end -0.1778 -0.2794)
						)
						(arc
							(start 0.1778 -0.2794)
							(mid 0.249642 -0.249642)
							(end 0.2794 -0.1778)
						)
						(arc
							(start 0.2794 0.1778)
							(mid 0.249642 0.249642)
							(end 0.1778 0.2794)
						)
					)
					(width 0)
					(fill yes)
				)
			)
		)
		(pad "2" smd custom
			(at 0 0.4445 90)
			(size 0.1397 0.1397)
			(layers "B.Cu" "B.Mask" "B.Paste")
			(net "P3V3_STBY_VFB")
			(options
				(clearance outline)
				(anchor circle)
			)
			(primitives
				(gr_poly
					(pts
						(arc
							(start -0.1778 0.2794)
							(mid -0.249642 0.249642)
							(end -0.2794 0.1778)
						)
						(arc
							(start -0.2794 -0.1778)
							(mid -0.249642 -0.249642)
							(end -0.1778 -0.2794)
						)
						(arc
							(start 0.1778 -0.2794)
							(mid 0.249642 -0.249642)
							(end 0.2794 -0.1778)
						)
						(arc
							(start 0.2794 0.1778)
							(mid 0.249642 0.249642)
							(end 0.1778 0.2794)
						)
					)
					(width 0)
					(fill yes)
				)
			)
		)
	)
	(footprint ""
		(layer "B.Cu")
		(at 476.6564 -220.11259)
		(property "Reference" "TC10"
			(at 0 0 0)
			(layer "B.SilkS")
			(hide yes)
			(effects
				(font
					(size 1.27 1.27)
				)
				(justify mirror)
			)
		)
		(property "Value" "ST220U10VDM-LGP"
			(at 0 -9.6012 0)
			(unlocked yes)
			(layer "B.Fab")
			(hide yes)
			(effects
				(font
					(size 1.016 1.016)
					(thickness 0.1524)
				)
				(justify mirror)
			)
		)
		(property "Device Type" "CT7343H119"
			(at 0 -11.1252 0)
			(unlocked yes)
			(layer "B.Fab")
			(hide yes)
			(effects
				(font
					(size 1.016 1.016)
					(thickness 0.1524)
				)
				(justify mirror)
			)
		)
		(duplicate_pad_numbers_are_jumpers no)
		(fp_line
			(start -2.286 -4.8768)
			(end 2.286 -4.8768)
			(stroke
				(width 0.1524)
				(type default)
			)
			(layer "B.SilkS")
		)
		(fp_line
			(start -2.286 -2.032)
			(end -2.286 -4.8768)
			(stroke
				(width 0.1524)
				(type default)
			)
			(layer "B.SilkS")
		)
		(fp_line
			(start -2.286 2.032)
			(end -2.286 4.8768)
			(stroke
				(width 0.1524)
				(type default)
			)
			(layer "B.SilkS")
		)
		(fp_line
			(start -2.286 4.8768)
			(end 2.286 4.8768)
			(stroke
				(width 0.1524)
				(type default)
			)
			(layer "B.SilkS")
		)
		(fp_line
			(start -2.1082 -4.699)
			(end 2.1082 -4.699)
			(stroke
				(width 0.508)
				(type default)
			)
			(layer "B.SilkS")
		)
		(fp_line
			(start 2.286 -4.8768)
			(end 2.286 -2.032)
			(stroke
				(width 0.1524)
				(type default)
			)
			(layer "B.SilkS")
		)
		(fp_line
			(start 2.286 4.8768)
			(end 2.286 2.032)
			(stroke
				(width 0.1524)
				(type default)
			)
			(layer "B.SilkS")
		)
		(fp_rect
			(start 2.1463 3.6449)
			(end -2.1463 -3.6449)
			(stroke
				(width 0)
				(type default)
			)
			(fill no)
			(layer "B.CrtYd")
		)
		(fp_poly
			(pts
				(xy 2.54 4.953) (xy 2.54 4.2926) (xy 3.81 4.2926) (xy 3.81 -4.2926) (xy 2.54 -4.2926) (xy 2.54 -4.953)
				(xy -2.54 -4.953) (xy -2.54 -4.2926) (xy -3.81 -4.2926) (xy -3.81 -1.6256) (xy -2.1463 -1.6256)
				(xy -2.1463 -3.6449) (xy 2.1463 -3.6449) (xy 2.1463 3.6449) (xy -2.1463 3.6449) (xy -2.1463 -1.6129)
				(xy -3.81 -1.6129) (xy -3.81 4.2926) (xy -2.54 4.2926) (xy -2.54 4.953)
			)
			(stroke
				(width 0)
				(type default)
			)
			(fill no)
			(layer "B.CrtYd")
		)
		(fp_rect
			(start -2.54 4.2926)
			(end -3.81 -4.2926)
			(stroke
				(width 0)
				(type default)
			)
			(fill no)
			(layer "B.Fab")
		)
		(fp_rect
			(start 2.54 4.953)
			(end -2.54 -4.953)
			(stroke
				(width 0)
				(type default)
			)
			(fill no)
			(layer "B.Fab")
		)
		(fp_rect
			(start 3.81 4.2926)
			(end 2.54 -4.2926)
			(stroke
				(width 0)
				(type default)
			)
			(fill no)
			(layer "B.Fab")
		)
		(pad "1" smd rect
			(at 0 -3.1496 180)
			(size 2.413 2.286)
			(layers "B.Cu" "B.Mask" "B.Paste")
			(net "P5V_B_3")
		)
		(pad "2" smd rect
			(at 0 3.1496 180)
			(size 2.413 2.286)
			(layers "B.Cu" "B.Mask" "B.Paste")
			(net "GND")
		)
		(zone
			(layer "B.Cu")
			(hatch none 0.5)
			(connect_pads
				(clearance 0)
			)
			(min_thickness 0.25)
			(keepout
				(tracks allowed)
				(vias not_allowed)
				(pads allowed)
				(copperpour not_allowed)
				(footprints allowed)
			)
			(placement
				(enabled no)
				(sheetname "")
			)
			(fill
				(thermal_gap 0.5)
				(thermal_bridge_width 0.5)
				(island_removal_mode 0)
			)
			(polygon
				(pts
					(xy 475.1451 -221.80169) (xy 475.1451 -224.70999) (xy 478.1677 -224.70999) (xy 478.1677 -221.81439)
					(xy 478.1677 -221.48419) (xy 475.1451 -221.48419)
				)
			)
		)
		(zone
			(layer "B.Cu")
			(hatch none 0.5)
			(connect_pads
				(clearance 0)
			)
			(min_thickness 0.25)
			(keepout
				(tracks allowed)
				(vias not_allowed)
				(pads allowed)
				(copperpour not_allowed)
				(footprints allowed)
			)
			(placement
				(enabled no)
				(sheetname "")
			)
			(fill
				(thermal_gap 0.5)
				(thermal_bridge_width 0.5)
				(island_removal_mode 0)
			)
			(polygon
				(pts
					(xy 478.1677 -215.51519) (xy 475.1451 -215.51519) (xy 475.1451 -218.41079) (xy 475.1451 -218.74099)
					(xy 478.1677 -218.74099) (xy 478.1677 -218.41079)
				)
			)
		)
	)
	(footprint ""
		(layer "B.Cu")
		(at 167.7162 -371.856 90)
		(property "Reference" "R999"
			(at 0 0 90)
			(layer "B.SilkS")
			(hide yes)
			(effects
				(font
					(size 1.27 1.27)
				)
				(justify mirror)
			)
		)
		(property "Value" "10R2F-L-GP"
			(at -0.064008 -3.993896 90)
			(unlocked yes)
			(layer "B.Fab")
			(hide yes)
			(effects
				(font
					(size 1.016 1.016)
					(thickness 0.1524)
				)
				(justify mirror)
			)
		)
		(property "Device Type" "R402H14"
			(at -0.064008 -5.517896 90)
			(unlocked yes)
			(layer "B.Fab")
			(hide yes)
			(effects
				(font
					(size 1.016 1.016)
					(thickness 0.1524)
				)
				(justify mirror)
			)
		)
		(duplicate_pad_numbers_are_jumpers no)
		(fp_line
			(start 0.508 -0.9398)
			(end 0.508 0.9398)
			(stroke
				(width 0.1524)
				(type default)
			)
			(layer "B.SilkS")
		)
		(fp_line
			(start -0.508 -0.9398)
			(end 0.508 -0.9398)
			(stroke
				(width 0.1524)
				(type default)
			)
			(layer "B.SilkS")
		)
		(fp_rect
			(start 0.508 0.9398)
			(end -0.508 -0.9398)
			(stroke
				(width 0)
				(type default)
			)
			(fill no)
			(layer "B.CrtYd")
		)
		(fp_rect
			(start 0.508 0.9398)
			(end -0.508 -0.9398)
			(stroke
				(width 0)
				(type default)
			)
			(fill no)
			(layer "B.Fab")
		)
		(pad "1" smd custom
			(at 0 -0.4445 270)
			(size 0.1397 0.1397)
			(layers "B.Cu" "B.Mask" "B.Paste")
			(net "MB0_CM_SENSE_R1_N")
			(options
				(clearance outline)
				(anchor circle)
			)
			(primitives
				(gr_poly
					(pts
						(arc
							(start -0.1778 0.2794)
							(mid -0.249642 0.249642)
							(end -0.2794 0.1778)
						)
						(arc
							(start -0.2794 -0.1778)
							(mid -0.249642 -0.249642)
							(end -0.1778 -0.2794)
						)
						(arc
							(start 0.1778 -0.2794)
							(mid 0.249642 -0.249642)
							(end 0.2794 -0.1778)
						)
						(arc
							(start 0.2794 0.1778)
							(mid 0.249642 0.249642)
							(end 0.1778 0.2794)
						)
					)
					(width 0)
					(fill yes)
				)
			)
		)
		(pad "2" smd custom
			(at 0 0.4445 270)
			(size 0.1397 0.1397)
			(layers "B.Cu" "B.Mask" "B.Paste")
			(net "MB0_CM_SENSE_N")
			(options
				(clearance outline)
				(anchor circle)
			)
			(primitives
				(gr_poly
					(pts
						(arc
							(start -0.1778 0.2794)
							(mid -0.249642 0.249642)
							(end -0.2794 0.1778)
						)
						(arc
							(start -0.2794 -0.1778)
							(mid -0.249642 -0.249642)
							(end -0.1778 -0.2794)
						)
						(arc
							(start 0.1778 -0.2794)
							(mid 0.249642 -0.249642)
							(end 0.2794 -0.1778)
						)
						(arc
							(start 0.2794 0.1778)
							(mid 0.249642 0.249642)
							(end 0.1778 0.2794)
						)
					)
					(width 0)
					(fill yes)
				)
			)
		)
	)
	(footprint ""
		(layer "B.Cu")
		(at 56.801258 -110.912656 90)
		(property "Reference" "L4"
			(at 0 0 90)
			(layer "B.SilkS")
			(hide yes)
			(effects
				(font
					(size 1.27 1.27)
				)
				(justify mirror)
			)
		)
		(property "Value" "IND-1UH-191-GP"
			(at 6.7818 -2.1082 90)
			(unlocked yes)
			(layer "B.Fab")
			(hide yes)
			(effects
				(font
					(size 1.016 1.016)
					(thickness 0.1524)
				)
				(justify mirror)
			)
		)
		(property "Device Type" "L109100-2430-UH119"
			(at 6.7818 -3.6322 90)
			(unlocked yes)
			(layer "B.Fab")
			(hide yes)
			(effects
				(font
					(size 1.016 1.016)
					(thickness 0.1524)
				)
				(justify mirror)
			)
		)
		(duplicate_pad_numbers_are_jumpers no)
		(fp_line
			(start 5.2578 -6.4262)
			(end -5.2578 -6.4262)
			(stroke
				(width 0.1524)
				(type default)
			)
			(layer "B.SilkS")
		)
		(fp_line
			(start -5.2578 -6.4262)
			(end -5.2578 6.4262)
			(stroke
				(width 0.1524)
				(type default)
			)
			(layer "B.SilkS")
		)
		(fp_line
			(start 5.2578 6.4262)
			(end 5.2578 -6.4262)
			(stroke
				(width 0.1524)
				(type default)
			)
			(layer "B.SilkS")
		)
		(fp_line
			(start -5.2578 6.4262)
			(end 5.2578 6.4262)
			(stroke
				(width 0.1524)
				(type default)
			)
			(layer "B.SilkS")
		)
		(fp_rect
			(start 5.0038 5.4229)
			(end -5.0038 -5.4229)
			(stroke
				(width 0)
				(type default)
			)
			(fill no)
			(layer "B.CrtYd")
		)
		(fp_poly
			(pts
				(xy 5.5118 6.5024) (xy 5.5118 -6.5024) (xy -5.5118 -6.5024) (xy -5.5118 -0.8509) (xy -5.0038 -0.8509)
				(xy -5.0038 -5.4229) (xy 5.0038 -5.4229) (xy 5.0038 5.4229) (xy -5.0038 5.4229) (xy -5.0038 -0.8382)
				(xy -5.5118 -0.8382) (xy -5.5118 6.5024)
			)
			(stroke
				(width 0)
				(type default)
			)
			(fill no)
			(layer "B.CrtYd")
		)
		(fp_rect
			(start 5.5118 6.5024)
			(end -5.5118 -6.5024)
			(stroke
				(width 0)
				(type default)
			)
			(fill no)
			(layer "B.Fab")
		)
		(pad "1" smd rect
			(at 0 -4.396994 270)
			(size 3.5052 3.556)
			(layers "B.Cu" "B.Mask" "B.Paste")
			(net "P5V_B_2_LL")
		)
		(pad "2" smd rect
			(at 0 4.396994 270)
			(size 3.5052 3.556)
			(layers "B.Cu" "B.Mask" "B.Paste")
			(net "P5V_B_2")
		)
	)
	(footprint ""
		(layer "B.Cu")
		(at 206.756 -329.184 90)
		(property "Reference" "R1015"
			(at 0 0 90)
			(layer "B.SilkS")
			(hide yes)
			(effects
				(font
					(size 1.27 1.27)
				)
				(justify mirror)
			)
		)
		(property "Value" "10R5F-1-GP"
			(at 0 -8.9535 90)
			(unlocked yes)
			(layer "B.Fab")
			(hide yes)
			(effects
				(font
					(size 1.27 1.016)
					(thickness 0.1524)
				)
				(justify mirror)
			)
		)
		(property "Device Type" "R805H24"
			(at 0 -10.6299 90)
			(unlocked yes)
			(layer "B.Fab")
			(hide yes)
			(effects
				(font
					(size 1.27 1.016)
					(thickness 0.1524)
				)
				(justify mirror)
			)
		)
		(duplicate_pad_numbers_are_jumpers no)
		(fp_line
			(start 0.889 -1.7018)
			(end 0.889 0.2794)
			(stroke
				(width 0.1524)
				(type default)
			)
			(layer "B.SilkS")
		)
		(fp_line
			(start -0.889 -1.7018)
			(end 0.889 -1.7018)
			(stroke
				(width 0.1524)
				(type default)
			)
			(layer "B.SilkS")
		)
		(fp_line
			(start -0.889 -1.7018)
			(end -0.889 -0.381)
			(stroke
				(width 0.1524)
				(type default)
			)
			(layer "B.SilkS")
		)
		(fp_line
			(start 0.889 0.0762)
			(end 0.889 1.7018)
			(stroke
				(width 0.1524)
				(type default)
			)
			(layer "B.SilkS")
		)
		(fp_line
			(start 0.889 1.7018)
			(end -0.889 1.7018)
			(stroke
				(width 0.1524)
				(type default)
			)
			(layer "B.SilkS")
		)
		(fp_line
			(start -0.889 1.7018)
			(end -0.889 -0.508)
			(stroke
				(width 0.1524)
				(type default)
			)
			(layer "B.SilkS")
		)
		(fp_poly
			(pts
				(xy -0.9652 -1.778) (xy -0.9652 1.778) (xy 0.9652 1.778) (xy 0.9652 -1.778)
			)
			(stroke
				(width 0)
				(type default)
			)
			(fill no)
			(layer "B.CrtYd")
		)
		(fp_rect
			(start 0.9652 1.778)
			(end -0.9652 -1.778)
			(stroke
				(width 0)
				(type default)
			)
			(fill no)
			(layer "B.Fab")
		)
		(pad "1" smd rect
			(at 0 -0.9652 270)
			(size 1.397 1.143)
			(layers "B.Cu" "B.Mask" "B.Paste")
			(net "MB0_12V_CTRL_GATE1")
		)
		(pad "2" smd rect
			(at 0 0.9652 270)
			(size 1.397 1.143)
			(layers "B.Cu" "B.Mask" "B.Paste")
			(net "MB0_CM_GATE_R")
		)
	)
	(footprint ""
		(layer "B.Cu")
		(at 201.955654 -344.193114 90)
		(property "Reference" "Q196"
			(at 0 0 90)
			(layer "B.SilkS")
			(hide yes)
			(effects
				(font
					(size 1.27 1.27)
				)
				(justify mirror)
			)
		)
		(property "Value" "IRFH8201TRPBF-GP"
			(at 4.2164 -4.3688 90)
			(unlocked yes)
			(layer "B.Fab")
			(hide yes)
			(effects
				(font
					(size 1.016 1.016)
					(thickness 0.1524)
				)
				(justify mirror)
			)
		)
		(property "Device Type" "PPAK-5PH42"
			(at 4.2164 -5.8928 90)
			(unlocked yes)
			(layer "B.Fab")
			(hide yes)
			(effects
				(font
					(size 1.016 1.016)
					(thickness 0.1524)
				)
				(justify mirror)
			)
		)
		(duplicate_pad_numbers_are_jumpers no)
		(fp_line
			(start 2.8956 -2.794)
			(end -2.8956 -2.794)
			(stroke
				(width 0.1524)
				(type default)
			)
			(layer "B.SilkS")
		)
		(fp_line
			(start -2.8956 -2.794)
			(end -2.8956 4.826)
			(stroke
				(width 0.1524)
				(type default)
			)
			(layer "B.SilkS")
		)
		(fp_line
			(start 2.8956 4.826)
			(end 2.8956 -2.794)
			(stroke
				(width 0.1524)
				(type default)
			)
			(layer "B.SilkS")
		)
		(fp_line
			(start -2.8956 4.826)
			(end 2.8956 4.826)
			(stroke
				(width 0.1524)
				(type default)
			)
			(layer "B.SilkS")
		)
		(fp_line
			(start 3.0353 4.9276)
			(end 3.0353 3.9624)
			(stroke
				(width 0.3302)
				(type default)
			)
			(layer "B.SilkS")
		)
		(fp_line
			(start 1.9431 4.9276)
			(end 3.0353 4.9276)
			(stroke
				(width 0.3302)
				(type default)
			)
			(layer "B.SilkS")
		)
		(fp_poly
			(pts
				(xy 2.3622 5.334) (xy 1.4986 5.334) (xy 1.9304 4.9022)
			)
			(stroke
				(width 0)
				(type default)
			)
			(fill yes)
			(layer "B.SilkS")
		)
		(fp_poly
			(pts
				(xy 2.6416 -0.3556) (xy 0.3556 -0.3556) (xy 0.3556 -2.54) (xy 2.6416 -2.54)
			)
			(stroke
				(width 0)
				(type default)
			)
			(fill yes)
			(layer "B.Paste")
		)
		(fp_poly
			(pts
				(xy -0.3556 -0.3556) (xy -2.6416 -0.3556) (xy -2.6416 -2.54) (xy -0.3556 -2.54)
			)
			(stroke
				(width 0)
				(type default)
			)
			(fill yes)
			(layer "B.Paste")
		)
		(fp_poly
			(pts
				(xy 2.6416 2.54) (xy 0.3556 2.54) (xy 0.3556 0.3556) (xy 2.6416 0.3556)
			)
			(stroke
				(width 0)
				(type default)
			)
			(fill yes)
			(layer "B.Paste")
		)
		(fp_poly
			(pts
				(xy -0.3556 2.54) (xy -2.6416 2.54) (xy -2.6416 0.3556) (xy -0.3556 0.3556)
			)
			(stroke
				(width 0)
				(type default)
			)
			(fill yes)
			(layer "B.Paste")
		)
		(fp_rect
			(start 2.5781 3.9878)
			(end -2.5781 -2.1082)
			(stroke
				(width 0)
				(type default)
			)
			(fill no)
			(layer "B.CrtYd")
		)
		(fp_poly
			(pts
				(xy 3.1496 5.08) (xy 3.1496 -3.048) (xy -3.1496 -3.048) (xy -3.1496 3.9751) (xy -2.5781 3.9751)
				(xy -2.5781 -2.1082) (xy 2.5781 -2.1082) (xy 2.5781 3.9878) (xy -3.1496 3.9878) (xy -3.1496 5.08)
			)
			(stroke
				(width 0)
				(type default)
			)
			(fill no)
			(layer "B.CrtYd")
		)
		(fp_rect
			(start 3.1496 5.08)
			(end -3.1496 -3.048)
			(stroke
				(width 0)
				(type default)
			)
			(fill no)
			(layer "B.Fab")
		)
		(pad "1" smd rect
			(at 1.905 3.81 270)
			(size 0.762 1.524)
			(layers "B.Cu" "B.Mask" "B.Paste")
			(net "P12V_IN")
		)
		(pad "2" smd rect
			(at 0.635 3.81 270)
			(size 0.762 1.524)
			(layers "B.Cu" "B.Mask" "B.Paste")
			(net "P12V_IN")
		)
		(pad "3" smd rect
			(at -0.635 3.81 270)
			(size 0.762 1.524)
			(layers "B.Cu" "B.Mask" "B.Paste")
			(net "P12V_IN")
		)
		(pad "4" smd rect
			(at -1.905 3.81 270)
			(size 0.762 1.524)
			(layers "B.Cu" "B.Mask" "B.Paste")
			(net "MB0_12V_CTRL_GATE3")
		)
		(pad "5" smd rect
			(at 0 0 270)
			(size 5.2832 5.08)
			(layers "B.Cu" "B.Mask" "B.Paste")
			(net "MB0_P12V_IN_R")
		)
		(pad "6" smd rect
			(at -0.635 -2.032 270)
			(size 0.0254 0.0254)
			(layers "B.Cu" "B.Mask" "B.Paste")
			(net "MB0_P12V_IN_R")
		)
		(pad "7" smd rect
			(at 0.635 -2.032 270)
			(size 0.0254 0.0254)
			(layers "B.Cu" "B.Mask" "B.Paste")
			(net "MB0_P12V_IN_R")
		)
		(pad "8" smd rect
			(at 1.905 -2.032 270)
			(size 0.0254 0.0254)
			(layers "B.Cu" "B.Mask" "B.Paste")
			(net "MB0_P12V_IN_R")
		)
	)
	(footprint ""
		(layer "B.Cu")
		(at 460.0448 -229.6922 90)
		(property "Reference" "R1147"
			(at 0 0 90)
			(layer "B.SilkS")
			(hide yes)
			(effects
				(font
					(size 1.27 1.27)
				)
				(justify mirror)
			)
		)
		(property "Value" "71K5R2F-GP"
			(at -0.064008 -3.993896 90)
			(unlocked yes)
			(layer "B.Fab")
			(hide yes)
			(effects
				(font
					(size 1.016 1.016)
					(thickness 0.1524)
				)
				(justify mirror)
			)
		)
		(property "Device Type" "R402H16"
			(at -0.064008 -5.517896 90)
			(unlocked yes)
			(layer "B.Fab")
			(hide yes)
			(effects
				(font
					(size 1.016 1.016)
					(thickness 0.1524)
				)
				(justify mirror)
			)
		)
		(duplicate_pad_numbers_are_jumpers no)
		(fp_line
			(start 0.508 -0.9398)
			(end 0.508 0.9398)
			(stroke
				(width 0.1524)
				(type default)
			)
			(layer "B.SilkS")
		)
		(fp_line
			(start -0.508 -0.9398)
			(end 0.508 -0.9398)
			(stroke
				(width 0.1524)
				(type default)
			)
			(layer "B.SilkS")
		)
		(fp_rect
			(start 0.508 0.9398)
			(end -0.508 -0.9398)
			(stroke
				(width 0)
				(type default)
			)
			(fill no)
			(layer "B.CrtYd")
		)
		(fp_rect
			(start 0.508 0.9398)
			(end -0.508 -0.9398)
			(stroke
				(width 0)
				(type default)
			)
			(fill no)
			(layer "B.Fab")
		)
		(pad "1" smd custom
			(at 0 -0.4445 270)
			(size 0.1397 0.1397)
			(layers "B.Cu" "B.Mask" "B.Paste")
			(net "P5V_B_3_VFB")
			(options
				(clearance outline)
				(anchor circle)
			)
			(primitives
				(gr_poly
					(pts
						(arc
							(start -0.1778 0.2794)
							(mid -0.249642 0.249642)
							(end -0.2794 0.1778)
						)
						(arc
							(start -0.2794 -0.1778)
							(mid -0.249642 -0.249642)
							(end -0.1778 -0.2794)
						)
						(arc
							(start 0.1778 -0.2794)
							(mid 0.249642 -0.249642)
							(end 0.2794 -0.1778)
						)
						(arc
							(start 0.2794 0.1778)
							(mid 0.249642 0.249642)
							(end 0.1778 0.2794)
						)
					)
					(width 0)
					(fill yes)
				)
			)
		)
		(pad "2" smd custom
			(at 0 0.4445 270)
			(size 0.1397 0.1397)
			(layers "B.Cu" "B.Mask" "B.Paste")
			(net "P5V_B_3_VFB_R")
			(options
				(clearance outline)
				(anchor circle)
			)
			(primitives
				(gr_poly
					(pts
						(arc
							(start -0.1778 0.2794)
							(mid -0.249642 0.249642)
							(end -0.2794 0.1778)
						)
						(arc
							(start -0.2794 -0.1778)
							(mid -0.249642 -0.249642)
							(end -0.1778 -0.2794)
						)
						(arc
							(start 0.1778 -0.2794)
							(mid 0.249642 -0.249642)
							(end 0.2794 -0.1778)
						)
						(arc
							(start 0.2794 0.1778)
							(mid 0.249642 0.249642)
							(end 0.1778 0.2794)
						)
					)
					(width 0)
					(fill yes)
				)
			)
		)
	)
	(footprint ""
		(layer "B.Cu")
		(at 261.874 -279.273 180)
		(property "Reference" "TP206"
			(at 0 0 0)
			(layer "B.SilkS")
			(hide yes)
			(effects
				(font
					(size 1.27 1.27)
				)
				(justify mirror)
			)
		)
		(property "Value" "*"
			(at 0.0508 -1.6764 180)
			(unlocked yes)
			(layer "B.Fab")
			(hide yes)
			(effects
				(font
					(size 1.016 1.016)
					(thickness 0.1524)
				)
				(justify mirror)
			)
		)
		(property "Device Type" "TPAD32"
			(at 0.0508 -3.2004 180)
			(unlocked yes)
			(layer "B.Fab")
			(hide yes)
			(effects
				(font
					(size 1.016 1.016)
					(thickness 0.1524)
				)
				(justify mirror)
			)
		)
		(duplicate_pad_numbers_are_jumpers no)
		(fp_poly
			(pts
				(arc
					(start -0.4064 0)
					(mid 0.4064 0)
					(end -0.4064 0)
				)
			)
			(stroke
				(width 0)
				(type default)
			)
			(fill no)
			(layer "B.CrtYd")
		)
		(fp_poly
			(pts
				(arc
					(start -0.7112 0)
					(mid 0.7112 0)
					(end -0.7112 0)
				)
			)
			(stroke
				(width 0)
				(type default)
			)
			(fill no)
			(layer "B.Fab")
		)
		(pad "1" smd circle
			(at 0 0)
			(size 0.8128 0.8128)
			(layers "B.Cu" "B.Mask" "B.Paste")
			(net "PWRGD_P3V3_STBY")
		)
	)
	(footprint ""
		(layer "B.Cu")
		(at 245.237 -285.75 -90)
		(property "Reference" "G10"
			(at 0 0 90)
			(layer "B.SilkS")
			(hide yes)
			(effects
				(font
					(size 1.27 1.27)
				)
				(justify mirror)
			)
		)
		(property "Value" "GAP-CLOSE-PWR-4-GP"
			(at 2.4638 -0.5461 270)
			(unlocked yes)
			(layer "B.Fab")
			(hide yes)
			(effects
				(font
					(size 1.016 1.016)
					(thickness 0.1524)
				)
				(justify mirror)
			)
		)
		(property "Device Type" "GAP-CLOSE-PWR-4"
			(at 2.4638 -2.0701 270)
			(unlocked yes)
			(layer "B.Fab")
			(hide yes)
			(effects
				(font
					(size 1.016 1.016)
					(thickness 0.1524)
				)
				(justify mirror)
			)
		)
		(duplicate_pad_numbers_are_jumpers no)
		(fp_rect
			(start 0.2794 0.254)
			(end -0.2794 -0.254)
			(stroke
				(width 0)
				(type default)
			)
			(fill no)
			(layer "B.CrtYd")
		)
		(fp_rect
			(start 0.2794 0.254)
			(end -0.2794 -0.254)
			(stroke
				(width 0)
				(type default)
			)
			(fill no)
			(layer "B.Fab")
		)
		(pad "1" smd rect
			(at 0.0635 0 90)
			(size 0.1778 0.254)
			(layers "B.Cu" "B.Mask" "B.Paste")
			(net "P3V3_STBY_B")
		)
		(pad "2" smd rect
			(at -0.0635 0 90)
			(size 0.1778 0.254)
			(layers "B.Cu" "B.Mask" "B.Paste")
			(net "P3V3_STBY_CC")
		)
	)
	(footprint ""
		(layer "B.Cu")
		(at 485.714802 -228.22535 -90)
		(property "Reference" "G5"
			(at 0 0 90)
			(layer "B.SilkS")
			(hide yes)
			(effects
				(font
					(size 1.27 1.27)
				)
				(justify mirror)
			)
		)
		(property "Value" "GAP-CLOSE-PWR-4-GP"
			(at 2.4638 -0.5461 270)
			(unlocked yes)
			(layer "B.Fab")
			(hide yes)
			(effects
				(font
					(size 1.016 1.016)
					(thickness 0.1524)
				)
				(justify mirror)
			)
		)
		(property "Device Type" "GAP-CLOSE-PWR-4"
			(at 2.4638 -2.0701 270)
			(unlocked yes)
			(layer "B.Fab")
			(hide yes)
			(effects
				(font
					(size 1.016 1.016)
					(thickness 0.1524)
				)
				(justify mirror)
			)
		)
		(duplicate_pad_numbers_are_jumpers no)
		(fp_rect
			(start 0.2794 0.254)
			(end -0.2794 -0.254)
			(stroke
				(width 0)
				(type default)
			)
			(fill no)
			(layer "B.CrtYd")
		)
		(fp_rect
			(start 0.2794 0.254)
			(end -0.2794 -0.254)
			(stroke
				(width 0)
				(type default)
			)
			(fill no)
			(layer "B.Fab")
		)
		(pad "1" smd rect
			(at 0.0635 0 90)
			(size 0.1778 0.254)
			(layers "B.Cu" "B.Mask" "B.Paste")
			(net "P5V_B_3")
		)
		(pad "2" smd rect
			(at -0.0635 0 90)
			(size 0.1778 0.254)
			(layers "B.Cu" "B.Mask" "B.Paste")
			(net "P5V_B_3_CC")
		)
	)
	(footprint ""
		(layer "B.Cu")
		(at 12.385802 -223.01835 180)
		(property "Reference" "C618"
			(at 0 0 0)
			(layer "B.SilkS")
			(hide yes)
			(effects
				(font
					(size 1.27 1.27)
				)
				(justify mirror)
			)
		)
		(property "Value" "SC10U16V5KX-7-GP-U"
			(at 0.0762 -6.1214 180)
			(unlocked yes)
			(layer "B.Fab")
			(hide yes)
			(effects
				(font
					(size 1.016 1.016)
					(thickness 0.1524)
				)
				(justify mirror)
			)
		)
		(property "Device Type" "C805H58"
			(at 0.0762 -8.1534 180)
			(unlocked yes)
			(layer "B.Fab")
			(hide yes)
			(effects
				(font
					(size 1.016 1.016)
					(thickness 0.1524)
				)
				(justify mirror)
			)
		)
		(duplicate_pad_numbers_are_jumpers no)
		(fp_line
			(start -0.635 0)
			(end 0.635 0)
			(stroke
				(width 0.508)
				(type default)
			)
			(layer "B.SilkS")
		)
		(fp_rect
			(start 0.9652 1.778)
			(end -0.9652 -1.778)
			(stroke
				(width 0)
				(type default)
			)
			(fill no)
			(layer "B.CrtYd")
		)
		(fp_poly
			(pts
				(xy 0.9652 -1.778) (xy -0.9652 -1.778) (xy -0.9652 1.778) (xy 0.9652 1.778)
			)
			(stroke
				(width 0)
				(type default)
			)
			(fill no)
			(layer "B.Fab")
		)
		(pad "1" smd rect
			(at 0 -0.9652)
			(size 1.397 1.143)
			(layers "B.Cu" "B.Mask" "B.Paste")
			(net "P12V_B_1_VIN_U31")
		)
		(pad "2" smd rect
			(at 0 0.9652)
			(size 1.397 1.143)
			(layers "B.Cu" "B.Mask" "B.Paste")
			(net "GND")
		)
	)
	(footprint ""
		(layer "B.Cu")
		(at 21.59 -224.917 -90)
		(property "Reference" "U31"
			(at 0 0 90)
			(layer "B.SilkS")
			(hide yes)
			(effects
				(font
					(size 1.27 1.27)
				)
				(justify mirror)
			)
		)
		(property "Value" "TPS53319DQPR-GP"
			(at -4.7498 -5.6896 270)
			(unlocked yes)
			(layer "B.Fab")
			(hide yes)
			(effects
				(font
					(size 1.016 1.016)
					(thickness 0.1524)
				)
				(justify mirror)
			)
		)
		(property "Device Type" "QFN22G6050-G6133H60"
			(at -4.7498 -7.2136 270)
			(unlocked yes)
			(layer "B.Fab")
			(hide yes)
			(effects
				(font
					(size 1.016 1.016)
					(thickness 0.1524)
				)
				(justify mirror)
			)
		)
		(duplicate_pad_numbers_are_jumpers no)
		(fp_line
			(start -3.556 3.5179)
			(end -3.556 2.2479)
			(stroke
				(width 0.1524)
				(type default)
			)
			(layer "B.SilkS")
		)
		(fp_line
			(start -2.286 3.5179)
			(end -3.556 3.5179)
			(stroke
				(width 0.1524)
				(type default)
			)
			(layer "B.SilkS")
		)
		(fp_line
			(start 3.556 3.5179)
			(end 2.286 3.5179)
			(stroke
				(width 0.1524)
				(type default)
			)
			(layer "B.SilkS")
		)
		(fp_line
			(start -1.500124 3.262122)
			(end -1.500124 4.024122)
			(stroke
				(width 0.1524)
				(type default)
			)
			(layer "B.SilkS")
		)
		(fp_line
			(start 0.999998 3.262122)
			(end 0.999998 3.770122)
			(stroke
				(width 0.1524)
				(type default)
			)
			(layer "B.SilkS")
		)
		(fp_line
			(start 3.556 2.2479)
			(end 3.556 3.5179)
			(stroke
				(width 0.1524)
				(type default)
			)
			(layer "B.SilkS")
		)
		(fp_line
			(start -0.500126 -3.262122)
			(end -0.500126 -3.770122)
			(stroke
				(width 0.1524)
				(type default)
			)
			(layer "B.SilkS")
		)
		(fp_line
			(start 1.999996 -3.262122)
			(end 1.999996 -4.024122)
			(stroke
				(width 0.1524)
				(type default)
			)
			(layer "B.SilkS")
		)
		(fp_line
			(start 2.286 -3.5179)
			(end 3.556 -3.5179)
			(stroke
				(width 0.1524)
				(type default)
			)
			(layer "B.SilkS")
		)
		(fp_line
			(start 3.556 -3.5179)
			(end 3.556 -2.2479)
			(stroke
				(width 0.1524)
				(type default)
			)
			(layer "B.SilkS")
		)
		(fp_poly
			(pts
				(xy -3.556 -3.5179) (xy -2.5273 -3.5179) (xy -3.556 -2.4892)
			)
			(stroke
				(width 0)
				(type default)
			)
			(fill yes)
			(layer "B.SilkS")
		)
		(fp_rect
			(start 2.9972 2.5019)
			(end -2.9972 -2.5019)
			(stroke
				(width 0)
				(type default)
			)
			(fill no)
			(layer "B.CrtYd")
		)
		(fp_poly
			(pts
				(xy -3.556 -2.5019) (xy 2.9972 -2.5019) (xy 2.9972 2.5019) (xy -2.9972 2.5019) (xy -2.9972 -2.4892)
				(xy -3.556 -2.4892) (xy -3.556 3.5179) (xy 3.556 3.5179) (xy 3.556 -3.5179) (xy -3.556 -3.5179)
			)
			(stroke
				(width 0)
				(type default)
			)
			(fill no)
			(layer "B.CrtYd")
		)
		(fp_rect
			(start 3.556 3.5179)
			(end -3.556 -3.5179)
			(stroke
				(width 0)
				(type default)
			)
			(fill no)
			(layer "B.Fab")
		)
		(pad "1" smd rect
			(at -2.500122 -2.449322 90)
			(size 0.3048 1.1176)
			(layers "B.Cu" "B.Mask" "B.Paste")
			(net "P5V_B_1_VFB")
		)
		(pad "2" smd rect
			(at -1.999996 -2.449322 90)
			(size 0.3048 1.1176)
			(layers "B.Cu" "B.Mask" "B.Paste")
			(net "P5V_B_1_EN_R")
		)
		(pad "3" smd rect
			(at -1.500124 -2.449322 90)
			(size 0.3048 1.1176)
			(layers "B.Cu" "B.Mask" "B.Paste")
			(net "P5V_B_1_PGOOD")
		)
		(pad "4" smd rect
			(at -0.999998 -2.449322 90)
			(size 0.3048 1.1176)
			(layers "B.Cu" "B.Mask" "B.Paste")
			(net "P5V_B_1_VBST")
		)
		(pad "5" smd rect
			(at -0.500126 -2.449322 90)
			(size 0.3048 1.1176)
			(layers "B.Cu" "B.Mask" "B.Paste")
			(net "P5V_B_1_ROVP")
		)
		(pad "6" smd rect
			(at 0 -2.449322 90)
			(size 0.3048 1.1176)
			(layers "B.Cu" "B.Mask" "B.Paste")
			(net "P5V_B_1_LL")
		)
		(pad "7" smd rect
			(at 0.500126 -2.449322 90)
			(size 0.3048 1.1176)
			(layers "B.Cu" "B.Mask" "B.Paste")
			(net "P5V_B_1_LL")
		)
		(pad "8" smd rect
			(at 0.999998 -2.449322 90)
			(size 0.3048 1.1176)
			(layers "B.Cu" "B.Mask" "B.Paste")
			(net "P5V_B_1_LL")
		)
		(pad "9" smd rect
			(at 1.500124 -2.449322 90)
			(size 0.3048 1.1176)
			(layers "B.Cu" "B.Mask" "B.Paste")
			(net "P5V_B_1_LL")
		)
		(pad "10" smd rect
			(at 1.999996 -2.449322 90)
			(size 0.3048 1.1176)
			(layers "B.Cu" "B.Mask" "B.Paste")
			(net "P5V_B_1_LL")
		)
		(pad "11" smd rect
			(at 2.500122 -2.449322 90)
			(size 0.3048 1.1176)
			(layers "B.Cu" "B.Mask" "B.Paste")
			(net "P5V_B_1_LL")
		)
		(pad "12" smd rect
			(at 2.500122 2.449322 90)
			(size 0.3048 1.1176)
			(layers "B.Cu" "B.Mask" "B.Paste")
			(net "P12V_B_1_VIN_U31")
		)
		(pad "13" smd rect
			(at 1.999996 2.449322 90)
			(size 0.3048 1.1176)
			(layers "B.Cu" "B.Mask" "B.Paste")
			(net "P12V_B_1_VIN_U31")
		)
		(pad "14" smd rect
			(at 1.500124 2.449322 90)
			(size 0.3048 1.1176)
			(layers "B.Cu" "B.Mask" "B.Paste")
			(net "P12V_B_1_VIN_U31")
		)
		(pad "15" smd rect
			(at 0.999998 2.449322 90)
			(size 0.3048 1.1176)
			(layers "B.Cu" "B.Mask" "B.Paste")
			(net "P12V_B_1_VIN_U31")
		)
		(pad "16" smd rect
			(at 0.500126 2.449322 90)
			(size 0.3048 1.1176)
			(layers "B.Cu" "B.Mask" "B.Paste")
			(net "P12V_B_1_VIN_U31")
		)
		(pad "17" smd rect
			(at 0 2.449322 90)
			(size 0.3048 1.1176)
			(layers "B.Cu" "B.Mask" "B.Paste")
			(net "P12V_B_1_VIN_U31")
		)
		(pad "18" smd rect
			(at -0.500126 2.449322 90)
			(size 0.3048 1.1176)
			(layers "B.Cu" "B.Mask" "B.Paste")
			(net "P5V_B_1_VREG")
		)
		(pad "19" smd rect
			(at -0.999998 2.449322 90)
			(size 0.3048 1.1176)
			(layers "B.Cu" "B.Mask" "B.Paste")
			(net "P12V_B_1_VDD_U31")
		)
		(pad "20" smd rect
			(at -1.500124 2.449322 90)
			(size 0.3048 1.1176)
			(layers "B.Cu" "B.Mask" "B.Paste")
			(net "P5V_B_1_MODE")
		)
		(pad "21" smd rect
			(at -1.999996 2.449322 90)
			(size 0.3048 1.1176)
			(layers "B.Cu" "B.Mask" "B.Paste")
			(net "P5V_B_1_TRIP")
		)
		(pad "22" smd rect
			(at -2.500122 2.449322 90)
			(size 0.3048 1.1176)
			(layers "B.Cu" "B.Mask" "B.Paste")
			(net "P5V_B_1_RF")
		)
		(pad "23" smd custom
			(at 0 0 90)
			(size 0.83185 0.83185)
			(layers "B.Cu" "B.Mask" "B.Paste")
			(net "GND")
			(options
				(clearance outline)
				(anchor circle)
			)
			(primitives
				(gr_poly
					(pts
						(xy -2.7813 -1.6637) (xy -2.7813 -1.2954) (xy -3.048 -1.2954) (xy -3.048 -0.9525) (xy -2.7813 -0.9525)
						(xy -2.7813 0.9525) (xy -3.048 0.9525) (xy -3.048 1.2954) (xy -2.7813 1.2954) (xy -2.7813 1.6637)
						(xy 2.7813 1.6637) (xy 2.7813 1.2954) (xy 3.048 1.2954) (xy 3.048 0.9525) (xy 2.7813 0.9525) (xy 2.7813 -0.9525)
						(xy 3.048 -0.9525) (xy 3.048 -1.2954) (xy 2.7813 -1.2954) (xy 2.7813 -1.6637)
					)
					(width 0)
					(fill yes)
				)
			)
		)
	)
	(footprint ""
		(layer "B.Cu")
		(at 240.896394 -276.262592 -90)
		(property "Reference" "C700"
			(at 0 0 90)
			(layer "B.SilkS")
			(hide yes)
			(effects
				(font
					(size 1.27 1.27)
				)
				(justify mirror)
			)
		)
		(property "Value" "SCD1U16V2KX-3GP"
			(at -1.1811 -2.7051 270)
			(unlocked yes)
			(layer "B.Fab")
			(hide yes)
			(effects
				(font
					(size 1.016 1.016)
					(thickness 0.1524)
				)
				(justify mirror)
			)
		)
		(property "Device Type" "C402H22"
			(at -1.1811 -4.2291 270)
			(unlocked yes)
			(layer "B.Fab")
			(hide yes)
			(effects
				(font
					(size 1.016 1.016)
					(thickness 0.1524)
				)
				(justify mirror)
			)
		)
		(duplicate_pad_numbers_are_jumpers no)
		(fp_rect
			(start 0.4318 0.9525)
			(end -0.4318 -0.9525)
			(stroke
				(width 0)
				(type default)
			)
			(fill no)
			(layer "B.CrtYd")
		)
		(fp_rect
			(start 0.4318 0.9525)
			(end -0.4318 -0.9525)
			(stroke
				(width 0)
				(type default)
			)
			(fill no)
			(layer "B.Fab")
		)
		(pad "1" smd custom
			(at 0 -0.4445 90)
			(size 0.1524 0.1524)
			(layers "B.Cu" "B.Mask" "B.Paste")
			(net "P3V3_STBY_B")
			(options
				(clearance outline)
				(anchor circle)
			)
			(primitives
				(gr_poly
					(pts
						(arc
							(start 0.3048 0.2032)
							(mid 0.275042 0.275042)
							(end 0.2032 0.3048)
						)
						(arc
							(start -0.2032 0.3048)
							(mid -0.275042 0.275042)
							(end -0.3048 0.2032)
						)
						(arc
							(start -0.3048 -0.2032)
							(mid -0.275042 -0.275042)
							(end -0.2032 -0.3048)
						)
						(arc
							(start 0.2032 -0.3048)
							(mid 0.275042 -0.275042)
							(end 0.3048 -0.2032)
						)
					)
					(width 0)
					(fill yes)
				)
			)
		)
		(pad "2" smd custom
			(at 0 0.4445 90)
			(size 0.1524 0.1524)
			(layers "B.Cu" "B.Mask" "B.Paste")
			(net "GND")
			(options
				(clearance outline)
				(anchor circle)
			)
			(primitives
				(gr_poly
					(pts
						(arc
							(start 0.3048 0.2032)
							(mid 0.275042 0.275042)
							(end 0.2032 0.3048)
						)
						(arc
							(start -0.2032 0.3048)
							(mid -0.275042 0.275042)
							(end -0.3048 0.2032)
						)
						(arc
							(start -0.3048 -0.2032)
							(mid -0.275042 -0.275042)
							(end -0.2032 -0.3048)
						)
						(arc
							(start 0.2032 -0.3048)
							(mid 0.275042 -0.275042)
							(end 0.3048 -0.2032)
						)
					)
					(width 0)
					(fill yes)
				)
			)
		)
	)
	(footprint ""
		(layer "B.Cu")
		(at 31.307024 -230.911654 -90)
		(property "Reference" "C629"
			(at 0 0 90)
			(layer "B.SilkS")
			(hide yes)
			(effects
				(font
					(size 1.27 1.27)
				)
				(justify mirror)
			)
		)
		(property "Value" "SC470P50V2KX-3GP"
			(at -1.1811 -2.7051 270)
			(unlocked yes)
			(layer "B.Fab")
			(hide yes)
			(effects
				(font
					(size 1.016 1.016)
					(thickness 0.1524)
				)
				(justify mirror)
			)
		)
		(property "Device Type" "C402H22"
			(at -1.1811 -4.2291 270)
			(unlocked yes)
			(layer "B.Fab")
			(hide yes)
			(effects
				(font
					(size 1.016 1.016)
					(thickness 0.1524)
				)
				(justify mirror)
			)
		)
		(duplicate_pad_numbers_are_jumpers no)
		(fp_rect
			(start 0.4318 0.9525)
			(end -0.4318 -0.9525)
			(stroke
				(width 0)
				(type default)
			)
			(fill no)
			(layer "B.CrtYd")
		)
		(fp_rect
			(start 0.4318 0.9525)
			(end -0.4318 -0.9525)
			(stroke
				(width 0)
				(type default)
			)
			(fill no)
			(layer "B.Fab")
		)
		(pad "1" smd custom
			(at 0 -0.4445 90)
			(size 0.1524 0.1524)
			(layers "B.Cu" "B.Mask" "B.Paste")
			(net "P5V_B_1_LL_R")
			(options
				(clearance outline)
				(anchor circle)
			)
			(primitives
				(gr_poly
					(pts
						(arc
							(start 0.3048 0.2032)
							(mid 0.275042 0.275042)
							(end 0.2032 0.3048)
						)
						(arc
							(start -0.2032 0.3048)
							(mid -0.275042 0.275042)
							(end -0.3048 0.2032)
						)
						(arc
							(start -0.3048 -0.2032)
							(mid -0.275042 -0.275042)
							(end -0.2032 -0.3048)
						)
						(arc
							(start 0.2032 -0.3048)
							(mid 0.275042 -0.275042)
							(end 0.3048 -0.2032)
						)
					)
					(width 0)
					(fill yes)
				)
			)
		)
		(pad "2" smd custom
			(at 0 0.4445 90)
			(size 0.1524 0.1524)
			(layers "B.Cu" "B.Mask" "B.Paste")
			(net "P5V_B_1_VFB")
			(options
				(clearance outline)
				(anchor circle)
			)
			(primitives
				(gr_poly
					(pts
						(arc
							(start 0.3048 0.2032)
							(mid 0.275042 0.275042)
							(end 0.2032 0.3048)
						)
						(arc
							(start -0.2032 0.3048)
							(mid -0.275042 0.275042)
							(end -0.3048 0.2032)
						)
						(arc
							(start -0.3048 -0.2032)
							(mid -0.275042 -0.275042)
							(end -0.2032 -0.3048)
						)
						(arc
							(start 0.2032 -0.3048)
							(mid 0.275042 -0.275042)
							(end 0.3048 -0.2032)
						)
					)
					(width 0)
					(fill yes)
				)
			)
		)
	)
	(footprint ""
		(layer "B.Cu")
		(at 466.505798 -117.939058 -90)
		(property "Reference" "G7"
			(at 0 0 90)
			(layer "B.SilkS")
			(hide yes)
			(effects
				(font
					(size 1.27 1.27)
				)
				(justify mirror)
			)
		)
		(property "Value" "GAP-CLOSE-PWR-4-GP"
			(at 2.4638 -0.5461 270)
			(unlocked yes)
			(layer "B.Fab")
			(hide yes)
			(effects
				(font
					(size 1.016 1.016)
					(thickness 0.1524)
				)
				(justify mirror)
			)
		)
		(property "Device Type" "GAP-CLOSE-PWR-4"
			(at 2.4638 -2.0701 270)
			(unlocked yes)
			(layer "B.Fab")
			(hide yes)
			(effects
				(font
					(size 1.016 1.016)
					(thickness 0.1524)
				)
				(justify mirror)
			)
		)
		(duplicate_pad_numbers_are_jumpers no)
		(fp_rect
			(start 0.2794 0.254)
			(end -0.2794 -0.254)
			(stroke
				(width 0)
				(type default)
			)
			(fill no)
			(layer "B.CrtYd")
		)
		(fp_rect
			(start 0.2794 0.254)
			(end -0.2794 -0.254)
			(stroke
				(width 0)
				(type default)
			)
			(fill no)
			(layer "B.Fab")
		)
		(pad "1" smd rect
			(at 0.0635 0 90)
			(size 0.1778 0.254)
			(layers "B.Cu" "B.Mask" "B.Paste")
			(net "P5V_B_4")
		)
		(pad "2" smd rect
			(at -0.0635 0 90)
			(size 0.1778 0.254)
			(layers "B.Cu" "B.Mask" "B.Paste")
			(net "P5V_B_4_CC")
		)
	)
	(footprint ""
		(layer "B.Cu")
		(at 255.905 -290.576 90)
		(property "Reference" "R1174"
			(at 0 0 90)
			(layer "B.SilkS")
			(hide yes)
			(effects
				(font
					(size 1.27 1.27)
				)
				(justify mirror)
			)
		)
		(property "Value" "0R6J-3-GP"
			(at 0.0508 -4.8514 90)
			(unlocked yes)
			(layer "B.Fab")
			(hide yes)
			(effects
				(font
					(size 1.016 1.016)
					(thickness 0.1524)
				)
				(justify mirror)
			)
		)
		(property "Device Type" "R1206H28"
			(at 0 -6.3754 90)
			(unlocked yes)
			(layer "B.Fab")
			(hide yes)
			(effects
				(font
					(size 1.016 1.016)
					(thickness 0.1524)
				)
				(justify mirror)
			)
		)
		(duplicate_pad_numbers_are_jumpers no)
		(fp_line
			(start 1.016 -2.2352)
			(end -1.016 -2.2352)
			(stroke
				(width 0.1524)
				(type default)
			)
			(layer "B.SilkS")
		)
		(fp_line
			(start -1.016 -2.2352)
			(end -1.016 2.2352)
			(stroke
				(width 0.1524)
				(type default)
			)
			(layer "B.SilkS")
		)
		(fp_line
			(start 1.016 2.2352)
			(end 1.016 -2.2352)
			(stroke
				(width 0.1524)
				(type default)
			)
			(layer "B.SilkS")
		)
		(fp_line
			(start -1.016 2.2352)
			(end 1.016 2.2352)
			(stroke
				(width 0.1524)
				(type default)
			)
			(layer "B.SilkS")
		)
		(fp_rect
			(start 1.0922 2.3114)
			(end -1.0922 -2.3114)
			(stroke
				(width 0)
				(type default)
			)
			(fill no)
			(layer "B.CrtYd")
		)
		(fp_poly
			(pts
				(xy 1.0922 -2.3114) (xy -1.0922 -2.3114) (xy -1.0922 2.3114) (xy 1.0922 2.3114)
			)
			(stroke
				(width 0)
				(type default)
			)
			(fill no)
			(layer "B.Fab")
		)
		(pad "1" smd rect
			(at 0 -1.397 270)
			(size 1.651 1.27)
			(layers "B.Cu" "B.Mask" "B.Paste")
			(net "P3V3_STBY_VIN")
		)
		(pad "2" smd rect
			(at 0 1.397 270)
			(size 1.651 1.27)
			(layers "B.Cu" "B.Mask" "B.Paste")
			(net "P12V_B")
		)
	)
	(footprint ""
		(layer "B.Cu")
		(at 21.123402 -229.54615)
		(property "Reference" "G2"
			(at 0 0 0)
			(layer "B.SilkS")
			(hide yes)
			(effects
				(font
					(size 1.27 1.27)
				)
				(justify mirror)
			)
		)
		(property "Value" "COPPER-CLOSE-GP-U"
			(at -0.0762 -2.8702 0)
			(unlocked yes)
			(layer "B.Fab")
			(hide yes)
			(effects
				(font
					(size 1.016 1.016)
					(thickness 0.1524)
				)
				(justify mirror)
			)
		)
		(property "Device Type" "CON2C-U"
			(at -0.0762 -4.3942 0)
			(unlocked yes)
			(layer "B.Fab")
			(hide yes)
			(effects
				(font
					(size 1.016 1.016)
					(thickness 0.1524)
				)
				(justify mirror)
			)
		)
		(duplicate_pad_numbers_are_jumpers no)
		(fp_rect
			(start 0.9398 0.9652)
			(end -0.9398 -0.9652)
			(stroke
				(width 0)
				(type default)
			)
			(fill no)
			(layer "B.CrtYd")
		)
		(fp_rect
			(start 0.9398 0.9652)
			(end -0.9398 -0.9652)
			(stroke
				(width 0)
				(type default)
			)
			(fill no)
			(layer "B.Fab")
		)
		(pad "1" smd custom
			(at 0 -0.5334 180)
			(size 0.17145 0.17145)
			(layers "B.Cu" "B.Mask" "B.Paste")
			(net "AGND_P5V_B_1")
			(options
				(clearance outline)
				(anchor circle)
			)
			(primitives
				(gr_poly
					(pts
						(xy -0.127 -0.3429) (xy -0.127 -0.1651) (xy -0.635 0.3429) (xy 0.635 0.3429) (xy 0.127 -0.1651)
						(xy 0.127 -0.3429)
					)
					(width 0)
					(fill yes)
				)
			)
		)
		(pad "2" smd custom
			(at 0 0.5334 180)
			(size 0.17145 0.17145)
			(layers "B.Cu" "B.Mask" "B.Paste")
			(net "GND")
			(options
				(clearance outline)
				(anchor circle)
			)
			(primitives
				(gr_poly
					(pts
						(xy -0.635 -0.3429) (xy -0.127 0.1651) (xy -0.127 0.3429) (xy 0.127 0.3429) (xy 0.127 0.1651)
						(xy 0.635 -0.3429)
					)
					(width 0)
					(fill yes)
				)
			)
		)
	)
	(footprint ""
		(layer "B.Cu")
		(at 244.856 -274.955 -90)
		(property "Reference" "R1182"
			(at 0 0 90)
			(layer "B.SilkS")
			(hide yes)
			(effects
				(font
					(size 1.27 1.27)
				)
				(justify mirror)
			)
		)
		(property "Value" "3D01R5F-GP"
			(at 0 -8.9535 270)
			(unlocked yes)
			(layer "B.Fab")
			(hide yes)
			(effects
				(font
					(size 1.27 1.016)
					(thickness 0.1524)
				)
				(justify mirror)
			)
		)
		(property "Device Type" "R805H24"
			(at 0 -10.6299 270)
			(unlocked yes)
			(layer "B.Fab")
			(hide yes)
			(effects
				(font
					(size 1.27 1.016)
					(thickness 0.1524)
				)
				(justify mirror)
			)
		)
		(duplicate_pad_numbers_are_jumpers no)
		(fp_line
			(start -0.889 1.7018)
			(end -0.889 -0.508)
			(stroke
				(width 0.1524)
				(type default)
			)
			(layer "B.SilkS")
		)
		(fp_line
			(start 0.889 1.7018)
			(end -0.889 1.7018)
			(stroke
				(width 0.1524)
				(type default)
			)
			(layer "B.SilkS")
		)
		(fp_line
			(start 0.889 0.0762)
			(end 0.889 1.7018)
			(stroke
				(width 0.1524)
				(type default)
			)
			(layer "B.SilkS")
		)
		(fp_line
			(start -0.889 -1.7018)
			(end -0.889 -0.381)
			(stroke
				(width 0.1524)
				(type default)
			)
			(layer "B.SilkS")
		)
		(fp_line
			(start -0.889 -1.7018)
			(end 0.889 -1.7018)
			(stroke
				(width 0.1524)
				(type default)
			)
			(layer "B.SilkS")
		)
		(fp_line
			(start 0.889 -1.7018)
			(end 0.889 0.2794)
			(stroke
				(width 0.1524)
				(type default)
			)
			(layer "B.SilkS")
		)
		(fp_poly
			(pts
				(xy -0.9652 -1.778) (xy -0.9652 1.778) (xy 0.9652 1.778) (xy 0.9652 -1.778)
			)
			(stroke
				(width 0)
				(type default)
			)
			(fill no)
			(layer "B.CrtYd")
		)
		(fp_rect
			(start 0.9652 1.778)
			(end -0.9652 -1.778)
			(stroke
				(width 0)
				(type default)
			)
			(fill no)
			(layer "B.Fab")
		)
		(pad "1" smd rect
			(at 0 -0.9652 90)
			(size 1.397 1.143)
			(layers "B.Cu" "B.Mask" "B.Paste")
			(net "P3V3_STBY_SNB")
		)
		(pad "2" smd rect
			(at 0 0.9652 90)
			(size 1.397 1.143)
			(layers "B.Cu" "B.Mask" "B.Paste")
			(net "GND")
		)
	)
	(footprint ""
		(layer "B.Cu")
		(at 247.4468 -286.5882 180)
		(property "Reference" "R1181"
			(at 0 0 0)
			(layer "B.SilkS")
			(hide yes)
			(effects
				(font
					(size 1.27 1.27)
				)
				(justify mirror)
			)
		)
		(property "Value" "2KR2F-3-GP"
			(at -0.064008 -3.993896 180)
			(unlocked yes)
			(layer "B.Fab")
			(hide yes)
			(effects
				(font
					(size 1.016 1.016)
					(thickness 0.1524)
				)
				(justify mirror)
			)
		)
		(property "Device Type" "R402H16"
			(at -0.064008 -5.517896 180)
			(unlocked yes)
			(layer "B.Fab")
			(hide yes)
			(effects
				(font
					(size 1.016 1.016)
					(thickness 0.1524)
				)
				(justify mirror)
			)
		)
		(duplicate_pad_numbers_are_jumpers no)
		(fp_line
			(start 0.508 -0.9398)
			(end 0.508 0.9398)
			(stroke
				(width 0.1524)
				(type default)
			)
			(layer "B.SilkS")
		)
		(fp_line
			(start -0.508 -0.9398)
			(end 0.508 -0.9398)
			(stroke
				(width 0.1524)
				(type default)
			)
			(layer "B.SilkS")
		)
		(fp_rect
			(start 0.508 0.9398)
			(end -0.508 -0.9398)
			(stroke
				(width 0)
				(type default)
			)
			(fill no)
			(layer "B.CrtYd")
		)
		(fp_rect
			(start 0.508 0.9398)
			(end -0.508 -0.9398)
			(stroke
				(width 0)
				(type default)
			)
			(fill no)
			(layer "B.Fab")
		)
		(pad "1" smd custom
			(at 0 -0.4445)
			(size 0.1397 0.1397)
			(layers "B.Cu" "B.Mask" "B.Paste")
			(net "P3V3_STBY_SW")
			(options
				(clearance outline)
				(anchor circle)
			)
			(primitives
				(gr_poly
					(pts
						(arc
							(start -0.1778 0.2794)
							(mid -0.249642 0.249642)
							(end -0.2794 0.1778)
						)
						(arc
							(start -0.2794 -0.1778)
							(mid -0.249642 -0.249642)
							(end -0.1778 -0.2794)
						)
						(arc
							(start 0.1778 -0.2794)
							(mid 0.249642 -0.249642)
							(end 0.2794 -0.1778)
						)
						(arc
							(start 0.2794 0.1778)
							(mid 0.249642 0.249642)
							(end 0.1778 0.2794)
						)
					)
					(width 0)
					(fill yes)
				)
			)
		)
		(pad "2" smd custom
			(at 0 0.4445)
			(size 0.1397 0.1397)
			(layers "B.Cu" "B.Mask" "B.Paste")
			(net "P3V3_STBY_VFB_R")
			(options
				(clearance outline)
				(anchor circle)
			)
			(primitives
				(gr_poly
					(pts
						(arc
							(start -0.1778 0.2794)
							(mid -0.249642 0.249642)
							(end -0.2794 0.1778)
						)
						(arc
							(start -0.2794 -0.1778)
							(mid -0.249642 -0.249642)
							(end -0.1778 -0.2794)
						)
						(arc
							(start 0.1778 -0.2794)
							(mid 0.249642 -0.249642)
							(end 0.2794 -0.1778)
						)
						(arc
							(start 0.2794 0.1778)
							(mid 0.249642 0.249642)
							(end 0.1778 0.2794)
						)
					)
					(width 0)
					(fill yes)
				)
			)
		)
	)
	(footprint ""
		(layer "B.Cu")
		(at 130.250946 -362.04017)
		(property "Reference" "Q212"
			(at 0 0 0)
			(layer "B.SilkS")
			(hide yes)
			(effects
				(font
					(size 1.27 1.27)
				)
				(justify mirror)
			)
		)
		(property "Value" "2N7002K-2-GP"
			(at -0.127 -8.9662 0)
			(unlocked yes)
			(layer "B.Fab")
			(hide yes)
			(effects
				(font
					(size 1.016 1.016)
					(thickness 0.1524)
				)
				(justify mirror)
			)
		)
		(property "Device Type" "SOT23DGS2D4H44"
			(at -0.127 -10.4902 0)
			(unlocked yes)
			(layer "B.Fab")
			(hide yes)
			(effects
				(font
					(size 1.016 1.016)
					(thickness 0.1524)
				)
				(justify mirror)
			)
		)
		(duplicate_pad_numbers_are_jumpers no)
		(fp_line
			(start -1.651 -1.778)
			(end 1.651 -1.778)
			(stroke
				(width 0.1524)
				(type default)
			)
			(layer "B.SilkS")
		)
		(fp_line
			(start -1.651 1.778)
			(end -1.651 -1.778)
			(stroke
				(width 0.1524)
				(type default)
			)
			(layer "B.SilkS")
		)
		(fp_line
			(start 1.651 -1.778)
			(end 1.651 1.778)
			(stroke
				(width 0.1524)
				(type default)
			)
			(layer "B.SilkS")
		)
		(fp_line
			(start 1.651 1.778)
			(end -1.651 1.778)
			(stroke
				(width 0.1524)
				(type default)
			)
			(layer "B.SilkS")
		)
		(fp_poly
			(pts
				(xy 1.778 1.8796) (xy 1.778 -1.8796) (xy -1.778 -1.8796) (xy -1.778 1.8796)
			)
			(stroke
				(width 0)
				(type default)
			)
			(fill no)
			(layer "B.CrtYd")
		)
		(fp_poly
			(pts
				(xy 1.778 1.8796) (xy 1.778 -1.8796) (xy -1.778 -1.8796) (xy -1.778 1.8796)
			)
			(stroke
				(width 0)
				(type default)
			)
			(fill no)
			(layer "B.Fab")
		)
		(pad "D" smd custom
			(at 0 -0.9525 180)
			(size 0.1905 0.1905)
			(layers "B.Cu" "B.Mask" "B.Paste")
			(net "GATE_FAN1")
			(options
				(clearance outline)
				(anchor circle)
			)
			(primitives
				(gr_poly
					(pts
						(arc
							(start -0.1778 -0.5715)
							(mid -0.321484 -0.511984)
							(end -0.381 -0.3683)
						)
						(arc
							(start -0.381 0.3683)
							(mid -0.321484 0.511984)
							(end -0.1778 0.5715)
						)
						(arc
							(start 0.1778 0.5715)
							(mid 0.321484 0.511984)
							(end 0.381 0.3683)
						)
						(arc
							(start 0.381 -0.3683)
							(mid 0.321484 -0.511984)
							(end 0.1778 -0.5715)
						)
					)
					(width 0)
					(fill yes)
				)
			)
		)
		(pad "G" smd custom
			(at 0.98425 0.9525 180)
			(size 0.1905 0.1905)
			(layers "B.Cu" "B.Mask" "B.Paste")
			(net "FAN_EN")
			(options
				(clearance outline)
				(anchor circle)
			)
			(primitives
				(gr_poly
					(pts
						(arc
							(start -0.1778 -0.5715)
							(mid -0.321484 -0.511984)
							(end -0.381 -0.3683)
						)
						(arc
							(start -0.381 0.3683)
							(mid -0.321484 0.511984)
							(end -0.1778 0.5715)
						)
						(arc
							(start 0.1778 0.5715)
							(mid 0.321484 0.511984)
							(end 0.381 0.3683)
						)
						(arc
							(start 0.381 -0.3683)
							(mid 0.321484 -0.511984)
							(end 0.1778 -0.5715)
						)
					)
					(width 0)
					(fill yes)
				)
			)
		)
		(pad "S" smd custom
			(at -0.98425 0.9525 180)
			(size 0.1905 0.1905)
			(layers "B.Cu" "B.Mask" "B.Paste")
			(net "GND")
			(options
				(clearance outline)
				(anchor circle)
			)
			(primitives
				(gr_poly
					(pts
						(arc
							(start -0.1778 -0.5715)
							(mid -0.321484 -0.511984)
							(end -0.381 -0.3683)
						)
						(arc
							(start -0.381 0.3683)
							(mid -0.321484 0.511984)
							(end -0.1778 0.5715)
						)
						(arc
							(start 0.1778 0.5715)
							(mid 0.321484 0.511984)
							(end 0.381 0.3683)
						)
						(arc
							(start 0.381 -0.3683)
							(mid 0.321484 -0.511984)
							(end 0.1778 -0.5715)
						)
					)
					(width 0)
					(fill yes)
				)
			)
		)
	)
	(footprint ""
		(layer "B.Cu")
		(at 71.52386 -117.167406 180)
		(property "Reference" "C652"
			(at 0 0 0)
			(layer "B.SilkS")
			(hide yes)
			(effects
				(font
					(size 1.27 1.27)
				)
				(justify mirror)
			)
		)
		(property "Value" "SC10U16V5KX-7-GP-U"
			(at 0.0762 -6.1214 180)
			(unlocked yes)
			(layer "B.Fab")
			(hide yes)
			(effects
				(font
					(size 1.016 1.016)
					(thickness 0.1524)
				)
				(justify mirror)
			)
		)
		(property "Device Type" "C805H58"
			(at 0.0762 -8.1534 180)
			(unlocked yes)
			(layer "B.Fab")
			(hide yes)
			(effects
				(font
					(size 1.016 1.016)
					(thickness 0.1524)
				)
				(justify mirror)
			)
		)
		(duplicate_pad_numbers_are_jumpers no)
		(fp_line
			(start -0.635 0)
			(end 0.635 0)
			(stroke
				(width 0.508)
				(type default)
			)
			(layer "B.SilkS")
		)
		(fp_rect
			(start 0.9652 1.778)
			(end -0.9652 -1.778)
			(stroke
				(width 0)
				(type default)
			)
			(fill no)
			(layer "B.CrtYd")
		)
		(fp_poly
			(pts
				(xy 0.9652 -1.778) (xy -0.9652 -1.778) (xy -0.9652 1.778) (xy 0.9652 1.778)
			)
			(stroke
				(width 0)
				(type default)
			)
			(fill no)
			(layer "B.Fab")
		)
		(pad "1" smd rect
			(at 0 -0.9652)
			(size 1.397 1.143)
			(layers "B.Cu" "B.Mask" "B.Paste")
			(net "P5V_B_2")
		)
		(pad "2" smd rect
			(at 0 0.9652)
			(size 1.397 1.143)
			(layers "B.Cu" "B.Mask" "B.Paste")
			(net "GND")
		)
	)
	(footprint ""
		(layer "B.Cu")
		(at 15.814802 -223.27235 180)
		(property "Reference" "C620"
			(at 0 0 0)
			(layer "B.SilkS")
			(hide yes)
			(effects
				(font
					(size 1.27 1.27)
				)
				(justify mirror)
			)
		)
		(property "Value" "SCD1U16V2KX-3GP"
			(at -1.1811 -2.7051 180)
			(unlocked yes)
			(layer "B.Fab")
			(hide yes)
			(effects
				(font
					(size 1.016 1.016)
					(thickness 0.1524)
				)
				(justify mirror)
			)
		)
		(property "Device Type" "C402H22"
			(at -1.1811 -4.2291 180)
			(unlocked yes)
			(layer "B.Fab")
			(hide yes)
			(effects
				(font
					(size 1.016 1.016)
					(thickness 0.1524)
				)
				(justify mirror)
			)
		)
		(duplicate_pad_numbers_are_jumpers no)
		(fp_rect
			(start 0.4318 0.9525)
			(end -0.4318 -0.9525)
			(stroke
				(width 0)
				(type default)
			)
			(fill no)
			(layer "B.CrtYd")
		)
		(fp_rect
			(start 0.4318 0.9525)
			(end -0.4318 -0.9525)
			(stroke
				(width 0)
				(type default)
			)
			(fill no)
			(layer "B.Fab")
		)
		(pad "1" smd custom
			(at 0 -0.4445)
			(size 0.1524 0.1524)
			(layers "B.Cu" "B.Mask" "B.Paste")
			(net "P12V_B_1_VIN_U31")
			(options
				(clearance outline)
				(anchor circle)
			)
			(primitives
				(gr_poly
					(pts
						(arc
							(start 0.3048 0.2032)
							(mid 0.275042 0.275042)
							(end 0.2032 0.3048)
						)
						(arc
							(start -0.2032 0.3048)
							(mid -0.275042 0.275042)
							(end -0.3048 0.2032)
						)
						(arc
							(start -0.3048 -0.2032)
							(mid -0.275042 -0.275042)
							(end -0.2032 -0.3048)
						)
						(arc
							(start 0.2032 -0.3048)
							(mid 0.275042 -0.275042)
							(end 0.3048 -0.2032)
						)
					)
					(width 0)
					(fill yes)
				)
			)
		)
		(pad "2" smd custom
			(at 0 0.4445)
			(size 0.1524 0.1524)
			(layers "B.Cu" "B.Mask" "B.Paste")
			(net "GND")
			(options
				(clearance outline)
				(anchor circle)
			)
			(primitives
				(gr_poly
					(pts
						(arc
							(start 0.3048 0.2032)
							(mid 0.275042 0.275042)
							(end 0.2032 0.3048)
						)
						(arc
							(start -0.2032 0.3048)
							(mid -0.275042 0.275042)
							(end -0.3048 0.2032)
						)
						(arc
							(start -0.3048 -0.2032)
							(mid -0.275042 -0.275042)
							(end -0.2032 -0.3048)
						)
						(arc
							(start 0.2032 -0.3048)
							(mid 0.275042 -0.275042)
							(end 0.3048 -0.2032)
						)
					)
					(width 0)
					(fill yes)
				)
			)
		)
	)
	(footprint ""
		(layer "B.Cu")
		(at 22.591014 -229.543864 180)
		(property "Reference" "R1113"
			(at 0 0 0)
			(layer "B.SilkS")
			(hide yes)
			(effects
				(font
					(size 1.27 1.27)
				)
				(justify mirror)
			)
		)
		(property "Value" "10KR2F-2-GP"
			(at -0.064008 -3.993896 180)
			(unlocked yes)
			(layer "B.Fab")
			(hide yes)
			(effects
				(font
					(size 1.016 1.016)
					(thickness 0.1524)
				)
				(justify mirror)
			)
		)
		(property "Device Type" "R402H16"
			(at -0.064008 -5.517896 180)
			(unlocked yes)
			(layer "B.Fab")
			(hide yes)
			(effects
				(font
					(size 1.016 1.016)
					(thickness 0.1524)
				)
				(justify mirror)
			)
		)
		(duplicate_pad_numbers_are_jumpers no)
		(fp_line
			(start 0.508 -0.9398)
			(end 0.508 0.9398)
			(stroke
				(width 0.1524)
				(type default)
			)
			(layer "B.SilkS")
		)
		(fp_line
			(start -0.508 -0.9398)
			(end 0.508 -0.9398)
			(stroke
				(width 0.1524)
				(type default)
			)
			(layer "B.SilkS")
		)
		(fp_rect
			(start 0.508 0.9398)
			(end -0.508 -0.9398)
			(stroke
				(width 0)
				(type default)
			)
			(fill no)
			(layer "B.CrtYd")
		)
		(fp_rect
			(start 0.508 0.9398)
			(end -0.508 -0.9398)
			(stroke
				(width 0)
				(type default)
			)
			(fill no)
			(layer "B.Fab")
		)
		(pad "1" smd custom
			(at 0 -0.4445)
			(size 0.1397 0.1397)
			(layers "B.Cu" "B.Mask" "B.Paste")
			(net "P5V_B_1_VFB")
			(options
				(clearance outline)
				(anchor circle)
			)
			(primitives
				(gr_poly
					(pts
						(arc
							(start -0.1778 0.2794)
							(mid -0.249642 0.249642)
							(end -0.2794 0.1778)
						)
						(arc
							(start -0.2794 -0.1778)
							(mid -0.249642 -0.249642)
							(end -0.1778 -0.2794)
						)
						(arc
							(start 0.1778 -0.2794)
							(mid 0.249642 -0.249642)
							(end 0.2794 -0.1778)
						)
						(arc
							(start 0.2794 0.1778)
							(mid 0.249642 0.249642)
							(end 0.1778 0.2794)
						)
					)
					(width 0)
					(fill yes)
				)
			)
		)
		(pad "2" smd custom
			(at 0 0.4445)
			(size 0.1397 0.1397)
			(layers "B.Cu" "B.Mask" "B.Paste")
			(net "AGND_P5V_B_1")
			(options
				(clearance outline)
				(anchor circle)
			)
			(primitives
				(gr_poly
					(pts
						(arc
							(start -0.1778 0.2794)
							(mid -0.249642 0.249642)
							(end -0.2794 0.1778)
						)
						(arc
							(start -0.2794 -0.1778)
							(mid -0.249642 -0.249642)
							(end -0.1778 -0.2794)
						)
						(arc
							(start 0.1778 -0.2794)
							(mid 0.249642 -0.249642)
							(end 0.2794 -0.1778)
						)
						(arc
							(start 0.2794 0.1778)
							(mid 0.249642 0.249642)
							(end 0.1778 0.2794)
						)
					)
					(width 0)
					(fill yes)
				)
			)
		)
	)
	(footprint ""
		(layer "B.Cu")
		(at 441.171584 -119.375428 90)
		(property "Reference" "R1166"
			(at 0 0 90)
			(layer "B.SilkS")
			(hide yes)
			(effects
				(font
					(size 1.27 1.27)
				)
				(justify mirror)
			)
		)
		(property "Value" "71K5R2F-GP"
			(at -0.064008 -3.993896 90)
			(unlocked yes)
			(layer "B.Fab")
			(hide yes)
			(effects
				(font
					(size 1.016 1.016)
					(thickness 0.1524)
				)
				(justify mirror)
			)
		)
		(property "Device Type" "R402H16"
			(at -0.064008 -5.517896 90)
			(unlocked yes)
			(layer "B.Fab")
			(hide yes)
			(effects
				(font
					(size 1.016 1.016)
					(thickness 0.1524)
				)
				(justify mirror)
			)
		)
		(duplicate_pad_numbers_are_jumpers no)
		(fp_line
			(start 0.508 -0.9398)
			(end 0.508 0.9398)
			(stroke
				(width 0.1524)
				(type default)
			)
			(layer "B.SilkS")
		)
		(fp_line
			(start -0.508 -0.9398)
			(end 0.508 -0.9398)
			(stroke
				(width 0.1524)
				(type default)
			)
			(layer "B.SilkS")
		)
		(fp_rect
			(start 0.508 0.9398)
			(end -0.508 -0.9398)
			(stroke
				(width 0)
				(type default)
			)
			(fill no)
			(layer "B.CrtYd")
		)
		(fp_rect
			(start 0.508 0.9398)
			(end -0.508 -0.9398)
			(stroke
				(width 0)
				(type default)
			)
			(fill no)
			(layer "B.Fab")
		)
		(pad "1" smd custom
			(at 0 -0.4445 270)
			(size 0.1397 0.1397)
			(layers "B.Cu" "B.Mask" "B.Paste")
			(net "P5V_B_4_VFB")
			(options
				(clearance outline)
				(anchor circle)
			)
			(primitives
				(gr_poly
					(pts
						(arc
							(start -0.1778 0.2794)
							(mid -0.249642 0.249642)
							(end -0.2794 0.1778)
						)
						(arc
							(start -0.2794 -0.1778)
							(mid -0.249642 -0.249642)
							(end -0.1778 -0.2794)
						)
						(arc
							(start 0.1778 -0.2794)
							(mid 0.249642 -0.249642)
							(end 0.2794 -0.1778)
						)
						(arc
							(start 0.2794 0.1778)
							(mid 0.249642 0.249642)
							(end 0.1778 0.2794)
						)
					)
					(width 0)
					(fill yes)
				)
			)
		)
		(pad "2" smd custom
			(at 0 0.4445 270)
			(size 0.1397 0.1397)
			(layers "B.Cu" "B.Mask" "B.Paste")
			(net "P5V_B_4_VFB_R")
			(options
				(clearance outline)
				(anchor circle)
			)
			(primitives
				(gr_poly
					(pts
						(arc
							(start -0.1778 0.2794)
							(mid -0.249642 0.249642)
							(end -0.2794 0.1778)
						)
						(arc
							(start -0.2794 -0.1778)
							(mid -0.249642 -0.249642)
							(end -0.1778 -0.2794)
						)
						(arc
							(start 0.1778 -0.2794)
							(mid 0.249642 -0.249642)
							(end 0.2794 -0.1778)
						)
						(arc
							(start 0.2794 0.1778)
							(mid 0.249642 0.249642)
							(end 0.1778 0.2794)
						)
					)
					(width 0)
					(fill yes)
				)
			)
		)
	)
	(footprint ""
		(layer "B.Cu")
		(at 260.168136 -279.828244)
		(property "Reference" "G9"
			(at 0 0 0)
			(layer "B.SilkS")
			(hide yes)
			(effects
				(font
					(size 1.27 1.27)
				)
				(justify mirror)
			)
		)
		(property "Value" "COPPER-CLOSE-GP-U"
			(at -0.0762 -2.8702 0)
			(unlocked yes)
			(layer "B.Fab")
			(hide yes)
			(effects
				(font
					(size 1.016 1.016)
					(thickness 0.1524)
				)
				(justify mirror)
			)
		)
		(property "Device Type" "CON2C-U"
			(at -0.0762 -4.3942 0)
			(unlocked yes)
			(layer "B.Fab")
			(hide yes)
			(effects
				(font
					(size 1.016 1.016)
					(thickness 0.1524)
				)
				(justify mirror)
			)
		)
		(duplicate_pad_numbers_are_jumpers no)
		(fp_rect
			(start 0.9398 0.9652)
			(end -0.9398 -0.9652)
			(stroke
				(width 0)
				(type default)
			)
			(fill no)
			(layer "B.CrtYd")
		)
		(fp_rect
			(start 0.9398 0.9652)
			(end -0.9398 -0.9652)
			(stroke
				(width 0)
				(type default)
			)
			(fill no)
			(layer "B.Fab")
		)
		(pad "1" smd custom
			(at 0 -0.5334 180)
			(size 0.17145 0.17145)
			(layers "B.Cu" "B.Mask" "B.Paste")
			(net "AGND_P3V3_STBY")
			(options
				(clearance outline)
				(anchor circle)
			)
			(primitives
				(gr_poly
					(pts
						(xy -0.127 -0.3429) (xy -0.127 -0.1651) (xy -0.635 0.3429) (xy 0.635 0.3429) (xy 0.127 -0.1651)
						(xy 0.127 -0.3429)
					)
					(width 0)
					(fill yes)
				)
			)
		)
		(pad "2" smd custom
			(at 0 0.5334 180)
			(size 0.17145 0.17145)
			(layers "B.Cu" "B.Mask" "B.Paste")
			(net "GND")
			(options
				(clearance outline)
				(anchor circle)
			)
			(primitives
				(gr_poly
					(pts
						(xy -0.635 -0.3429) (xy -0.127 0.1651) (xy -0.127 0.3429) (xy 0.127 0.3429) (xy 0.127 0.1651)
						(xy 0.635 -0.3429)
					)
					(width 0)
					(fill yes)
				)
			)
		)
	)
	(footprint ""
		(layer "B.Cu")
		(at 461.349852 -118.014242 180)
		(property "Reference" "C686"
			(at 0 0 0)
			(layer "B.SilkS")
			(hide yes)
			(effects
				(font
					(size 1.27 1.27)
				)
				(justify mirror)
			)
		)
		(property "Value" "SC10U16V5KX-7-GP-U"
			(at 0.0762 -6.1214 180)
			(unlocked yes)
			(layer "B.Fab")
			(hide yes)
			(effects
				(font
					(size 1.016 1.016)
					(thickness 0.1524)
				)
				(justify mirror)
			)
		)
		(property "Device Type" "C805H58"
			(at 0.0762 -8.1534 180)
			(unlocked yes)
			(layer "B.Fab")
			(hide yes)
			(effects
				(font
					(size 1.016 1.016)
					(thickness 0.1524)
				)
				(justify mirror)
			)
		)
		(duplicate_pad_numbers_are_jumpers no)
		(fp_line
			(start -0.635 0)
			(end 0.635 0)
			(stroke
				(width 0.508)
				(type default)
			)
			(layer "B.SilkS")
		)
		(fp_rect
			(start 0.9652 1.778)
			(end -0.9652 -1.778)
			(stroke
				(width 0)
				(type default)
			)
			(fill no)
			(layer "B.CrtYd")
		)
		(fp_poly
			(pts
				(xy 0.9652 -1.778) (xy -0.9652 -1.778) (xy -0.9652 1.778) (xy 0.9652 1.778)
			)
			(stroke
				(width 0)
				(type default)
			)
			(fill no)
			(layer "B.Fab")
		)
		(pad "1" smd rect
			(at 0 -0.9652)
			(size 1.397 1.143)
			(layers "B.Cu" "B.Mask" "B.Paste")
			(net "P5V_B_4")
		)
		(pad "2" smd rect
			(at 0 0.9652)
			(size 1.397 1.143)
			(layers "B.Cu" "B.Mask" "B.Paste")
			(net "GND")
		)
	)
	(footprint ""
		(layer "B.Cu")
		(at 10.353802 -223.01835 180)
		(property "Reference" "C619"
			(at 0 0 0)
			(layer "B.SilkS")
			(hide yes)
			(effects
				(font
					(size 1.27 1.27)
				)
				(justify mirror)
			)
		)
		(property "Value" "SC10U16V5KX-7-GP-U"
			(at 0.0762 -6.1214 180)
			(unlocked yes)
			(layer "B.Fab")
			(hide yes)
			(effects
				(font
					(size 1.016 1.016)
					(thickness 0.1524)
				)
				(justify mirror)
			)
		)
		(property "Device Type" "C805H58"
			(at 0.0762 -8.1534 180)
			(unlocked yes)
			(layer "B.Fab")
			(hide yes)
			(effects
				(font
					(size 1.016 1.016)
					(thickness 0.1524)
				)
				(justify mirror)
			)
		)
		(duplicate_pad_numbers_are_jumpers no)
		(fp_line
			(start -0.635 0)
			(end 0.635 0)
			(stroke
				(width 0.508)
				(type default)
			)
			(layer "B.SilkS")
		)
		(fp_rect
			(start 0.9652 1.778)
			(end -0.9652 -1.778)
			(stroke
				(width 0)
				(type default)
			)
			(fill no)
			(layer "B.CrtYd")
		)
		(fp_poly
			(pts
				(xy 0.9652 -1.778) (xy -0.9652 -1.778) (xy -0.9652 1.778) (xy 0.9652 1.778)
			)
			(stroke
				(width 0)
				(type default)
			)
			(fill no)
			(layer "B.Fab")
		)
		(pad "1" smd rect
			(at 0 -0.9652)
			(size 1.397 1.143)
			(layers "B.Cu" "B.Mask" "B.Paste")
			(net "P12V_B_1_VIN_U31")
		)
		(pad "2" smd rect
			(at 0 0.9652)
			(size 1.397 1.143)
			(layers "B.Cu" "B.Mask" "B.Paste")
			(net "GND")
		)
	)
	(footprint ""
		(layer "B.Cu")
		(at 49.29886 -119.453406 90)
		(property "Reference" "C648"
			(at 0 0 90)
			(layer "B.SilkS")
			(hide yes)
			(effects
				(font
					(size 1.27 1.27)
				)
				(justify mirror)
			)
		)
		(property "Value" "SC68P50V2JN-2-GP"
			(at -1.1811 -2.7051 90)
			(unlocked yes)
			(layer "B.Fab")
			(hide yes)
			(effects
				(font
					(size 1.016 1.016)
					(thickness 0.1524)
				)
				(justify mirror)
			)
		)
		(property "Device Type" "C402H22"
			(at -1.1811 -4.2291 90)
			(unlocked yes)
			(layer "B.Fab")
			(hide yes)
			(effects
				(font
					(size 1.016 1.016)
					(thickness 0.1524)
				)
				(justify mirror)
			)
		)
		(duplicate_pad_numbers_are_jumpers no)
		(fp_rect
			(start 0.4318 0.9525)
			(end -0.4318 -0.9525)
			(stroke
				(width 0)
				(type default)
			)
			(fill no)
			(layer "B.CrtYd")
		)
		(fp_rect
			(start 0.4318 0.9525)
			(end -0.4318 -0.9525)
			(stroke
				(width 0)
				(type default)
			)
			(fill no)
			(layer "B.Fab")
		)
		(pad "1" smd custom
			(at 0 -0.4445 270)
			(size 0.1524 0.1524)
			(layers "B.Cu" "B.Mask" "B.Paste")
			(net "P5V_B_2_VFB")
			(options
				(clearance outline)
				(anchor circle)
			)
			(primitives
				(gr_poly
					(pts
						(arc
							(start 0.3048 0.2032)
							(mid 0.275042 0.275042)
							(end 0.2032 0.3048)
						)
						(arc
							(start -0.2032 0.3048)
							(mid -0.275042 0.275042)
							(end -0.3048 0.2032)
						)
						(arc
							(start -0.3048 -0.2032)
							(mid -0.275042 -0.275042)
							(end -0.2032 -0.3048)
						)
						(arc
							(start 0.2032 -0.3048)
							(mid 0.275042 -0.275042)
							(end 0.3048 -0.2032)
						)
					)
					(width 0)
					(fill yes)
				)
			)
		)
		(pad "2" smd custom
			(at 0 0.4445 270)
			(size 0.1524 0.1524)
			(layers "B.Cu" "B.Mask" "B.Paste")
			(net "P5V_B_2_VFB_R")
			(options
				(clearance outline)
				(anchor circle)
			)
			(primitives
				(gr_poly
					(pts
						(arc
							(start 0.3048 0.2032)
							(mid 0.275042 0.275042)
							(end 0.2032 0.3048)
						)
						(arc
							(start -0.2032 0.3048)
							(mid -0.275042 0.275042)
							(end -0.3048 0.2032)
						)
						(arc
							(start -0.3048 -0.2032)
							(mid -0.275042 -0.275042)
							(end -0.2032 -0.3048)
						)
						(arc
							(start 0.2032 -0.3048)
							(mid 0.275042 -0.275042)
							(end 0.3048 -0.2032)
						)
					)
					(width 0)
					(fill yes)
				)
			)
		)
	)
	(footprint ""
		(layer "B.Cu")
		(at 221.383606 -329.057)
		(property "Reference" "C567"
			(at 0 0 0)
			(layer "B.SilkS")
			(hide yes)
			(effects
				(font
					(size 1.27 1.27)
				)
				(justify mirror)
			)
		)
		(property "Value" "SC22U25V6KX-2-GP-U"
			(at 2.860802 -5.279644 0)
			(unlocked yes)
			(layer "B.Fab")
			(hide yes)
			(effects
				(font
					(size 1.016 1.016)
					(thickness 0.1524)
				)
				(justify mirror)
			)
		)
		(property "Device Type" "C1206-TO0D3H75"
			(at 2.860802 -6.803644 0)
			(unlocked yes)
			(layer "B.Fab")
			(hide yes)
			(effects
				(font
					(size 1.016 1.016)
					(thickness 0.1524)
				)
				(justify mirror)
			)
		)
		(duplicate_pad_numbers_are_jumpers no)
		(fp_line
			(start -1.3081 -2.3749)
			(end -1.3081 2.3749)
			(stroke
				(width 0.1524)
				(type default)
			)
			(layer "B.SilkS")
		)
		(fp_line
			(start -1.3081 2.3749)
			(end 1.3081 2.3749)
			(stroke
				(width 0.1524)
				(type default)
			)
			(layer "B.SilkS")
		)
		(fp_line
			(start 1.3081 -2.3749)
			(end -1.3081 -2.3749)
			(stroke
				(width 0.1524)
				(type default)
			)
			(layer "B.SilkS")
		)
		(fp_line
			(start 1.3081 2.3749)
			(end 1.3081 -2.3749)
			(stroke
				(width 0.1524)
				(type default)
			)
			(layer "B.SilkS")
		)
		(fp_rect
			(start 0.8001 1.6002)
			(end -0.8001 -1.6002)
			(stroke
				(width 0)
				(type default)
			)
			(fill no)
			(layer "B.CrtYd")
		)
		(fp_poly
			(pts
				(xy 1.5621 2.4511) (xy 1.5621 1.6002) (xy -0.8001 1.6002) (xy -0.8001 -1.6002) (xy 0.8001 -1.6002)
				(xy 0.8001 1.5875) (xy 1.5621 1.5875) (xy 1.5621 -2.4511) (xy -1.5621 -2.4511) (xy -1.5621 2.4511)
			)
			(stroke
				(width 0)
				(type default)
			)
			(fill no)
			(layer "B.CrtYd")
		)
		(fp_rect
			(start 1.5621 2.4511)
			(end -1.5621 -2.4511)
			(stroke
				(width 0)
				(type default)
			)
			(fill no)
			(layer "B.Fab")
		)
		(pad "1" smd rect
			(at 0 -1.392936 180)
			(size 2.1082 1.4478)
			(layers "B.Cu" "B.Mask" "B.Paste")
			(net "P12V_IN")
		)
		(pad "2" smd rect
			(at 0 1.392936 180)
			(size 2.1082 1.4478)
			(layers "B.Cu" "B.Mask" "B.Paste")
			(net "GND")
		)
	)
	(footprint ""
		(layer "B.Cu")
		(at 41.0972 -229.94239 180)
		(property "Reference" "TC13"
			(at 0 0 0)
			(layer "B.SilkS")
			(hide yes)
			(effects
				(font
					(size 1.27 1.27)
				)
				(justify mirror)
			)
		)
		(property "Value" "ST220U10VDM-LGP"
			(at 0 -9.6012 180)
			(unlocked yes)
			(layer "B.Fab")
			(hide yes)
			(effects
				(font
					(size 1.016 1.016)
					(thickness 0.1524)
				)
				(justify mirror)
			)
		)
		(property "Device Type" "CT7343H119"
			(at 0 -11.1252 180)
			(unlocked yes)
			(layer "B.Fab")
			(hide yes)
			(effects
				(font
					(size 1.016 1.016)
					(thickness 0.1524)
				)
				(justify mirror)
			)
		)
		(duplicate_pad_numbers_are_jumpers no)
		(fp_line
			(start 2.286 4.8768)
			(end 2.286 2.032)
			(stroke
				(width 0.1524)
				(type default)
			)
			(layer "B.SilkS")
		)
		(fp_line
			(start 2.286 -4.8768)
			(end 2.286 -2.032)
			(stroke
				(width 0.1524)
				(type default)
			)
			(layer "B.SilkS")
		)
		(fp_line
			(start -2.1082 -4.699)
			(end 2.1082 -4.699)
			(stroke
				(width 0.508)
				(type default)
			)
			(layer "B.SilkS")
		)
		(fp_line
			(start -2.286 4.8768)
			(end 2.286 4.8768)
			(stroke
				(width 0.1524)
				(type default)
			)
			(layer "B.SilkS")
		)
		(fp_line
			(start -2.286 2.032)
			(end -2.286 4.8768)
			(stroke
				(width 0.1524)
				(type default)
			)
			(layer "B.SilkS")
		)
		(fp_line
			(start -2.286 -2.032)
			(end -2.286 -4.8768)
			(stroke
				(width 0.1524)
				(type default)
			)
			(layer "B.SilkS")
		)
		(fp_line
			(start -2.286 -4.8768)
			(end 2.286 -4.8768)
			(stroke
				(width 0.1524)
				(type default)
			)
			(layer "B.SilkS")
		)
		(fp_rect
			(start 2.1463 3.6449)
			(end -2.1463 -3.6449)
			(stroke
				(width 0)
				(type default)
			)
			(fill no)
			(layer "B.CrtYd")
		)
		(fp_poly
			(pts
				(xy 2.54 4.953) (xy 2.54 4.2926) (xy 3.81 4.2926) (xy 3.81 -4.2926) (xy 2.54 -4.2926) (xy 2.54 -4.953)
				(xy -2.54 -4.953) (xy -2.54 -4.2926) (xy -3.81 -4.2926) (xy -3.81 -1.6256) (xy -2.1463 -1.6256)
				(xy -2.1463 -3.6449) (xy 2.1463 -3.6449) (xy 2.1463 3.6449) (xy -2.1463 3.6449) (xy -2.1463 -1.6129)
				(xy -3.81 -1.6129) (xy -3.81 4.2926) (xy -2.54 4.2926) (xy -2.54 4.953)
			)
			(stroke
				(width 0)
				(type default)
			)
			(fill no)
			(layer "B.CrtYd")
		)
		(fp_rect
			(start 3.81 4.2926)
			(end 2.54 -4.2926)
			(stroke
				(width 0)
				(type default)
			)
			(fill no)
			(layer "B.Fab")
		)
		(fp_rect
			(start 2.54 4.953)
			(end -2.54 -4.953)
			(stroke
				(width 0)
				(type default)
			)
			(fill no)
			(layer "B.Fab")
		)
		(fp_rect
			(start -2.54 4.2926)
			(end -3.81 -4.2926)
			(stroke
				(width 0)
				(type default)
			)
			(fill no)
			(layer "B.Fab")
		)
		(pad "1" smd rect
			(at 0 -3.1496)
			(size 2.413 2.286)
			(layers "B.Cu" "B.Mask" "B.Paste")
			(net "P5V_B_1")
		)
		(pad "2" smd rect
			(at 0 3.1496)
			(size 2.413 2.286)
			(layers "B.Cu" "B.Mask" "B.Paste")
			(net "GND")
		)
		(zone
			(layer "B.Cu")
			(hatch none 0.5)
			(connect_pads
				(clearance 0)
			)
			(min_thickness 0.25)
			(keepout
				(tracks allowed)
				(vias not_allowed)
				(pads allowed)
				(copperpour not_allowed)
				(footprints allowed)
			)
			(placement
				(enabled no)
				(sheetname "")
			)
			(fill
				(thermal_gap 0.5)
				(thermal_bridge_width 0.5)
				(island_removal_mode 0)
			)
			(polygon
				(pts
					(xy 39.5859 -234.53979) (xy 42.6085 -234.53979) (xy 42.6085 -231.64419) (xy 42.6085 -231.31399)
					(xy 39.5859 -231.31399) (xy 39.5859 -231.64419)
				)
			)
		)
		(zone
			(layer "B.Cu")
			(hatch none 0.5)
			(connect_pads
				(clearance 0)
			)
			(min_thickness 0.25)
			(keepout
				(tracks allowed)
				(vias not_allowed)
				(pads allowed)
				(copperpour not_allowed)
				(footprints allowed)
			)
			(placement
				(enabled no)
				(sheetname "")
			)
			(fill
				(thermal_gap 0.5)
				(thermal_bridge_width 0.5)
				(island_removal_mode 0)
			)
			(polygon
				(pts
					(xy 42.6085 -228.25329) (xy 42.6085 -225.34499) (xy 39.5859 -225.34499) (xy 39.5859 -228.24059)
					(xy 39.5859 -228.57079) (xy 42.6085 -228.57079)
				)
			)
		)
	)
	(footprint ""
		(layer "B.Cu")
		(at 467.5632 -222.0976 90)
		(property "Reference" "L6"
			(at 0 0 90)
			(layer "B.SilkS")
			(hide yes)
			(effects
				(font
					(size 1.27 1.27)
				)
				(justify mirror)
			)
		)
		(property "Value" "IND-1UH-191-GP"
			(at 6.7818 -2.1082 90)
			(unlocked yes)
			(layer "B.Fab")
			(hide yes)
			(effects
				(font
					(size 1.016 1.016)
					(thickness 0.1524)
				)
				(justify mirror)
			)
		)
		(property "Device Type" "L109100-2430-UH119"
			(at 6.7818 -3.6322 90)
			(unlocked yes)
			(layer "B.Fab")
			(hide yes)
			(effects
				(font
					(size 1.016 1.016)
					(thickness 0.1524)
				)
				(justify mirror)
			)
		)
		(duplicate_pad_numbers_are_jumpers no)
		(fp_line
			(start 5.2578 -6.4262)
			(end -5.2578 -6.4262)
			(stroke
				(width 0.1524)
				(type default)
			)
			(layer "B.SilkS")
		)
		(fp_line
			(start -5.2578 -6.4262)
			(end -5.2578 6.4262)
			(stroke
				(width 0.1524)
				(type default)
			)
			(layer "B.SilkS")
		)
		(fp_line
			(start 5.2578 6.4262)
			(end 5.2578 -6.4262)
			(stroke
				(width 0.1524)
				(type default)
			)
			(layer "B.SilkS")
		)
		(fp_line
			(start -5.2578 6.4262)
			(end 5.2578 6.4262)
			(stroke
				(width 0.1524)
				(type default)
			)
			(layer "B.SilkS")
		)
		(fp_rect
			(start 5.0038 5.4229)
			(end -5.0038 -5.4229)
			(stroke
				(width 0)
				(type default)
			)
			(fill no)
			(layer "B.CrtYd")
		)
		(fp_poly
			(pts
				(xy 5.5118 6.5024) (xy 5.5118 -6.5024) (xy -5.5118 -6.5024) (xy -5.5118 -0.8509) (xy -5.0038 -0.8509)
				(xy -5.0038 -5.4229) (xy 5.0038 -5.4229) (xy 5.0038 5.4229) (xy -5.0038 5.4229) (xy -5.0038 -0.8382)
				(xy -5.5118 -0.8382) (xy -5.5118 6.5024)
			)
			(stroke
				(width 0)
				(type default)
			)
			(fill no)
			(layer "B.CrtYd")
		)
		(fp_rect
			(start 5.5118 6.5024)
			(end -5.5118 -6.5024)
			(stroke
				(width 0)
				(type default)
			)
			(fill no)
			(layer "B.Fab")
		)
		(pad "1" smd rect
			(at 0 -4.396994 270)
			(size 3.5052 3.556)
			(layers "B.Cu" "B.Mask" "B.Paste")
			(net "P5V_B_3_LL")
		)
		(pad "2" smd rect
			(at 0 4.396994 270)
			(size 3.5052 3.556)
			(layers "B.Cu" "B.Mask" "B.Paste")
			(net "P5V_B_3")
		)
	)
	(footprint ""
		(layer "B.Cu")
		(at 437.834786 -119.229378)
		(property "Reference" "G8"
			(at 0 0 0)
			(layer "B.SilkS")
			(hide yes)
			(effects
				(font
					(size 1.27 1.27)
				)
				(justify mirror)
			)
		)
		(property "Value" "COPPER-CLOSE-GP-U"
			(at -0.0762 -2.8702 0)
			(unlocked yes)
			(layer "B.Fab")
			(hide yes)
			(effects
				(font
					(size 1.016 1.016)
					(thickness 0.1524)
				)
				(justify mirror)
			)
		)
		(property "Device Type" "CON2C-U"
			(at -0.0762 -4.3942 0)
			(unlocked yes)
			(layer "B.Fab")
			(hide yes)
			(effects
				(font
					(size 1.016 1.016)
					(thickness 0.1524)
				)
				(justify mirror)
			)
		)
		(duplicate_pad_numbers_are_jumpers no)
		(fp_rect
			(start 0.9398 0.9652)
			(end -0.9398 -0.9652)
			(stroke
				(width 0)
				(type default)
			)
			(fill no)
			(layer "B.CrtYd")
		)
		(fp_rect
			(start 0.9398 0.9652)
			(end -0.9398 -0.9652)
			(stroke
				(width 0)
				(type default)
			)
			(fill no)
			(layer "B.Fab")
		)
		(pad "1" smd custom
			(at 0 -0.5334 180)
			(size 0.17145 0.17145)
			(layers "B.Cu" "B.Mask" "B.Paste")
			(net "AGND_P5V_B_4")
			(options
				(clearance outline)
				(anchor circle)
			)
			(primitives
				(gr_poly
					(pts
						(xy -0.127 -0.3429) (xy -0.127 -0.1651) (xy -0.635 0.3429) (xy 0.635 0.3429) (xy 0.127 -0.1651)
						(xy 0.127 -0.3429)
					)
					(width 0)
					(fill yes)
				)
			)
		)
		(pad "2" smd custom
			(at 0 0.5334 180)
			(size 0.17145 0.17145)
			(layers "B.Cu" "B.Mask" "B.Paste")
			(net "GND")
			(options
				(clearance outline)
				(anchor circle)
			)
			(primitives
				(gr_poly
					(pts
						(xy -0.635 -0.3429) (xy -0.127 0.1651) (xy -0.127 0.3429) (xy 0.127 0.3429) (xy 0.127 0.1651)
						(xy 0.635 -0.3429)
					)
					(width 0)
					(fill yes)
				)
			)
		)
	)
	(footprint ""
		(layer "B.Cu")
		(at 218.207844 -329.057)
		(property "Reference" "C568"
			(at 0 0 0)
			(layer "B.SilkS")
			(hide yes)
			(effects
				(font
					(size 1.27 1.27)
				)
				(justify mirror)
			)
		)
		(property "Value" "SC22U25V6KX-2-GP-U"
			(at 2.860802 -5.279644 0)
			(unlocked yes)
			(layer "B.Fab")
			(hide yes)
			(effects
				(font
					(size 1.016 1.016)
					(thickness 0.1524)
				)
				(justify mirror)
			)
		)
		(property "Device Type" "C1206-TO0D3H75"
			(at 2.860802 -6.803644 0)
			(unlocked yes)
			(layer "B.Fab")
			(hide yes)
			(effects
				(font
					(size 1.016 1.016)
					(thickness 0.1524)
				)
				(justify mirror)
			)
		)
		(duplicate_pad_numbers_are_jumpers no)
		(fp_line
			(start -1.3081 -2.3749)
			(end -1.3081 2.3749)
			(stroke
				(width 0.1524)
				(type default)
			)
			(layer "B.SilkS")
		)
		(fp_line
			(start -1.3081 2.3749)
			(end 1.3081 2.3749)
			(stroke
				(width 0.1524)
				(type default)
			)
			(layer "B.SilkS")
		)
		(fp_line
			(start 1.3081 -2.3749)
			(end -1.3081 -2.3749)
			(stroke
				(width 0.1524)
				(type default)
			)
			(layer "B.SilkS")
		)
		(fp_line
			(start 1.3081 2.3749)
			(end 1.3081 -2.3749)
			(stroke
				(width 0.1524)
				(type default)
			)
			(layer "B.SilkS")
		)
		(fp_rect
			(start 0.8001 1.6002)
			(end -0.8001 -1.6002)
			(stroke
				(width 0)
				(type default)
			)
			(fill no)
			(layer "B.CrtYd")
		)
		(fp_poly
			(pts
				(xy 1.5621 2.4511) (xy 1.5621 1.6002) (xy -0.8001 1.6002) (xy -0.8001 -1.6002) (xy 0.8001 -1.6002)
				(xy 0.8001 1.5875) (xy 1.5621 1.5875) (xy 1.5621 -2.4511) (xy -1.5621 -2.4511) (xy -1.5621 2.4511)
			)
			(stroke
				(width 0)
				(type default)
			)
			(fill no)
			(layer "B.CrtYd")
		)
		(fp_rect
			(start 1.5621 2.4511)
			(end -1.5621 -2.4511)
			(stroke
				(width 0)
				(type default)
			)
			(fill no)
			(layer "B.Fab")
		)
		(pad "1" smd rect
			(at 0 -1.392936 180)
			(size 2.1082 1.4478)
			(layers "B.Cu" "B.Mask" "B.Paste")
			(net "P12V_IN")
		)
		(pad "2" smd rect
			(at 0 1.392936 180)
			(size 2.1082 1.4478)
			(layers "B.Cu" "B.Mask" "B.Paste")
			(net "GND")
		)
	)
	(footprint ""
		(layer "B.Cu")
		(at 15.433802 -227.08235 -90)
		(property "Reference" "C624"
			(at 0 0 90)
			(layer "B.SilkS")
			(hide yes)
			(effects
				(font
					(size 1.27 1.27)
				)
				(justify mirror)
			)
		)
		(property "Value" "SC4D7U25V5KX-1-GP"
			(at 0.0762 -6.1214 270)
			(unlocked yes)
			(layer "B.Fab")
			(hide yes)
			(effects
				(font
					(size 1.016 1.016)
					(thickness 0.1524)
				)
				(justify mirror)
			)
		)
		(property "Device Type" "C805H58"
			(at 0.0762 -8.1534 270)
			(unlocked yes)
			(layer "B.Fab")
			(hide yes)
			(effects
				(font
					(size 1.016 1.016)
					(thickness 0.1524)
				)
				(justify mirror)
			)
		)
		(duplicate_pad_numbers_are_jumpers no)
		(fp_line
			(start -0.635 0)
			(end 0.635 0)
			(stroke
				(width 0.508)
				(type default)
			)
			(layer "B.SilkS")
		)
		(fp_rect
			(start 0.9652 1.778)
			(end -0.9652 -1.778)
			(stroke
				(width 0)
				(type default)
			)
			(fill no)
			(layer "B.CrtYd")
		)
		(fp_poly
			(pts
				(xy 0.9652 -1.778) (xy -0.9652 -1.778) (xy -0.9652 1.778) (xy 0.9652 1.778)
			)
			(stroke
				(width 0)
				(type default)
			)
			(fill no)
			(layer "B.Fab")
		)
		(pad "1" smd rect
			(at 0 -0.9652 90)
			(size 1.397 1.143)
			(layers "B.Cu" "B.Mask" "B.Paste")
			(net "P12V_B_1_VDD_U31")
		)
		(pad "2" smd rect
			(at 0 0.9652 90)
			(size 1.397 1.143)
			(layers "B.Cu" "B.Mask" "B.Paste")
			(net "GND")
		)
	)
	(footprint ""
		(layer "B.Cu")
		(at 439.302398 -119.227092 180)
		(property "Reference" "R1171"
			(at 0 0 0)
			(layer "B.SilkS")
			(hide yes)
			(effects
				(font
					(size 1.27 1.27)
				)
				(justify mirror)
			)
		)
		(property "Value" "10KR2F-2-GP"
			(at -0.064008 -3.993896 180)
			(unlocked yes)
			(layer "B.Fab")
			(hide yes)
			(effects
				(font
					(size 1.016 1.016)
					(thickness 0.1524)
				)
				(justify mirror)
			)
		)
		(property "Device Type" "R402H16"
			(at -0.064008 -5.517896 180)
			(unlocked yes)
			(layer "B.Fab")
			(hide yes)
			(effects
				(font
					(size 1.016 1.016)
					(thickness 0.1524)
				)
				(justify mirror)
			)
		)
		(duplicate_pad_numbers_are_jumpers no)
		(fp_line
			(start 0.508 -0.9398)
			(end 0.508 0.9398)
			(stroke
				(width 0.1524)
				(type default)
			)
			(layer "B.SilkS")
		)
		(fp_line
			(start -0.508 -0.9398)
			(end 0.508 -0.9398)
			(stroke
				(width 0.1524)
				(type default)
			)
			(layer "B.SilkS")
		)
		(fp_rect
			(start 0.508 0.9398)
			(end -0.508 -0.9398)
			(stroke
				(width 0)
				(type default)
			)
			(fill no)
			(layer "B.CrtYd")
		)
		(fp_rect
			(start 0.508 0.9398)
			(end -0.508 -0.9398)
			(stroke
				(width 0)
				(type default)
			)
			(fill no)
			(layer "B.Fab")
		)
		(pad "1" smd custom
			(at 0 -0.4445)
			(size 0.1397 0.1397)
			(layers "B.Cu" "B.Mask" "B.Paste")
			(net "P5V_B_4_VFB")
			(options
				(clearance outline)
				(anchor circle)
			)
			(primitives
				(gr_poly
					(pts
						(arc
							(start -0.1778 0.2794)
							(mid -0.249642 0.249642)
							(end -0.2794 0.1778)
						)
						(arc
							(start -0.2794 -0.1778)
							(mid -0.249642 -0.249642)
							(end -0.1778 -0.2794)
						)
						(arc
							(start 0.1778 -0.2794)
							(mid 0.249642 -0.249642)
							(end 0.2794 -0.1778)
						)
						(arc
							(start 0.2794 0.1778)
							(mid 0.249642 0.249642)
							(end 0.1778 0.2794)
						)
					)
					(width 0)
					(fill yes)
				)
			)
		)
		(pad "2" smd custom
			(at 0 0.4445)
			(size 0.1397 0.1397)
			(layers "B.Cu" "B.Mask" "B.Paste")
			(net "AGND_P5V_B_4")
			(options
				(clearance outline)
				(anchor circle)
			)
			(primitives
				(gr_poly
					(pts
						(arc
							(start -0.1778 0.2794)
							(mid -0.249642 0.249642)
							(end -0.2794 0.1778)
						)
						(arc
							(start -0.2794 -0.1778)
							(mid -0.249642 -0.249642)
							(end -0.1778 -0.2794)
						)
						(arc
							(start 0.1778 -0.2794)
							(mid 0.249642 -0.249642)
							(end 0.2794 -0.1778)
						)
						(arc
							(start 0.2794 0.1778)
							(mid 0.249642 0.249642)
							(end 0.1778 0.2794)
						)
					)
					(width 0)
					(fill yes)
				)
			)
		)
	)
	(footprint ""
		(layer "B.Cu")
		(at 9.210802 -220.09735 90)
		(property "Reference" "L1"
			(at 0 0 90)
			(layer "B.SilkS")
			(hide yes)
			(effects
				(font
					(size 1.27 1.27)
				)
				(justify mirror)
			)
		)
		(property "Value" "BLM21PG220SN1DGP"
			(at -0.0254 -5.6896 90)
			(unlocked yes)
			(layer "B.Fab")
			(hide yes)
			(effects
				(font
					(size 1.016 1.016)
					(thickness 0.1524)
				)
				(justify mirror)
			)
		)
		(property "Device Type" "L20125H42"
			(at -0.0254 -7.5946 90)
			(unlocked yes)
			(layer "B.Fab")
			(hide yes)
			(effects
				(font
					(size 1.016 1.016)
					(thickness 0.1524)
				)
				(justify mirror)
			)
		)
		(duplicate_pad_numbers_are_jumpers no)
		(fp_line
			(start 0.9144 -1.7018)
			(end 0.9144 1.7018)
			(stroke
				(width 0.1524)
				(type default)
			)
			(layer "B.SilkS")
		)
		(fp_line
			(start -0.9144 -1.7018)
			(end 0.9144 -1.7018)
			(stroke
				(width 0.1524)
				(type default)
			)
			(layer "B.SilkS")
		)
		(fp_line
			(start 0.9144 1.7018)
			(end -0.9144 1.7018)
			(stroke
				(width 0.1524)
				(type default)
			)
			(layer "B.SilkS")
		)
		(fp_line
			(start -0.9144 1.7018)
			(end -0.9144 -1.7018)
			(stroke
				(width 0.1524)
				(type default)
			)
			(layer "B.SilkS")
		)
		(fp_rect
			(start 1.0033 1.778)
			(end -1.0033 -1.778)
			(stroke
				(width 0)
				(type default)
			)
			(fill no)
			(layer "B.CrtYd")
		)
		(fp_poly
			(pts
				(xy 1.0033 -1.778) (xy -1.0033 -1.778) (xy -1.0033 1.778) (xy 1.0033 1.778)
			)
			(stroke
				(width 0)
				(type default)
			)
			(fill no)
			(layer "B.Fab")
		)
		(pad "1" smd rect
			(at 0 -0.9652 270)
			(size 1.397 1.143)
			(layers "B.Cu" "B.Mask" "B.Paste")
			(net "P12V_B")
		)
		(pad "2" smd rect
			(at 0 0.9652 270)
			(size 1.397 1.143)
			(layers "B.Cu" "B.Mask" "B.Paste")
			(net "P12V_B_1_VIN_U31")
		)
	)
	(footprint ""
		(layer "B.Cu")
		(at 460.060802 -230.63835 90)
		(property "Reference" "C666"
			(at 0 0 90)
			(layer "B.SilkS")
			(hide yes)
			(effects
				(font
					(size 1.27 1.27)
				)
				(justify mirror)
			)
		)
		(property "Value" "SC68P50V2JN-2-GP"
			(at -1.1811 -2.7051 90)
			(unlocked yes)
			(layer "B.Fab")
			(hide yes)
			(effects
				(font
					(size 1.016 1.016)
					(thickness 0.1524)
				)
				(justify mirror)
			)
		)
		(property "Device Type" "C402H22"
			(at -1.1811 -4.2291 90)
			(unlocked yes)
			(layer "B.Fab")
			(hide yes)
			(effects
				(font
					(size 1.016 1.016)
					(thickness 0.1524)
				)
				(justify mirror)
			)
		)
		(duplicate_pad_numbers_are_jumpers no)
		(fp_rect
			(start 0.4318 0.9525)
			(end -0.4318 -0.9525)
			(stroke
				(width 0)
				(type default)
			)
			(fill no)
			(layer "B.CrtYd")
		)
		(fp_rect
			(start 0.4318 0.9525)
			(end -0.4318 -0.9525)
			(stroke
				(width 0)
				(type default)
			)
			(fill no)
			(layer "B.Fab")
		)
		(pad "1" smd custom
			(at 0 -0.4445 270)
			(size 0.1524 0.1524)
			(layers "B.Cu" "B.Mask" "B.Paste")
			(net "P5V_B_3_VFB")
			(options
				(clearance outline)
				(anchor circle)
			)
			(primitives
				(gr_poly
					(pts
						(arc
							(start 0.3048 0.2032)
							(mid 0.275042 0.275042)
							(end 0.2032 0.3048)
						)
						(arc
							(start -0.2032 0.3048)
							(mid -0.275042 0.275042)
							(end -0.3048 0.2032)
						)
						(arc
							(start -0.3048 -0.2032)
							(mid -0.275042 -0.275042)
							(end -0.2032 -0.3048)
						)
						(arc
							(start 0.2032 -0.3048)
							(mid 0.275042 -0.275042)
							(end 0.3048 -0.2032)
						)
					)
					(width 0)
					(fill yes)
				)
			)
		)
		(pad "2" smd custom
			(at 0 0.4445 270)
			(size 0.1524 0.1524)
			(layers "B.Cu" "B.Mask" "B.Paste")
			(net "P5V_B_3_VFB_R")
			(options
				(clearance outline)
				(anchor circle)
			)
			(primitives
				(gr_poly
					(pts
						(arc
							(start 0.3048 0.2032)
							(mid 0.275042 0.275042)
							(end 0.2032 0.3048)
						)
						(arc
							(start -0.2032 0.3048)
							(mid -0.275042 0.275042)
							(end -0.3048 0.2032)
						)
						(arc
							(start -0.3048 -0.2032)
							(mid -0.275042 -0.275042)
							(end -0.2032 -0.3048)
						)
						(arc
							(start 0.2032 -0.3048)
							(mid 0.275042 -0.275042)
							(end 0.3048 -0.2032)
						)
					)
					(width 0)
					(fill yes)
				)
			)
		)
	)
	(footprint ""
		(layer "B.Cu")
		(at 458.201014 -229.543864 180)
		(property "Reference" "R1150"
			(at 0 0 0)
			(layer "B.SilkS")
			(hide yes)
			(effects
				(font
					(size 1.27 1.27)
				)
				(justify mirror)
			)
		)
		(property "Value" "10KR2F-2-GP"
			(at -0.064008 -3.993896 180)
			(unlocked yes)
			(layer "B.Fab")
			(hide yes)
			(effects
				(font
					(size 1.016 1.016)
					(thickness 0.1524)
				)
				(justify mirror)
			)
		)
		(property "Device Type" "R402H16"
			(at -0.064008 -5.517896 180)
			(unlocked yes)
			(layer "B.Fab")
			(hide yes)
			(effects
				(font
					(size 1.016 1.016)
					(thickness 0.1524)
				)
				(justify mirror)
			)
		)
		(duplicate_pad_numbers_are_jumpers no)
		(fp_line
			(start 0.508 -0.9398)
			(end 0.508 0.9398)
			(stroke
				(width 0.1524)
				(type default)
			)
			(layer "B.SilkS")
		)
		(fp_line
			(start -0.508 -0.9398)
			(end 0.508 -0.9398)
			(stroke
				(width 0.1524)
				(type default)
			)
			(layer "B.SilkS")
		)
		(fp_rect
			(start 0.508 0.9398)
			(end -0.508 -0.9398)
			(stroke
				(width 0)
				(type default)
			)
			(fill no)
			(layer "B.CrtYd")
		)
		(fp_rect
			(start 0.508 0.9398)
			(end -0.508 -0.9398)
			(stroke
				(width 0)
				(type default)
			)
			(fill no)
			(layer "B.Fab")
		)
		(pad "1" smd custom
			(at 0 -0.4445)
			(size 0.1397 0.1397)
			(layers "B.Cu" "B.Mask" "B.Paste")
			(net "P5V_B_3_VFB")
			(options
				(clearance outline)
				(anchor circle)
			)
			(primitives
				(gr_poly
					(pts
						(arc
							(start -0.1778 0.2794)
							(mid -0.249642 0.249642)
							(end -0.2794 0.1778)
						)
						(arc
							(start -0.2794 -0.1778)
							(mid -0.249642 -0.249642)
							(end -0.1778 -0.2794)
						)
						(arc
							(start 0.1778 -0.2794)
							(mid 0.249642 -0.249642)
							(end 0.2794 -0.1778)
						)
						(arc
							(start 0.2794 0.1778)
							(mid 0.249642 0.249642)
							(end 0.1778 0.2794)
						)
					)
					(width 0)
					(fill yes)
				)
			)
		)
		(pad "2" smd custom
			(at 0 0.4445)
			(size 0.1397 0.1397)
			(layers "B.Cu" "B.Mask" "B.Paste")
			(net "AGND_P5V_B_3")
			(options
				(clearance outline)
				(anchor circle)
			)
			(primitives
				(gr_poly
					(pts
						(arc
							(start -0.1778 0.2794)
							(mid -0.249642 0.249642)
							(end -0.2794 0.1778)
						)
						(arc
							(start -0.2794 -0.1778)
							(mid -0.249642 -0.249642)
							(end -0.1778 -0.2794)
						)
						(arc
							(start 0.1778 -0.2794)
							(mid 0.249642 -0.249642)
							(end 0.2794 -0.1778)
						)
						(arc
							(start 0.2794 0.1778)
							(mid 0.249642 0.249642)
							(end 0.1778 0.2794)
						)
					)
					(width 0)
					(fill yes)
				)
			)
		)
	)
	(footprint ""
		(layer "B.Cu")
		(at 34.82086 -108.988606 90)
		(property "Reference" "L3"
			(at 0 0 90)
			(layer "B.SilkS")
			(hide yes)
			(effects
				(font
					(size 1.27 1.27)
				)
				(justify mirror)
			)
		)
		(property "Value" "BLM21PG220SN1DGP"
			(at -0.0254 -5.6896 90)
			(unlocked yes)
			(layer "B.Fab")
			(hide yes)
			(effects
				(font
					(size 1.016 1.016)
					(thickness 0.1524)
				)
				(justify mirror)
			)
		)
		(property "Device Type" "L20125H42"
			(at -0.0254 -7.5946 90)
			(unlocked yes)
			(layer "B.Fab")
			(hide yes)
			(effects
				(font
					(size 1.016 1.016)
					(thickness 0.1524)
				)
				(justify mirror)
			)
		)
		(duplicate_pad_numbers_are_jumpers no)
		(fp_line
			(start 0.9144 -1.7018)
			(end 0.9144 1.7018)
			(stroke
				(width 0.1524)
				(type default)
			)
			(layer "B.SilkS")
		)
		(fp_line
			(start -0.9144 -1.7018)
			(end 0.9144 -1.7018)
			(stroke
				(width 0.1524)
				(type default)
			)
			(layer "B.SilkS")
		)
		(fp_line
			(start 0.9144 1.7018)
			(end -0.9144 1.7018)
			(stroke
				(width 0.1524)
				(type default)
			)
			(layer "B.SilkS")
		)
		(fp_line
			(start -0.9144 1.7018)
			(end -0.9144 -1.7018)
			(stroke
				(width 0.1524)
				(type default)
			)
			(layer "B.SilkS")
		)
		(fp_rect
			(start 1.0033 1.778)
			(end -1.0033 -1.778)
			(stroke
				(width 0)
				(type default)
			)
			(fill no)
			(layer "B.CrtYd")
		)
		(fp_poly
			(pts
				(xy 1.0033 -1.778) (xy -1.0033 -1.778) (xy -1.0033 1.778) (xy 1.0033 1.778)
			)
			(stroke
				(width 0)
				(type default)
			)
			(fill no)
			(layer "B.Fab")
		)
		(pad "1" smd rect
			(at 0 -0.9652 270)
			(size 1.397 1.143)
			(layers "B.Cu" "B.Mask" "B.Paste")
			(net "P12V_B")
		)
		(pad "2" smd rect
			(at 0 0.9652 270)
			(size 1.397 1.143)
			(layers "B.Cu" "B.Mask" "B.Paste")
			(net "P12V_B_2_VIN_U32")
		)
	)
	(footprint ""
		(layer "B.Cu")
		(at 259.82549 -286.582612)
		(property "Reference" "C692"
			(at 0 0 0)
			(layer "B.SilkS")
			(hide yes)
			(effects
				(font
					(size 1.27 1.27)
				)
				(justify mirror)
			)
		)
		(property "Value" "SC100P50V2JN-3GP"
			(at -1.1811 -2.7051 0)
			(unlocked yes)
			(layer "B.Fab")
			(hide yes)
			(effects
				(font
					(size 1.016 1.016)
					(thickness 0.1524)
				)
				(justify mirror)
			)
		)
		(property "Device Type" "C402H22"
			(at -1.1811 -4.2291 0)
			(unlocked yes)
			(layer "B.Fab")
			(hide yes)
			(effects
				(font
					(size 1.016 1.016)
					(thickness 0.1524)
				)
				(justify mirror)
			)
		)
		(duplicate_pad_numbers_are_jumpers no)
		(fp_rect
			(start 0.4318 0.9525)
			(end -0.4318 -0.9525)
			(stroke
				(width 0)
				(type default)
			)
			(fill no)
			(layer "B.CrtYd")
		)
		(fp_rect
			(start 0.4318 0.9525)
			(end -0.4318 -0.9525)
			(stroke
				(width 0)
				(type default)
			)
			(fill no)
			(layer "B.Fab")
		)
		(pad "1" smd custom
			(at 0 -0.4445 180)
			(size 0.1524 0.1524)
			(layers "B.Cu" "B.Mask" "B.Paste")
			(net "P3V3_STBY_CC_R")
			(options
				(clearance outline)
				(anchor circle)
			)
			(primitives
				(gr_poly
					(pts
						(arc
							(start 0.3048 0.2032)
							(mid 0.275042 0.275042)
							(end 0.2032 0.3048)
						)
						(arc
							(start -0.2032 0.3048)
							(mid -0.275042 0.275042)
							(end -0.3048 0.2032)
						)
						(arc
							(start -0.3048 -0.2032)
							(mid -0.275042 -0.275042)
							(end -0.2032 -0.3048)
						)
						(arc
							(start 0.2032 -0.3048)
							(mid 0.275042 -0.275042)
							(end 0.3048 -0.2032)
						)
					)
					(width 0)
					(fill yes)
				)
			)
		)
		(pad "2" smd custom
			(at 0 0.4445 180)
			(size 0.1524 0.1524)
			(layers "B.Cu" "B.Mask" "B.Paste")
			(net "P3V3_STBY_VFB")
			(options
				(clearance outline)
				(anchor circle)
			)
			(primitives
				(gr_poly
					(pts
						(arc
							(start 0.3048 0.2032)
							(mid 0.275042 0.275042)
							(end 0.2032 0.3048)
						)
						(arc
							(start -0.2032 0.3048)
							(mid -0.275042 0.275042)
							(end -0.3048 0.2032)
						)
						(arc
							(start -0.3048 -0.2032)
							(mid -0.275042 -0.275042)
							(end -0.2032 -0.3048)
						)
						(arc
							(start 0.2032 -0.3048)
							(mid 0.275042 -0.275042)
							(end 0.3048 -0.2032)
						)
					)
					(width 0)
					(fill yes)
				)
			)
		)
	)
	(footprint ""
		(layer "B.Cu")
		(at 206.756 -348.361 90)
		(property "Reference" "R1019"
			(at 0 0 90)
			(layer "B.SilkS")
			(hide yes)
			(effects
				(font
					(size 1.27 1.27)
				)
				(justify mirror)
			)
		)
		(property "Value" "10R5F-1-GP"
			(at 0 -8.9535 90)
			(unlocked yes)
			(layer "B.Fab")
			(hide yes)
			(effects
				(font
					(size 1.27 1.016)
					(thickness 0.1524)
				)
				(justify mirror)
			)
		)
		(property "Device Type" "R805H24"
			(at 0 -10.6299 90)
			(unlocked yes)
			(layer "B.Fab")
			(hide yes)
			(effects
				(font
					(size 1.27 1.016)
					(thickness 0.1524)
				)
				(justify mirror)
			)
		)
		(duplicate_pad_numbers_are_jumpers no)
		(fp_line
			(start 0.889 -1.7018)
			(end 0.889 0.2794)
			(stroke
				(width 0.1524)
				(type default)
			)
			(layer "B.SilkS")
		)
		(fp_line
			(start -0.889 -1.7018)
			(end 0.889 -1.7018)
			(stroke
				(width 0.1524)
				(type default)
			)
			(layer "B.SilkS")
		)
		(fp_line
			(start -0.889 -1.7018)
			(end -0.889 -0.381)
			(stroke
				(width 0.1524)
				(type default)
			)
			(layer "B.SilkS")
		)
		(fp_line
			(start 0.889 0.0762)
			(end 0.889 1.7018)
			(stroke
				(width 0.1524)
				(type default)
			)
			(layer "B.SilkS")
		)
		(fp_line
			(start 0.889 1.7018)
			(end -0.889 1.7018)
			(stroke
				(width 0.1524)
				(type default)
			)
			(layer "B.SilkS")
		)
		(fp_line
			(start -0.889 1.7018)
			(end -0.889 -0.508)
			(stroke
				(width 0.1524)
				(type default)
			)
			(layer "B.SilkS")
		)
		(fp_poly
			(pts
				(xy -0.9652 -1.778) (xy -0.9652 1.778) (xy 0.9652 1.778) (xy 0.9652 -1.778)
			)
			(stroke
				(width 0)
				(type default)
			)
			(fill no)
			(layer "B.CrtYd")
		)
		(fp_rect
			(start 0.9652 1.778)
			(end -0.9652 -1.778)
			(stroke
				(width 0)
				(type default)
			)
			(fill no)
			(layer "B.Fab")
		)
		(pad "1" smd rect
			(at 0 -0.9652 270)
			(size 1.397 1.143)
			(layers "B.Cu" "B.Mask" "B.Paste")
			(net "MB0_12V_CTRL_GATE5")
		)
		(pad "2" smd rect
			(at 0 0.9652 270)
			(size 1.397 1.143)
			(layers "B.Cu" "B.Mask" "B.Paste")
			(net "MB0_CM_GATE_R")
		)
	)
	(footprint ""
		(layer "B.Cu")
		(at 240.665 -279.8318 -90)
		(property "Reference" "C702"
			(at 0 0 90)
			(layer "B.SilkS")
			(hide yes)
			(effects
				(font
					(size 1.27 1.27)
				)
				(justify mirror)
			)
		)
		(property "Value" "SC10U6D3V5KX-4GP"
			(at 0.0762 -6.1214 270)
			(unlocked yes)
			(layer "B.Fab")
			(hide yes)
			(effects
				(font
					(size 1.016 1.016)
					(thickness 0.1524)
				)
				(justify mirror)
			)
		)
		(property "Device Type" "C805H58"
			(at 0.0762 -8.1534 270)
			(unlocked yes)
			(layer "B.Fab")
			(hide yes)
			(effects
				(font
					(size 1.016 1.016)
					(thickness 0.1524)
				)
				(justify mirror)
			)
		)
		(duplicate_pad_numbers_are_jumpers no)
		(fp_line
			(start -0.635 0)
			(end 0.635 0)
			(stroke
				(width 0.508)
				(type default)
			)
			(layer "B.SilkS")
		)
		(fp_rect
			(start 0.9652 1.778)
			(end -0.9652 -1.778)
			(stroke
				(width 0)
				(type default)
			)
			(fill no)
			(layer "B.CrtYd")
		)
		(fp_poly
			(pts
				(xy 0.9652 -1.778) (xy -0.9652 -1.778) (xy -0.9652 1.778) (xy 0.9652 1.778)
			)
			(stroke
				(width 0)
				(type default)
			)
			(fill no)
			(layer "B.Fab")
		)
		(pad "1" smd rect
			(at 0 -0.9652 90)
			(size 1.397 1.143)
			(layers "B.Cu" "B.Mask" "B.Paste")
			(net "P3V3_STBY_B")
		)
		(pad "2" smd rect
			(at 0 0.9652 90)
			(size 1.397 1.143)
			(layers "B.Cu" "B.Mask" "B.Paste")
			(net "GND")
		)
	)
	(footprint ""
		(layer "B.Cu")
		(at 131.292092 -364.927134)
		(property "Reference" "R966"
			(at 0 0 0)
			(layer "B.SilkS")
			(hide yes)
			(effects
				(font
					(size 1.27 1.27)
				)
				(justify mirror)
			)
		)
		(property "Value" "4K7R2J-2-GP"
			(at -0.064008 -3.993896 0)
			(unlocked yes)
			(layer "B.Fab")
			(hide yes)
			(effects
				(font
					(size 1.016 1.016)
					(thickness 0.1524)
				)
				(justify mirror)
			)
		)
		(property "Device Type" "R402H16"
			(at -0.064008 -5.517896 0)
			(unlocked yes)
			(layer "B.Fab")
			(hide yes)
			(effects
				(font
					(size 1.016 1.016)
					(thickness 0.1524)
				)
				(justify mirror)
			)
		)
		(duplicate_pad_numbers_are_jumpers no)
		(fp_line
			(start -0.508 -0.9398)
			(end 0.508 -0.9398)
			(stroke
				(width 0.1524)
				(type default)
			)
			(layer "B.SilkS")
		)
		(fp_line
			(start 0.508 -0.9398)
			(end 0.508 0.9398)
			(stroke
				(width 0.1524)
				(type default)
			)
			(layer "B.SilkS")
		)
		(fp_rect
			(start 0.508 0.9398)
			(end -0.508 -0.9398)
			(stroke
				(width 0)
				(type default)
			)
			(fill no)
			(layer "B.CrtYd")
		)
		(fp_rect
			(start 0.508 0.9398)
			(end -0.508 -0.9398)
			(stroke
				(width 0)
				(type default)
			)
			(fill no)
			(layer "B.Fab")
		)
		(pad "1" smd custom
			(at 0 -0.4445 180)
			(size 0.1397 0.1397)
			(layers "B.Cu" "B.Mask" "B.Paste")
			(net "P12V_IN")
			(options
				(clearance outline)
				(anchor circle)
			)
			(primitives
				(gr_poly
					(pts
						(arc
							(start -0.1778 0.2794)
							(mid -0.249642 0.249642)
							(end -0.2794 0.1778)
						)
						(arc
							(start -0.2794 -0.1778)
							(mid -0.249642 -0.249642)
							(end -0.1778 -0.2794)
						)
						(arc
							(start 0.1778 -0.2794)
							(mid 0.249642 -0.249642)
							(end 0.2794 -0.1778)
						)
						(arc
							(start 0.2794 0.1778)
							(mid 0.249642 0.249642)
							(end 0.1778 0.2794)
						)
					)
					(width 0)
					(fill yes)
				)
			)
		)
		(pad "2" smd custom
			(at 0 0.4445 180)
			(size 0.1397 0.1397)
			(layers "B.Cu" "B.Mask" "B.Paste")
			(net "GATE_FAN1")
			(options
				(clearance outline)
				(anchor circle)
			)
			(primitives
				(gr_poly
					(pts
						(arc
							(start -0.1778 0.2794)
							(mid -0.249642 0.249642)
							(end -0.2794 0.1778)
						)
						(arc
							(start -0.2794 -0.1778)
							(mid -0.249642 -0.249642)
							(end -0.1778 -0.2794)
						)
						(arc
							(start 0.1778 -0.2794)
							(mid 0.249642 -0.249642)
							(end 0.2794 -0.1778)
						)
						(arc
							(start 0.2794 0.1778)
							(mid 0.249642 0.249642)
							(end 0.1778 0.2794)
						)
					)
					(width 0)
					(fill yes)
				)
			)
		)
	)
	(footprint ""
		(layer "B.Cu")
		(at 425.174918 -66.799968)
		(property "Reference" "SCW2"
			(at 0 0 0)
			(layer "B.SilkS")
			(hide yes)
			(effects
				(font
					(size 1.27 1.27)
				)
				(justify mirror)
			)
		)
		(property "Value" ""
			(at 0 0 0)
			(layer "B.Fab")
			(effects
				(font
					(size 1.27 1.27)
				)
				(justify mirror)
			)
		)
		(duplicate_pad_numbers_are_jumpers no)
		(fp_poly
			(pts
				(arc
					(start 5.4356 0)
					(mid -5.4356 0)
					(end 5.4356 0)
				)
			)
			(stroke
				(width 0)
				(type default)
			)
			(fill no)
			(layer "B.CrtYd")
		)
		(fp_poly
			(pts
				(arc
					(start 5.4356 0)
					(mid -5.4356 0)
					(end 5.4356 0)
				)
			)
			(stroke
				(width 0)
				(type default)
			)
			(fill no)
			(layer "F.CrtYd")
		)
		(fp_poly
			(pts
				(arc
					(start 5.4356 0)
					(mid -5.4356 0)
					(end 5.4356 0)
				)
			)
			(stroke
				(width 0)
				(type default)
			)
			(fill no)
			(layer "B.Fab")
		)
		(fp_poly
			(pts
				(arc
					(start 5.4356 0)
					(mid -5.4356 0)
					(end 5.4356 0)
				)
			)
			(stroke
				(width 0)
				(type default)
			)
			(fill no)
			(layer "F.Fab")
		)
		(pad "" np_thru_hole circle
			(at 0 0 180)
			(size 0.254 0.254)
			(drill 10.2616)
			(layers "*.Cu" "*.Mask")
			(clearance 5.3594)
			(thermal_gap 5.3594)
		)
		(zone
			(layers "F.Cu" "B.Cu" "In1.Cu" "In2.Cu" "In3.Cu" "In4.Cu" "In5.Cu" "In6.Cu")
			(hatch none 0.5)
			(connect_pads
				(clearance 0)
			)
			(min_thickness 0.25)
			(keepout
				(tracks not_allowed)
				(vias allowed)
				(pads allowed)
				(copperpour not_allowed)
				(footprints allowed)
			)
			(placement
				(enabled no)
				(sheetname "")
			)
			(fill
				(thermal_gap 0.5)
				(thermal_bridge_width 0.5)
				(island_removal_mode 0)
			)
			(polygon
				(pts
					(arc
						(start 430.610518 -66.799968)
						(mid 419.739318 -66.799968)
						(end 430.610518 -66.799968)
					)
				)
			)
		)
	)
	(footprint ""
		(layer "B.Cu")
		(at 52.032662 -118.44147 -90)
		(property "Reference" "R1125"
			(at 0 0 90)
			(layer "B.SilkS")
			(hide yes)
			(effects
				(font
					(size 1.27 1.27)
				)
				(justify mirror)
			)
		)
		(property "Value" "10R3F-GP"
			(at 0.0254 -2.5146 270)
			(unlocked yes)
			(layer "B.Fab")
			(hide yes)
			(effects
				(font
					(size 1.016 1.016)
					(thickness 0.1524)
				)
				(justify mirror)
			)
		)
		(property "Device Type" "R603H22"
			(at 0.0254 -4.0386 270)
			(unlocked yes)
			(layer "B.Fab")
			(hide yes)
			(effects
				(font
					(size 1.016 1.016)
					(thickness 0.1524)
				)
				(justify mirror)
			)
		)
		(duplicate_pad_numbers_are_jumpers no)
		(fp_line
			(start -0.2032 0)
			(end -0.4826 0)
			(stroke
				(width 0.2032)
				(type default)
			)
			(layer "B.SilkS")
		)
		(fp_line
			(start 0.4826 0)
			(end 0.2032 0)
			(stroke
				(width 0.2032)
				(type default)
			)
			(layer "B.SilkS")
		)
		(fp_rect
			(start 0.5842 1.3335)
			(end -0.5842 -1.3335)
			(stroke
				(width 0)
				(type default)
			)
			(fill no)
			(layer "B.CrtYd")
		)
		(fp_rect
			(start 0.5842 1.3335)
			(end -0.5842 -1.3335)
			(stroke
				(width 0)
				(type default)
			)
			(fill no)
			(layer "B.Fab")
		)
		(pad "1" smd custom
			(at 0 -0.762 90)
			(size 0.2159 0.2159)
			(layers "B.Cu" "B.Mask" "B.Paste")
			(net "P5V_B_2_CC")
			(options
				(clearance outline)
				(anchor circle)
			)
			(primitives
				(gr_poly
					(pts
						(arc
							(start -0.3302 0.4318)
							(mid -0.402042 0.402042)
							(end -0.4318 0.3302)
						)
						(arc
							(start -0.4318 -0.3302)
							(mid -0.402042 -0.402042)
							(end -0.3302 -0.4318)
						)
						(arc
							(start 0.3302 -0.4318)
							(mid 0.402042 -0.402042)
							(end 0.4318 -0.3302)
						)
						(arc
							(start 0.4318 0.3302)
							(mid 0.402042 0.402042)
							(end 0.3302 0.4318)
						)
					)
					(width 0)
					(fill yes)
				)
			)
		)
		(pad "2" smd custom
			(at 0 0.762 90)
			(size 0.2159 0.2159)
			(layers "B.Cu" "B.Mask" "B.Paste")
			(net "P5V_B_2_VFB_R")
			(options
				(clearance outline)
				(anchor circle)
			)
			(primitives
				(gr_poly
					(pts
						(arc
							(start -0.3302 0.4318)
							(mid -0.402042 0.402042)
							(end -0.4318 0.3302)
						)
						(arc
							(start -0.4318 -0.3302)
							(mid -0.402042 -0.402042)
							(end -0.3302 -0.4318)
						)
						(arc
							(start 0.3302 -0.4318)
							(mid 0.402042 -0.402042)
							(end 0.4318 -0.3302)
						)
						(arc
							(start 0.4318 0.3302)
							(mid 0.402042 0.402042)
							(end 0.3302 0.4318)
						)
					)
					(width 0)
					(fill yes)
				)
			)
		)
	)
	(footprint ""
		(layer "B.Cu")
		(at 14.417802 -223.01835 180)
		(property "Reference" "C617"
			(at 0 0 0)
			(layer "B.SilkS")
			(hide yes)
			(effects
				(font
					(size 1.27 1.27)
				)
				(justify mirror)
			)
		)
		(property "Value" "SC10U16V5KX-7-GP-U"
			(at 0.0762 -6.1214 180)
			(unlocked yes)
			(layer "B.Fab")
			(hide yes)
			(effects
				(font
					(size 1.016 1.016)
					(thickness 0.1524)
				)
				(justify mirror)
			)
		)
		(property "Device Type" "C805H58"
			(at 0.0762 -8.1534 180)
			(unlocked yes)
			(layer "B.Fab")
			(hide yes)
			(effects
				(font
					(size 1.016 1.016)
					(thickness 0.1524)
				)
				(justify mirror)
			)
		)
		(duplicate_pad_numbers_are_jumpers no)
		(fp_line
			(start -0.635 0)
			(end 0.635 0)
			(stroke
				(width 0.508)
				(type default)
			)
			(layer "B.SilkS")
		)
		(fp_rect
			(start 0.9652 1.778)
			(end -0.9652 -1.778)
			(stroke
				(width 0)
				(type default)
			)
			(fill no)
			(layer "B.CrtYd")
		)
		(fp_poly
			(pts
				(xy 0.9652 -1.778) (xy -0.9652 -1.778) (xy -0.9652 1.778) (xy 0.9652 1.778)
			)
			(stroke
				(width 0)
				(type default)
			)
			(fill no)
			(layer "B.Fab")
		)
		(pad "1" smd rect
			(at 0 -0.9652)
			(size 1.397 1.143)
			(layers "B.Cu" "B.Mask" "B.Paste")
			(net "P12V_B_1_VIN_U31")
		)
		(pad "2" smd rect
			(at 0 0.9652)
			(size 1.397 1.143)
			(layers "B.Cu" "B.Mask" "B.Paste")
			(net "GND")
		)
	)
	(footprint ""
		(layer "B.Cu")
		(at 427.065186 -112.701578 180)
		(property "Reference" "C673"
			(at 0 0 0)
			(layer "B.SilkS")
			(hide yes)
			(effects
				(font
					(size 1.27 1.27)
				)
				(justify mirror)
			)
		)
		(property "Value" "SC10U16V5KX-7-GP-U"
			(at 0.0762 -6.1214 180)
			(unlocked yes)
			(layer "B.Fab")
			(hide yes)
			(effects
				(font
					(size 1.016 1.016)
					(thickness 0.1524)
				)
				(justify mirror)
			)
		)
		(property "Device Type" "C805H58"
			(at 0.0762 -8.1534 180)
			(unlocked yes)
			(layer "B.Fab")
			(hide yes)
			(effects
				(font
					(size 1.016 1.016)
					(thickness 0.1524)
				)
				(justify mirror)
			)
		)
		(duplicate_pad_numbers_are_jumpers no)
		(fp_line
			(start -0.635 0)
			(end 0.635 0)
			(stroke
				(width 0.508)
				(type default)
			)
			(layer "B.SilkS")
		)
		(fp_rect
			(start 0.9652 1.778)
			(end -0.9652 -1.778)
			(stroke
				(width 0)
				(type default)
			)
			(fill no)
			(layer "B.CrtYd")
		)
		(fp_poly
			(pts
				(xy 0.9652 -1.778) (xy -0.9652 -1.778) (xy -0.9652 1.778) (xy 0.9652 1.778)
			)
			(stroke
				(width 0)
				(type default)
			)
			(fill no)
			(layer "B.Fab")
		)
		(pad "1" smd rect
			(at 0 -0.9652)
			(size 1.397 1.143)
			(layers "B.Cu" "B.Mask" "B.Paste")
			(net "P12V_B_4_VIN_U34")
		)
		(pad "2" smd rect
			(at 0 0.9652)
			(size 1.397 1.143)
			(layers "B.Cu" "B.Mask" "B.Paste")
			(net "GND")
		)
	)
	(footprint ""
		(layer "B.Cu")
		(at 444.820802 -220.09735 90)
		(property "Reference" "L5"
			(at 0 0 90)
			(layer "B.SilkS")
			(hide yes)
			(effects
				(font
					(size 1.27 1.27)
				)
				(justify mirror)
			)
		)
		(property "Value" "BLM21PG220SN1DGP"
			(at -0.0254 -5.6896 90)
			(unlocked yes)
			(layer "B.Fab")
			(hide yes)
			(effects
				(font
					(size 1.016 1.016)
					(thickness 0.1524)
				)
				(justify mirror)
			)
		)
		(property "Device Type" "L20125H42"
			(at -0.0254 -7.5946 90)
			(unlocked yes)
			(layer "B.Fab")
			(hide yes)
			(effects
				(font
					(size 1.016 1.016)
					(thickness 0.1524)
				)
				(justify mirror)
			)
		)
		(duplicate_pad_numbers_are_jumpers no)
		(fp_line
			(start 0.9144 -1.7018)
			(end 0.9144 1.7018)
			(stroke
				(width 0.1524)
				(type default)
			)
			(layer "B.SilkS")
		)
		(fp_line
			(start -0.9144 -1.7018)
			(end 0.9144 -1.7018)
			(stroke
				(width 0.1524)
				(type default)
			)
			(layer "B.SilkS")
		)
		(fp_line
			(start 0.9144 1.7018)
			(end -0.9144 1.7018)
			(stroke
				(width 0.1524)
				(type default)
			)
			(layer "B.SilkS")
		)
		(fp_line
			(start -0.9144 1.7018)
			(end -0.9144 -1.7018)
			(stroke
				(width 0.1524)
				(type default)
			)
			(layer "B.SilkS")
		)
		(fp_rect
			(start 1.0033 1.778)
			(end -1.0033 -1.778)
			(stroke
				(width 0)
				(type default)
			)
			(fill no)
			(layer "B.CrtYd")
		)
		(fp_poly
			(pts
				(xy 1.0033 -1.778) (xy -1.0033 -1.778) (xy -1.0033 1.778) (xy 1.0033 1.778)
			)
			(stroke
				(width 0)
				(type default)
			)
			(fill no)
			(layer "B.Fab")
		)
		(pad "1" smd rect
			(at 0 -0.9652 270)
			(size 1.397 1.143)
			(layers "B.Cu" "B.Mask" "B.Paste")
			(net "P12V_B")
		)
		(pad "2" smd rect
			(at 0 0.9652 270)
			(size 1.397 1.143)
			(layers "B.Cu" "B.Mask" "B.Paste")
			(net "P12V_B_3_VIN_U33")
		)
	)
	(footprint ""
		(layer "B.Cu")
		(at 32.293814 -229.093776 180)
		(property "Reference" "C627"
			(at 0 0 0)
			(layer "B.SilkS")
			(hide yes)
			(effects
				(font
					(size 1.27 1.27)
				)
				(justify mirror)
			)
		)
		(property "Value" "SCD1U50V3KX-GP"
			(at 0 -2.8194 180)
			(unlocked yes)
			(layer "B.Fab")
			(hide yes)
			(effects
				(font
					(size 1.016 1.016)
					(thickness 0.1524)
				)
				(justify mirror)
			)
		)
		(property "Device Type" "C603H36"
			(at 0 -4.3434 180)
			(unlocked yes)
			(layer "B.Fab")
			(hide yes)
			(effects
				(font
					(size 1.016 1.016)
					(thickness 0.1524)
				)
				(justify mirror)
			)
		)
		(duplicate_pad_numbers_are_jumpers no)
		(fp_line
			(start -0.508 0)
			(end 0.508 0)
			(stroke
				(width 0.2032)
				(type default)
			)
			(layer "B.SilkS")
		)
		(fp_rect
			(start 0.5842 1.3335)
			(end -0.5842 -1.3335)
			(stroke
				(width 0)
				(type default)
			)
			(fill no)
			(layer "B.CrtYd")
		)
		(fp_rect
			(start 0.5842 1.3335)
			(end -0.5842 -1.3335)
			(stroke
				(width 0)
				(type default)
			)
			(fill no)
			(layer "B.Fab")
		)
		(pad "1" smd custom
			(at 0 -0.762)
			(size 0.2159 0.2159)
			(layers "B.Cu" "B.Mask" "B.Paste")
			(net "P5V_B_1")
			(options
				(clearance outline)
				(anchor circle)
			)
			(primitives
				(gr_poly
					(pts
						(arc
							(start -0.3302 0.4318)
							(mid -0.402042 0.402042)
							(end -0.4318 0.3302)
						)
						(arc
							(start -0.4318 -0.3302)
							(mid -0.402042 -0.402042)
							(end -0.3302 -0.4318)
						)
						(arc
							(start 0.3302 -0.4318)
							(mid 0.402042 -0.402042)
							(end 0.4318 -0.3302)
						)
						(arc
							(start 0.4318 0.3302)
							(mid 0.402042 0.402042)
							(end 0.3302 0.4318)
						)
					)
					(width 0)
					(fill yes)
				)
			)
		)
		(pad "2" smd custom
			(at 0 0.762)
			(size 0.2159 0.2159)
			(layers "B.Cu" "B.Mask" "B.Paste")
			(net "P5V_B_1_LL_R")
			(options
				(clearance outline)
				(anchor circle)
			)
			(primitives
				(gr_poly
					(pts
						(arc
							(start -0.3302 0.4318)
							(mid -0.402042 0.402042)
							(end -0.4318 0.3302)
						)
						(arc
							(start -0.4318 -0.3302)
							(mid -0.402042 -0.402042)
							(end -0.3302 -0.4318)
						)
						(arc
							(start 0.3302 -0.4318)
							(mid 0.402042 -0.402042)
							(end 0.4318 -0.3302)
						)
						(arc
							(start 0.4318 0.3302)
							(mid 0.402042 0.402042)
							(end 0.3302 0.4318)
						)
					)
					(width 0)
					(fill yes)
				)
			)
		)
	)
	(footprint ""
		(layer "B.Cu")
		(at 484.317802 -228.35235 180)
		(property "Reference" "C669"
			(at 0 0 0)
			(layer "B.SilkS")
			(hide yes)
			(effects
				(font
					(size 1.27 1.27)
				)
				(justify mirror)
			)
		)
		(property "Value" "SC10U16V5KX-7-GP-U"
			(at 0.0762 -6.1214 180)
			(unlocked yes)
			(layer "B.Fab")
			(hide yes)
			(effects
				(font
					(size 1.016 1.016)
					(thickness 0.1524)
				)
				(justify mirror)
			)
		)
		(property "Device Type" "C805H58"
			(at 0.0762 -8.1534 180)
			(unlocked yes)
			(layer "B.Fab")
			(hide yes)
			(effects
				(font
					(size 1.016 1.016)
					(thickness 0.1524)
				)
				(justify mirror)
			)
		)
		(duplicate_pad_numbers_are_jumpers no)
		(fp_line
			(start -0.635 0)
			(end 0.635 0)
			(stroke
				(width 0.508)
				(type default)
			)
			(layer "B.SilkS")
		)
		(fp_rect
			(start 0.9652 1.778)
			(end -0.9652 -1.778)
			(stroke
				(width 0)
				(type default)
			)
			(fill no)
			(layer "B.CrtYd")
		)
		(fp_poly
			(pts
				(xy 0.9652 -1.778) (xy -0.9652 -1.778) (xy -0.9652 1.778) (xy 0.9652 1.778)
			)
			(stroke
				(width 0)
				(type default)
			)
			(fill no)
			(layer "B.Fab")
		)
		(pad "1" smd rect
			(at 0 -0.9652)
			(size 1.397 1.143)
			(layers "B.Cu" "B.Mask" "B.Paste")
			(net "P5V_B_3")
		)
		(pad "2" smd rect
			(at 0 0.9652)
			(size 1.397 1.143)
			(layers "B.Cu" "B.Mask" "B.Paste")
			(net "GND")
		)
	)
	(footprint ""
		(layer "B.Cu")
		(at 206.756 -338.582 90)
		(property "Reference" "R1017"
			(at 0 0 90)
			(layer "B.SilkS")
			(hide yes)
			(effects
				(font
					(size 1.27 1.27)
				)
				(justify mirror)
			)
		)
		(property "Value" "10R5F-1-GP"
			(at 0 -8.9535 90)
			(unlocked yes)
			(layer "B.Fab")
			(hide yes)
			(effects
				(font
					(size 1.27 1.016)
					(thickness 0.1524)
				)
				(justify mirror)
			)
		)
		(property "Device Type" "R805H24"
			(at 0 -10.6299 90)
			(unlocked yes)
			(layer "B.Fab")
			(hide yes)
			(effects
				(font
					(size 1.27 1.016)
					(thickness 0.1524)
				)
				(justify mirror)
			)
		)
		(duplicate_pad_numbers_are_jumpers no)
		(fp_line
			(start 0.889 -1.7018)
			(end 0.889 0.2794)
			(stroke
				(width 0.1524)
				(type default)
			)
			(layer "B.SilkS")
		)
		(fp_line
			(start -0.889 -1.7018)
			(end 0.889 -1.7018)
			(stroke
				(width 0.1524)
				(type default)
			)
			(layer "B.SilkS")
		)
		(fp_line
			(start -0.889 -1.7018)
			(end -0.889 -0.381)
			(stroke
				(width 0.1524)
				(type default)
			)
			(layer "B.SilkS")
		)
		(fp_line
			(start 0.889 0.0762)
			(end 0.889 1.7018)
			(stroke
				(width 0.1524)
				(type default)
			)
			(layer "B.SilkS")
		)
		(fp_line
			(start 0.889 1.7018)
			(end -0.889 1.7018)
			(stroke
				(width 0.1524)
				(type default)
			)
			(layer "B.SilkS")
		)
		(fp_line
			(start -0.889 1.7018)
			(end -0.889 -0.508)
			(stroke
				(width 0.1524)
				(type default)
			)
			(layer "B.SilkS")
		)
		(fp_poly
			(pts
				(xy -0.9652 -1.778) (xy -0.9652 1.778) (xy 0.9652 1.778) (xy 0.9652 -1.778)
			)
			(stroke
				(width 0)
				(type default)
			)
			(fill no)
			(layer "B.CrtYd")
		)
		(fp_rect
			(start 0.9652 1.778)
			(end -0.9652 -1.778)
			(stroke
				(width 0)
				(type default)
			)
			(fill no)
			(layer "B.Fab")
		)
		(pad "1" smd rect
			(at 0 -0.9652 270)
			(size 1.397 1.143)
			(layers "B.Cu" "B.Mask" "B.Paste")
			(net "MB0_12V_CTRL_GATE3")
		)
		(pad "2" smd rect
			(at 0 0.9652 270)
			(size 1.397 1.143)
			(layers "B.Cu" "B.Mask" "B.Paste")
			(net "MB0_CM_GATE_R")
		)
	)
	(footprint ""
		(layer "B.Cu")
		(at 443.895988 -119.309642 -90)
		(property "Reference" "R1163"
			(at 0 0 90)
			(layer "B.SilkS")
			(hide yes)
			(effects
				(font
					(size 1.27 1.27)
				)
				(justify mirror)
			)
		)
		(property "Value" "10R3F-GP"
			(at 0.0254 -2.5146 270)
			(unlocked yes)
			(layer "B.Fab")
			(hide yes)
			(effects
				(font
					(size 1.016 1.016)
					(thickness 0.1524)
				)
				(justify mirror)
			)
		)
		(property "Device Type" "R603H22"
			(at 0.0254 -4.0386 270)
			(unlocked yes)
			(layer "B.Fab")
			(hide yes)
			(effects
				(font
					(size 1.016 1.016)
					(thickness 0.1524)
				)
				(justify mirror)
			)
		)
		(duplicate_pad_numbers_are_jumpers no)
		(fp_line
			(start -0.2032 0)
			(end -0.4826 0)
			(stroke
				(width 0.2032)
				(type default)
			)
			(layer "B.SilkS")
		)
		(fp_line
			(start 0.4826 0)
			(end 0.2032 0)
			(stroke
				(width 0.2032)
				(type default)
			)
			(layer "B.SilkS")
		)
		(fp_rect
			(start 0.5842 1.3335)
			(end -0.5842 -1.3335)
			(stroke
				(width 0)
				(type default)
			)
			(fill no)
			(layer "B.CrtYd")
		)
		(fp_rect
			(start 0.5842 1.3335)
			(end -0.5842 -1.3335)
			(stroke
				(width 0)
				(type default)
			)
			(fill no)
			(layer "B.Fab")
		)
		(pad "1" smd custom
			(at 0 -0.762 90)
			(size 0.2159 0.2159)
			(layers "B.Cu" "B.Mask" "B.Paste")
			(net "P5V_B_4_CC")
			(options
				(clearance outline)
				(anchor circle)
			)
			(primitives
				(gr_poly
					(pts
						(arc
							(start -0.3302 0.4318)
							(mid -0.402042 0.402042)
							(end -0.4318 0.3302)
						)
						(arc
							(start -0.4318 -0.3302)
							(mid -0.402042 -0.402042)
							(end -0.3302 -0.4318)
						)
						(arc
							(start 0.3302 -0.4318)
							(mid 0.402042 -0.402042)
							(end 0.4318 -0.3302)
						)
						(arc
							(start 0.4318 0.3302)
							(mid 0.402042 0.402042)
							(end 0.3302 0.4318)
						)
					)
					(width 0)
					(fill yes)
				)
			)
		)
		(pad "2" smd custom
			(at 0 0.762 90)
			(size 0.2159 0.2159)
			(layers "B.Cu" "B.Mask" "B.Paste")
			(net "P5V_B_4_VFB_R")
			(options
				(clearance outline)
				(anchor circle)
			)
			(primitives
				(gr_poly
					(pts
						(arc
							(start -0.3302 0.4318)
							(mid -0.402042 0.402042)
							(end -0.4318 0.3302)
						)
						(arc
							(start -0.4318 -0.3302)
							(mid -0.402042 -0.402042)
							(end -0.3302 -0.4318)
						)
						(arc
							(start 0.3302 -0.4318)
							(mid 0.402042 -0.402042)
							(end 0.4318 -0.3302)
						)
						(arc
							(start 0.4318 0.3302)
							(mid 0.402042 0.402042)
							(end 0.3302 0.4318)
						)
					)
					(width 0)
					(fill yes)
				)
			)
		)
	)
	(footprint ""
		(layer "B.Cu")
		(at 222.631 -355.473 180)
		(property "Reference" "C516"
			(at 0 0 0)
			(layer "B.SilkS")
			(hide yes)
			(effects
				(font
					(size 1.27 1.27)
				)
				(justify mirror)
			)
		)
		(property "Value" "SC22U25V6KX-2-GP-U"
			(at 2.860802 -5.279644 180)
			(unlocked yes)
			(layer "B.Fab")
			(hide yes)
			(effects
				(font
					(size 1.016 1.016)
					(thickness 0.1524)
				)
				(justify mirror)
			)
		)
		(property "Device Type" "C1206-TO0D3H75"
			(at 2.860802 -6.803644 180)
			(unlocked yes)
			(layer "B.Fab")
			(hide yes)
			(effects
				(font
					(size 1.016 1.016)
					(thickness 0.1524)
				)
				(justify mirror)
			)
		)
		(duplicate_pad_numbers_are_jumpers no)
		(fp_line
			(start 1.3081 2.3749)
			(end 1.3081 -2.3749)
			(stroke
				(width 0.1524)
				(type default)
			)
			(layer "B.SilkS")
		)
		(fp_line
			(start 1.3081 -2.3749)
			(end -1.3081 -2.3749)
			(stroke
				(width 0.1524)
				(type default)
			)
			(layer "B.SilkS")
		)
		(fp_line
			(start -1.3081 2.3749)
			(end 1.3081 2.3749)
			(stroke
				(width 0.1524)
				(type default)
			)
			(layer "B.SilkS")
		)
		(fp_line
			(start -1.3081 -2.3749)
			(end -1.3081 2.3749)
			(stroke
				(width 0.1524)
				(type default)
			)
			(layer "B.SilkS")
		)
		(fp_rect
			(start 0.8001 1.6002)
			(end -0.8001 -1.6002)
			(stroke
				(width 0)
				(type default)
			)
			(fill no)
			(layer "B.CrtYd")
		)
		(fp_poly
			(pts
				(xy 1.5621 2.4511) (xy 1.5621 1.6002) (xy -0.8001 1.6002) (xy -0.8001 -1.6002) (xy 0.8001 -1.6002)
				(xy 0.8001 1.5875) (xy 1.5621 1.5875) (xy 1.5621 -2.4511) (xy -1.5621 -2.4511) (xy -1.5621 2.4511)
			)
			(stroke
				(width 0)
				(type default)
			)
			(fill no)
			(layer "B.CrtYd")
		)
		(fp_rect
			(start 1.5621 2.4511)
			(end -1.5621 -2.4511)
			(stroke
				(width 0)
				(type default)
			)
			(fill no)
			(layer "B.Fab")
		)
		(pad "1" smd rect
			(at 0 -1.392936)
			(size 2.1082 1.4478)
			(layers "B.Cu" "B.Mask" "B.Paste")
			(net "P12V_IN")
		)
		(pad "2" smd rect
			(at 0 1.392936)
			(size 2.1082 1.4478)
			(layers "B.Cu" "B.Mask" "B.Paste")
			(net "GND")
		)
	)
	(footprint ""
		(layer "B.Cu")
		(at 424.906186 -112.193578 180)
		(property "Reference" "R1156"
			(at 0 0 0)
			(layer "B.SilkS")
			(hide yes)
			(effects
				(font
					(size 1.27 1.27)
				)
				(justify mirror)
			)
		)
		(property "Value" "2D2R3-1-U-GP"
			(at 0.0254 -2.5146 180)
			(unlocked yes)
			(layer "B.Fab")
			(hide yes)
			(effects
				(font
					(size 1.016 1.016)
					(thickness 0.1524)
				)
				(justify mirror)
			)
		)
		(property "Device Type" "R603H22"
			(at 0.0254 -4.0386 180)
			(unlocked yes)
			(layer "B.Fab")
			(hide yes)
			(effects
				(font
					(size 1.016 1.016)
					(thickness 0.1524)
				)
				(justify mirror)
			)
		)
		(duplicate_pad_numbers_are_jumpers no)
		(fp_line
			(start 0.4826 0)
			(end 0.2032 0)
			(stroke
				(width 0.2032)
				(type default)
			)
			(layer "B.SilkS")
		)
		(fp_line
			(start -0.2032 0)
			(end -0.4826 0)
			(stroke
				(width 0.2032)
				(type default)
			)
			(layer "B.SilkS")
		)
		(fp_rect
			(start 0.5842 1.3335)
			(end -0.5842 -1.3335)
			(stroke
				(width 0)
				(type default)
			)
			(fill no)
			(layer "B.CrtYd")
		)
		(fp_rect
			(start 0.5842 1.3335)
			(end -0.5842 -1.3335)
			(stroke
				(width 0)
				(type default)
			)
			(fill no)
			(layer "B.Fab")
		)
		(pad "1" smd custom
			(at 0 -0.762)
			(size 0.2159 0.2159)
			(layers "B.Cu" "B.Mask" "B.Paste")
			(net "P12V_B")
			(options
				(clearance outline)
				(anchor circle)
			)
			(primitives
				(gr_poly
					(pts
						(arc
							(start -0.3302 0.4318)
							(mid -0.402042 0.402042)
							(end -0.4318 0.3302)
						)
						(arc
							(start -0.4318 -0.3302)
							(mid -0.402042 -0.402042)
							(end -0.3302 -0.4318)
						)
						(arc
							(start 0.3302 -0.4318)
							(mid 0.402042 -0.402042)
							(end 0.4318 -0.3302)
						)
						(arc
							(start 0.4318 0.3302)
							(mid 0.402042 0.402042)
							(end 0.3302 0.4318)
						)
					)
					(width 0)
					(fill yes)
				)
			)
		)
		(pad "2" smd custom
			(at 0 0.762)
			(size 0.2159 0.2159)
			(layers "B.Cu" "B.Mask" "B.Paste")
			(net "P12V_B_4_VDD_U34")
			(options
				(clearance outline)
				(anchor circle)
			)
			(primitives
				(gr_poly
					(pts
						(arc
							(start -0.3302 0.4318)
							(mid -0.402042 0.402042)
							(end -0.4318 0.3302)
						)
						(arc
							(start -0.4318 -0.3302)
							(mid -0.402042 -0.402042)
							(end -0.3302 -0.4318)
						)
						(arc
							(start 0.3302 -0.4318)
							(mid 0.402042 -0.402042)
							(end 0.4318 -0.3302)
						)
						(arc
							(start 0.4318 0.3302)
							(mid 0.402042 0.402042)
							(end 0.3302 0.4318)
						)
					)
					(width 0)
					(fill yes)
				)
			)
		)
	)
	(footprint ""
		(layer "B.Cu")
		(at 429.097186 -112.701578 180)
		(property "Reference" "C672"
			(at 0 0 0)
			(layer "B.SilkS")
			(hide yes)
			(effects
				(font
					(size 1.27 1.27)
				)
				(justify mirror)
			)
		)
		(property "Value" "SC10U16V5KX-7-GP-U"
			(at 0.0762 -6.1214 180)
			(unlocked yes)
			(layer "B.Fab")
			(hide yes)
			(effects
				(font
					(size 1.016 1.016)
					(thickness 0.1524)
				)
				(justify mirror)
			)
		)
		(property "Device Type" "C805H58"
			(at 0.0762 -8.1534 180)
			(unlocked yes)
			(layer "B.Fab")
			(hide yes)
			(effects
				(font
					(size 1.016 1.016)
					(thickness 0.1524)
				)
				(justify mirror)
			)
		)
		(duplicate_pad_numbers_are_jumpers no)
		(fp_line
			(start -0.635 0)
			(end 0.635 0)
			(stroke
				(width 0.508)
				(type default)
			)
			(layer "B.SilkS")
		)
		(fp_rect
			(start 0.9652 1.778)
			(end -0.9652 -1.778)
			(stroke
				(width 0)
				(type default)
			)
			(fill no)
			(layer "B.CrtYd")
		)
		(fp_poly
			(pts
				(xy 0.9652 -1.778) (xy -0.9652 -1.778) (xy -0.9652 1.778) (xy 0.9652 1.778)
			)
			(stroke
				(width 0)
				(type default)
			)
			(fill no)
			(layer "B.Fab")
		)
		(pad "1" smd rect
			(at 0 -0.9652)
			(size 1.397 1.143)
			(layers "B.Cu" "B.Mask" "B.Paste")
			(net "P12V_B_4_VIN_U34")
		)
		(pad "2" smd rect
			(at 0 0.9652)
			(size 1.397 1.143)
			(layers "B.Cu" "B.Mask" "B.Paste")
			(net "GND")
		)
	)
	(footprint ""
		(layer "B.Cu")
		(at 224.55124 -329.065128)
		(property "Reference" "C512"
			(at 0 0 0)
			(layer "B.SilkS")
			(hide yes)
			(effects
				(font
					(size 1.27 1.27)
				)
				(justify mirror)
			)
		)
		(property "Value" "SC22U25V6KX-2-GP-U"
			(at 2.860802 -5.279644 0)
			(unlocked yes)
			(layer "B.Fab")
			(hide yes)
			(effects
				(font
					(size 1.016 1.016)
					(thickness 0.1524)
				)
				(justify mirror)
			)
		)
		(property "Device Type" "C1206-TO0D3H75"
			(at 2.860802 -6.803644 0)
			(unlocked yes)
			(layer "B.Fab")
			(hide yes)
			(effects
				(font
					(size 1.016 1.016)
					(thickness 0.1524)
				)
				(justify mirror)
			)
		)
		(duplicate_pad_numbers_are_jumpers no)
		(fp_line
			(start -1.3081 -2.3749)
			(end -1.3081 2.3749)
			(stroke
				(width 0.1524)
				(type default)
			)
			(layer "B.SilkS")
		)
		(fp_line
			(start -1.3081 2.3749)
			(end 1.3081 2.3749)
			(stroke
				(width 0.1524)
				(type default)
			)
			(layer "B.SilkS")
		)
		(fp_line
			(start 1.3081 -2.3749)
			(end -1.3081 -2.3749)
			(stroke
				(width 0.1524)
				(type default)
			)
			(layer "B.SilkS")
		)
		(fp_line
			(start 1.3081 2.3749)
			(end 1.3081 -2.3749)
			(stroke
				(width 0.1524)
				(type default)
			)
			(layer "B.SilkS")
		)
		(fp_rect
			(start 0.8001 1.6002)
			(end -0.8001 -1.6002)
			(stroke
				(width 0)
				(type default)
			)
			(fill no)
			(layer "B.CrtYd")
		)
		(fp_poly
			(pts
				(xy 1.5621 2.4511) (xy 1.5621 1.6002) (xy -0.8001 1.6002) (xy -0.8001 -1.6002) (xy 0.8001 -1.6002)
				(xy 0.8001 1.5875) (xy 1.5621 1.5875) (xy 1.5621 -2.4511) (xy -1.5621 -2.4511) (xy -1.5621 2.4511)
			)
			(stroke
				(width 0)
				(type default)
			)
			(fill no)
			(layer "B.CrtYd")
		)
		(fp_rect
			(start 1.5621 2.4511)
			(end -1.5621 -2.4511)
			(stroke
				(width 0)
				(type default)
			)
			(fill no)
			(layer "B.Fab")
		)
		(pad "1" smd rect
			(at 0 -1.392936 180)
			(size 2.1082 1.4478)
			(layers "B.Cu" "B.Mask" "B.Paste")
			(net "P12V_IN")
		)
		(pad "2" smd rect
			(at 0 1.392936 180)
			(size 2.1082 1.4478)
			(layers "B.Cu" "B.Mask" "B.Paste")
			(net "GND")
		)
	)
	(footprint ""
		(layer "B.Cu")
		(at 241.935 -286.004 180)
		(property "Reference" "C705"
			(at 0 0 0)
			(layer "B.SilkS")
			(hide yes)
			(effects
				(font
					(size 1.27 1.27)
				)
				(justify mirror)
			)
		)
		(property "Value" "SC10U6D3V5KX-4GP"
			(at 0.0762 -6.1214 180)
			(unlocked yes)
			(layer "B.Fab")
			(hide yes)
			(effects
				(font
					(size 1.016 1.016)
					(thickness 0.1524)
				)
				(justify mirror)
			)
		)
		(property "Device Type" "C805H58"
			(at 0.0762 -8.1534 180)
			(unlocked yes)
			(layer "B.Fab")
			(hide yes)
			(effects
				(font
					(size 1.016 1.016)
					(thickness 0.1524)
				)
				(justify mirror)
			)
		)
		(duplicate_pad_numbers_are_jumpers no)
		(fp_line
			(start -0.635 0)
			(end 0.635 0)
			(stroke
				(width 0.508)
				(type default)
			)
			(layer "B.SilkS")
		)
		(fp_rect
			(start 0.9652 1.778)
			(end -0.9652 -1.778)
			(stroke
				(width 0)
				(type default)
			)
			(fill no)
			(layer "B.CrtYd")
		)
		(fp_poly
			(pts
				(xy 0.9652 -1.778) (xy -0.9652 -1.778) (xy -0.9652 1.778) (xy 0.9652 1.778)
			)
			(stroke
				(width 0)
				(type default)
			)
			(fill no)
			(layer "B.Fab")
		)
		(pad "1" smd rect
			(at 0 -0.9652)
			(size 1.397 1.143)
			(layers "B.Cu" "B.Mask" "B.Paste")
			(net "P3V3_STBY_B")
		)
		(pad "2" smd rect
			(at 0 0.9652)
			(size 1.397 1.143)
			(layers "B.Cu" "B.Mask" "B.Paste")
			(net "GND")
		)
	)
	(footprint ""
		(layer "B.Cu")
		(at 246.3546 -286.9692 180)
		(property "Reference" "C698"
			(at 0 0 0)
			(layer "B.SilkS")
			(hide yes)
			(effects
				(font
					(size 1.27 1.27)
				)
				(justify mirror)
			)
		)
		(property "Value" "SCD1U25V3KX-GP"
			(at 0 -2.8194 180)
			(unlocked yes)
			(layer "B.Fab")
			(hide yes)
			(effects
				(font
					(size 1.016 1.016)
					(thickness 0.1524)
				)
				(justify mirror)
			)
		)
		(property "Device Type" "C603H36"
			(at 0 -4.3434 180)
			(unlocked yes)
			(layer "B.Fab")
			(hide yes)
			(effects
				(font
					(size 1.016 1.016)
					(thickness 0.1524)
				)
				(justify mirror)
			)
		)
		(duplicate_pad_numbers_are_jumpers no)
		(fp_line
			(start -0.508 0)
			(end 0.508 0)
			(stroke
				(width 0.2032)
				(type default)
			)
			(layer "B.SilkS")
		)
		(fp_rect
			(start 0.5842 1.3335)
			(end -0.5842 -1.3335)
			(stroke
				(width 0)
				(type default)
			)
			(fill no)
			(layer "B.CrtYd")
		)
		(fp_rect
			(start 0.5842 1.3335)
			(end -0.5842 -1.3335)
			(stroke
				(width 0)
				(type default)
			)
			(fill no)
			(layer "B.Fab")
		)
		(pad "1" smd custom
			(at 0 -0.762)
			(size 0.2159 0.2159)
			(layers "B.Cu" "B.Mask" "B.Paste")
			(net "P3V3_STBY_B")
			(options
				(clearance outline)
				(anchor circle)
			)
			(primitives
				(gr_poly
					(pts
						(arc
							(start -0.3302 0.4318)
							(mid -0.402042 0.402042)
							(end -0.4318 0.3302)
						)
						(arc
							(start -0.4318 -0.3302)
							(mid -0.402042 -0.402042)
							(end -0.3302 -0.4318)
						)
						(arc
							(start 0.3302 -0.4318)
							(mid 0.402042 -0.402042)
							(end 0.4318 -0.3302)
						)
						(arc
							(start 0.4318 0.3302)
							(mid 0.402042 0.402042)
							(end 0.3302 0.4318)
						)
					)
					(width 0)
					(fill yes)
				)
			)
		)
		(pad "2" smd custom
			(at 0 0.762)
			(size 0.2159 0.2159)
			(layers "B.Cu" "B.Mask" "B.Paste")
			(net "P3V3_STBY_VFB_R")
			(options
				(clearance outline)
				(anchor circle)
			)
			(primitives
				(gr_poly
					(pts
						(arc
							(start -0.3302 0.4318)
							(mid -0.402042 0.402042)
							(end -0.4318 0.3302)
						)
						(arc
							(start -0.4318 -0.3302)
							(mid -0.402042 -0.402042)
							(end -0.3302 -0.4318)
						)
						(arc
							(start 0.3302 -0.4318)
							(mid 0.402042 -0.402042)
							(end 0.4318 -0.3302)
						)
						(arc
							(start 0.4318 0.3302)
							(mid 0.402042 0.402042)
							(end 0.3302 0.4318)
						)
					)
					(width 0)
					(fill yes)
				)
			)
		)
	)
	(footprint ""
		(layer "B.Cu")
		(at 40.78986 -114.246406 90)
		(property "Reference" "C645"
			(at 0 0 90)
			(layer "B.SilkS")
			(hide yes)
			(effects
				(font
					(size 1.27 1.27)
				)
				(justify mirror)
			)
		)
		(property "Value" "SC1U16V3KX-5GP"
			(at 0 -2.8194 90)
			(unlocked yes)
			(layer "B.Fab")
			(hide yes)
			(effects
				(font
					(size 1.016 1.016)
					(thickness 0.1524)
				)
				(justify mirror)
			)
		)
		(property "Device Type" "C603H36"
			(at 0 -4.3434 90)
			(unlocked yes)
			(layer "B.Fab")
			(hide yes)
			(effects
				(font
					(size 1.016 1.016)
					(thickness 0.1524)
				)
				(justify mirror)
			)
		)
		(duplicate_pad_numbers_are_jumpers no)
		(fp_line
			(start -0.508 0)
			(end 0.508 0)
			(stroke
				(width 0.2032)
				(type default)
			)
			(layer "B.SilkS")
		)
		(fp_rect
			(start 0.5842 1.3335)
			(end -0.5842 -1.3335)
			(stroke
				(width 0)
				(type default)
			)
			(fill no)
			(layer "B.CrtYd")
		)
		(fp_rect
			(start 0.5842 1.3335)
			(end -0.5842 -1.3335)
			(stroke
				(width 0)
				(type default)
			)
			(fill no)
			(layer "B.Fab")
		)
		(pad "1" smd custom
			(at 0 -0.762 270)
			(size 0.2159 0.2159)
			(layers "B.Cu" "B.Mask" "B.Paste")
			(net "GND")
			(options
				(clearance outline)
				(anchor circle)
			)
			(primitives
				(gr_poly
					(pts
						(arc
							(start -0.3302 0.4318)
							(mid -0.402042 0.402042)
							(end -0.4318 0.3302)
						)
						(arc
							(start -0.4318 -0.3302)
							(mid -0.402042 -0.402042)
							(end -0.3302 -0.4318)
						)
						(arc
							(start 0.3302 -0.4318)
							(mid 0.402042 -0.402042)
							(end 0.4318 -0.3302)
						)
						(arc
							(start 0.4318 0.3302)
							(mid 0.402042 0.402042)
							(end 0.3302 0.4318)
						)
					)
					(width 0)
					(fill yes)
				)
			)
		)
		(pad "2" smd custom
			(at 0 0.762 270)
			(size 0.2159 0.2159)
			(layers "B.Cu" "B.Mask" "B.Paste")
			(net "P5V_B_2_VREG")
			(options
				(clearance outline)
				(anchor circle)
			)
			(primitives
				(gr_poly
					(pts
						(arc
							(start -0.3302 0.4318)
							(mid -0.402042 0.402042)
							(end -0.4318 0.3302)
						)
						(arc
							(start -0.4318 -0.3302)
							(mid -0.402042 -0.402042)
							(end -0.3302 -0.4318)
						)
						(arc
							(start 0.3302 -0.4318)
							(mid 0.402042 -0.402042)
							(end 0.4318 -0.3302)
						)
						(arc
							(start 0.4318 0.3302)
							(mid 0.402042 0.402042)
							(end 0.3302 0.4318)
						)
					)
					(width 0)
					(fill yes)
				)
			)
		)
	)
	(footprint ""
		(layer "B.Cu")
		(at 467.903814 -229.093776 180)
		(property "Reference" "C664"
			(at 0 0 0)
			(layer "B.SilkS")
			(hide yes)
			(effects
				(font
					(size 1.27 1.27)
				)
				(justify mirror)
			)
		)
		(property "Value" "SCD1U50V3KX-GP"
			(at 0 -2.8194 180)
			(unlocked yes)
			(layer "B.Fab")
			(hide yes)
			(effects
				(font
					(size 1.016 1.016)
					(thickness 0.1524)
				)
				(justify mirror)
			)
		)
		(property "Device Type" "C603H36"
			(at 0 -4.3434 180)
			(unlocked yes)
			(layer "B.Fab")
			(hide yes)
			(effects
				(font
					(size 1.016 1.016)
					(thickness 0.1524)
				)
				(justify mirror)
			)
		)
		(duplicate_pad_numbers_are_jumpers no)
		(fp_line
			(start -0.508 0)
			(end 0.508 0)
			(stroke
				(width 0.2032)
				(type default)
			)
			(layer "B.SilkS")
		)
		(fp_rect
			(start 0.5842 1.3335)
			(end -0.5842 -1.3335)
			(stroke
				(width 0)
				(type default)
			)
			(fill no)
			(layer "B.CrtYd")
		)
		(fp_rect
			(start 0.5842 1.3335)
			(end -0.5842 -1.3335)
			(stroke
				(width 0)
				(type default)
			)
			(fill no)
			(layer "B.Fab")
		)
		(pad "1" smd custom
			(at 0 -0.762)
			(size 0.2159 0.2159)
			(layers "B.Cu" "B.Mask" "B.Paste")
			(net "P5V_B_3")
			(options
				(clearance outline)
				(anchor circle)
			)
			(primitives
				(gr_poly
					(pts
						(arc
							(start -0.3302 0.4318)
							(mid -0.402042 0.402042)
							(end -0.4318 0.3302)
						)
						(arc
							(start -0.4318 -0.3302)
							(mid -0.402042 -0.402042)
							(end -0.3302 -0.4318)
						)
						(arc
							(start 0.3302 -0.4318)
							(mid 0.402042 -0.402042)
							(end 0.4318 -0.3302)
						)
						(arc
							(start 0.4318 0.3302)
							(mid 0.402042 0.402042)
							(end 0.3302 0.4318)
						)
					)
					(width 0)
					(fill yes)
				)
			)
		)
		(pad "2" smd custom
			(at 0 0.762)
			(size 0.2159 0.2159)
			(layers "B.Cu" "B.Mask" "B.Paste")
			(net "P5V_B_3_LL_R")
			(options
				(clearance outline)
				(anchor circle)
			)
			(primitives
				(gr_poly
					(pts
						(arc
							(start -0.3302 0.4318)
							(mid -0.402042 0.402042)
							(end -0.4318 0.3302)
						)
						(arc
							(start -0.4318 -0.3302)
							(mid -0.402042 -0.402042)
							(end -0.3302 -0.4318)
						)
						(arc
							(start 0.3302 -0.4318)
							(mid 0.402042 -0.402042)
							(end 0.4318 -0.3302)
						)
						(arc
							(start 0.4318 0.3302)
							(mid 0.402042 0.402042)
							(end 0.3302 0.4318)
						)
					)
					(width 0)
					(fill yes)
				)
			)
		)
	)
	(footprint ""
		(layer "B.Cu")
		(at 425.922186 -109.780578 90)
		(property "Reference" "L7"
			(at 0 0 90)
			(layer "B.SilkS")
			(hide yes)
			(effects
				(font
					(size 1.27 1.27)
				)
				(justify mirror)
			)
		)
		(property "Value" "BLM21PG220SN1DGP"
			(at -0.0254 -5.6896 90)
			(unlocked yes)
			(layer "B.Fab")
			(hide yes)
			(effects
				(font
					(size 1.016 1.016)
					(thickness 0.1524)
				)
				(justify mirror)
			)
		)
		(property "Device Type" "L20125H42"
			(at -0.0254 -7.5946 90)
			(unlocked yes)
			(layer "B.Fab")
			(hide yes)
			(effects
				(font
					(size 1.016 1.016)
					(thickness 0.1524)
				)
				(justify mirror)
			)
		)
		(duplicate_pad_numbers_are_jumpers no)
		(fp_line
			(start 0.9144 -1.7018)
			(end 0.9144 1.7018)
			(stroke
				(width 0.1524)
				(type default)
			)
			(layer "B.SilkS")
		)
		(fp_line
			(start -0.9144 -1.7018)
			(end 0.9144 -1.7018)
			(stroke
				(width 0.1524)
				(type default)
			)
			(layer "B.SilkS")
		)
		(fp_line
			(start 0.9144 1.7018)
			(end -0.9144 1.7018)
			(stroke
				(width 0.1524)
				(type default)
			)
			(layer "B.SilkS")
		)
		(fp_line
			(start -0.9144 1.7018)
			(end -0.9144 -1.7018)
			(stroke
				(width 0.1524)
				(type default)
			)
			(layer "B.SilkS")
		)
		(fp_rect
			(start 1.0033 1.778)
			(end -1.0033 -1.778)
			(stroke
				(width 0)
				(type default)
			)
			(fill no)
			(layer "B.CrtYd")
		)
		(fp_poly
			(pts
				(xy 1.0033 -1.778) (xy -1.0033 -1.778) (xy -1.0033 1.778) (xy 1.0033 1.778)
			)
			(stroke
				(width 0)
				(type default)
			)
			(fill no)
			(layer "B.Fab")
		)
		(pad "1" smd rect
			(at 0 -0.9652 270)
			(size 1.397 1.143)
			(layers "B.Cu" "B.Mask" "B.Paste")
			(net "P12V_B")
		)
		(pad "2" smd rect
			(at 0 0.9652 270)
			(size 1.397 1.143)
			(layers "B.Cu" "B.Mask" "B.Paste")
			(net "P12V_B_4_VIN_U34")
		)
	)
	(footprint ""
		(layer "B.Cu")
		(at 260.239002 -283.006546 90)
		(property "Reference" "C696"
			(at 0 0 90)
			(layer "B.SilkS")
			(hide yes)
			(effects
				(font
					(size 1.27 1.27)
				)
				(justify mirror)
			)
		)
		(property "Value" "SC1U16V3KX-5GP"
			(at 0 -2.8194 90)
			(unlocked yes)
			(layer "B.Fab")
			(hide yes)
			(effects
				(font
					(size 1.016 1.016)
					(thickness 0.1524)
				)
				(justify mirror)
			)
		)
		(property "Device Type" "C603H36"
			(at 0 -4.3434 90)
			(unlocked yes)
			(layer "B.Fab")
			(hide yes)
			(effects
				(font
					(size 1.016 1.016)
					(thickness 0.1524)
				)
				(justify mirror)
			)
		)
		(duplicate_pad_numbers_are_jumpers no)
		(fp_line
			(start -0.508 0)
			(end 0.508 0)
			(stroke
				(width 0.2032)
				(type default)
			)
			(layer "B.SilkS")
		)
		(fp_rect
			(start 0.5842 1.3335)
			(end -0.5842 -1.3335)
			(stroke
				(width 0)
				(type default)
			)
			(fill no)
			(layer "B.CrtYd")
		)
		(fp_rect
			(start 0.5842 1.3335)
			(end -0.5842 -1.3335)
			(stroke
				(width 0)
				(type default)
			)
			(fill no)
			(layer "B.Fab")
		)
		(pad "1" smd custom
			(at 0 -0.762 270)
			(size 0.2159 0.2159)
			(layers "B.Cu" "B.Mask" "B.Paste")
			(net "P3V3_STBY_VRG5")
			(options
				(clearance outline)
				(anchor circle)
			)
			(primitives
				(gr_poly
					(pts
						(arc
							(start -0.3302 0.4318)
							(mid -0.402042 0.402042)
							(end -0.4318 0.3302)
						)
						(arc
							(start -0.4318 -0.3302)
							(mid -0.402042 -0.402042)
							(end -0.3302 -0.4318)
						)
						(arc
							(start 0.3302 -0.4318)
							(mid 0.402042 -0.402042)
							(end 0.4318 -0.3302)
						)
						(arc
							(start 0.4318 0.3302)
							(mid 0.402042 0.402042)
							(end 0.3302 0.4318)
						)
					)
					(width 0)
					(fill yes)
				)
			)
		)
		(pad "2" smd custom
			(at 0 0.762 270)
			(size 0.2159 0.2159)
			(layers "B.Cu" "B.Mask" "B.Paste")
			(net "GND")
			(options
				(clearance outline)
				(anchor circle)
			)
			(primitives
				(gr_poly
					(pts
						(arc
							(start -0.3302 0.4318)
							(mid -0.402042 0.402042)
							(end -0.4318 0.3302)
						)
						(arc
							(start -0.4318 -0.3302)
							(mid -0.402042 -0.402042)
							(end -0.3302 -0.4318)
						)
						(arc
							(start 0.3302 -0.4318)
							(mid 0.402042 -0.402042)
							(end 0.4318 -0.3302)
						)
						(arc
							(start 0.4318 0.3302)
							(mid 0.402042 0.402042)
							(end 0.3302 0.4318)
						)
					)
					(width 0)
					(fill yes)
				)
			)
		)
	)
	(footprint ""
		(layer "B.Cu")
		(at 30.920944 -229.101396 180)
		(property "Reference" "R1103"
			(at 0 0 0)
			(layer "B.SilkS")
			(hide yes)
			(effects
				(font
					(size 1.27 1.27)
				)
				(justify mirror)
			)
		)
		(property "Value" "2K7R2F-GP"
			(at -0.064008 -3.993896 180)
			(unlocked yes)
			(layer "B.Fab")
			(hide yes)
			(effects
				(font
					(size 1.016 1.016)
					(thickness 0.1524)
				)
				(justify mirror)
			)
		)
		(property "Device Type" "R402H16"
			(at -0.064008 -5.517896 180)
			(unlocked yes)
			(layer "B.Fab")
			(hide yes)
			(effects
				(font
					(size 1.016 1.016)
					(thickness 0.1524)
				)
				(justify mirror)
			)
		)
		(duplicate_pad_numbers_are_jumpers no)
		(fp_line
			(start 0.508 -0.9398)
			(end 0.508 0.9398)
			(stroke
				(width 0.1524)
				(type default)
			)
			(layer "B.SilkS")
		)
		(fp_line
			(start -0.508 -0.9398)
			(end 0.508 -0.9398)
			(stroke
				(width 0.1524)
				(type default)
			)
			(layer "B.SilkS")
		)
		(fp_rect
			(start 0.508 0.9398)
			(end -0.508 -0.9398)
			(stroke
				(width 0)
				(type default)
			)
			(fill no)
			(layer "B.CrtYd")
		)
		(fp_rect
			(start 0.508 0.9398)
			(end -0.508 -0.9398)
			(stroke
				(width 0)
				(type default)
			)
			(fill no)
			(layer "B.Fab")
		)
		(pad "1" smd custom
			(at 0 -0.4445)
			(size 0.1397 0.1397)
			(layers "B.Cu" "B.Mask" "B.Paste")
			(net "P5V_B_1_LL")
			(options
				(clearance outline)
				(anchor circle)
			)
			(primitives
				(gr_poly
					(pts
						(arc
							(start -0.1778 0.2794)
							(mid -0.249642 0.249642)
							(end -0.2794 0.1778)
						)
						(arc
							(start -0.2794 -0.1778)
							(mid -0.249642 -0.249642)
							(end -0.1778 -0.2794)
						)
						(arc
							(start 0.1778 -0.2794)
							(mid 0.249642 -0.249642)
							(end 0.2794 -0.1778)
						)
						(arc
							(start 0.2794 0.1778)
							(mid 0.249642 0.249642)
							(end 0.1778 0.2794)
						)
					)
					(width 0)
					(fill yes)
				)
			)
		)
		(pad "2" smd custom
			(at 0 0.4445)
			(size 0.1397 0.1397)
			(layers "B.Cu" "B.Mask" "B.Paste")
			(net "P5V_B_1_LL_R")
			(options
				(clearance outline)
				(anchor circle)
			)
			(primitives
				(gr_poly
					(pts
						(arc
							(start -0.1778 0.2794)
							(mid -0.249642 0.249642)
							(end -0.2794 0.1778)
						)
						(arc
							(start -0.2794 -0.1778)
							(mid -0.249642 -0.249642)
							(end -0.1778 -0.2794)
						)
						(arc
							(start 0.1778 -0.2794)
							(mid 0.249642 -0.249642)
							(end 0.2794 -0.1778)
						)
						(arc
							(start 0.2794 0.1778)
							(mid 0.249642 0.249642)
							(end 0.1778 0.2794)
						)
					)
					(width 0)
					(fill yes)
				)
			)
		)
	)
	(footprint ""
		(layer "B.Cu")
		(at 260.7818 -287.5026)
		(property "Reference" "R1177"
			(at 0 0 0)
			(layer "B.SilkS")
			(hide yes)
			(effects
				(font
					(size 1.27 1.27)
				)
				(justify mirror)
			)
		)
		(property "Value" "33KR2J-3-GP"
			(at -0.064008 -3.993896 0)
			(unlocked yes)
			(layer "B.Fab")
			(hide yes)
			(effects
				(font
					(size 1.016 1.016)
					(thickness 0.1524)
				)
				(justify mirror)
			)
		)
		(property "Device Type" "R402H16"
			(at -0.064008 -5.517896 0)
			(unlocked yes)
			(layer "B.Fab")
			(hide yes)
			(effects
				(font
					(size 1.016 1.016)
					(thickness 0.1524)
				)
				(justify mirror)
			)
		)
		(duplicate_pad_numbers_are_jumpers no)
		(fp_line
			(start -0.508 -0.9398)
			(end 0.508 -0.9398)
			(stroke
				(width 0.1524)
				(type default)
			)
			(layer "B.SilkS")
		)
		(fp_line
			(start 0.508 -0.9398)
			(end 0.508 0.9398)
			(stroke
				(width 0.1524)
				(type default)
			)
			(layer "B.SilkS")
		)
		(fp_rect
			(start 0.508 0.9398)
			(end -0.508 -0.9398)
			(stroke
				(width 0)
				(type default)
			)
			(fill no)
			(layer "B.CrtYd")
		)
		(fp_rect
			(start 0.508 0.9398)
			(end -0.508 -0.9398)
			(stroke
				(width 0)
				(type default)
			)
			(fill no)
			(layer "B.Fab")
		)
		(pad "1" smd custom
			(at 0 -0.4445 180)
			(size 0.1397 0.1397)
			(layers "B.Cu" "B.Mask" "B.Paste")
			(net "P3V3_STBY_CC_R")
			(options
				(clearance outline)
				(anchor circle)
			)
			(primitives
				(gr_poly
					(pts
						(arc
							(start -0.1778 0.2794)
							(mid -0.249642 0.249642)
							(end -0.2794 0.1778)
						)
						(arc
							(start -0.2794 -0.1778)
							(mid -0.249642 -0.249642)
							(end -0.1778 -0.2794)
						)
						(arc
							(start 0.1778 -0.2794)
							(mid 0.249642 -0.249642)
							(end 0.2794 -0.1778)
						)
						(arc
							(start 0.2794 0.1778)
							(mid 0.249642 0.249642)
							(end 0.1778 0.2794)
						)
					)
					(width 0)
					(fill yes)
				)
			)
		)
		(pad "2" smd custom
			(at 0 0.4445 180)
			(size 0.1397 0.1397)
			(layers "B.Cu" "B.Mask" "B.Paste")
			(net "P3V3_STBY_VFB")
			(options
				(clearance outline)
				(anchor circle)
			)
			(primitives
				(gr_poly
					(pts
						(arc
							(start -0.1778 0.2794)
							(mid -0.249642 0.249642)
							(end -0.2794 0.1778)
						)
						(arc
							(start -0.2794 -0.1778)
							(mid -0.249642 -0.249642)
							(end -0.1778 -0.2794)
						)
						(arc
							(start 0.1778 -0.2794)
							(mid 0.249642 -0.249642)
							(end 0.2794 -0.1778)
						)
						(arc
							(start 0.2794 0.1778)
							(mid 0.249642 0.249642)
							(end 0.1778 0.2794)
						)
					)
					(width 0)
					(fill yes)
				)
			)
		)
	)
	(footprint ""
		(layer "B.Cu")
		(at 40.28186 -115.897406 -90)
		(property "Reference" "C642"
			(at 0 0 90)
			(layer "B.SilkS")
			(hide yes)
			(effects
				(font
					(size 1.27 1.27)
				)
				(justify mirror)
			)
		)
		(property "Value" "SC4D7U25V5KX-1-GP"
			(at 0.0762 -6.1214 270)
			(unlocked yes)
			(layer "B.Fab")
			(hide yes)
			(effects
				(font
					(size 1.016 1.016)
					(thickness 0.1524)
				)
				(justify mirror)
			)
		)
		(property "Device Type" "C805H58"
			(at 0.0762 -8.1534 270)
			(unlocked yes)
			(layer "B.Fab")
			(hide yes)
			(effects
				(font
					(size 1.016 1.016)
					(thickness 0.1524)
				)
				(justify mirror)
			)
		)
		(duplicate_pad_numbers_are_jumpers no)
		(fp_line
			(start -0.635 0)
			(end 0.635 0)
			(stroke
				(width 0.508)
				(type default)
			)
			(layer "B.SilkS")
		)
		(fp_rect
			(start 0.9652 1.778)
			(end -0.9652 -1.778)
			(stroke
				(width 0)
				(type default)
			)
			(fill no)
			(layer "B.CrtYd")
		)
		(fp_poly
			(pts
				(xy 0.9652 -1.778) (xy -0.9652 -1.778) (xy -0.9652 1.778) (xy 0.9652 1.778)
			)
			(stroke
				(width 0)
				(type default)
			)
			(fill no)
			(layer "B.Fab")
		)
		(pad "1" smd rect
			(at 0 -0.9652 90)
			(size 1.397 1.143)
			(layers "B.Cu" "B.Mask" "B.Paste")
			(net "P12V_B_2_VDD_U32")
		)
		(pad "2" smd rect
			(at 0 0.9652 90)
			(size 1.397 1.143)
			(layers "B.Cu" "B.Mask" "B.Paste")
			(net "GND")
		)
	)
	(footprint ""
		(layer "B.Cu")
		(at 218.44 -355.473 180)
		(property "Reference" "C515"
			(at 0 0 0)
			(layer "B.SilkS")
			(hide yes)
			(effects
				(font
					(size 1.27 1.27)
				)
				(justify mirror)
			)
		)
		(property "Value" "SC22U25V6KX-2-GP-U"
			(at 2.860802 -5.279644 180)
			(unlocked yes)
			(layer "B.Fab")
			(hide yes)
			(effects
				(font
					(size 1.016 1.016)
					(thickness 0.1524)
				)
				(justify mirror)
			)
		)
		(property "Device Type" "C1206-TO0D3H75"
			(at 2.860802 -6.803644 180)
			(unlocked yes)
			(layer "B.Fab")
			(hide yes)
			(effects
				(font
					(size 1.016 1.016)
					(thickness 0.1524)
				)
				(justify mirror)
			)
		)
		(duplicate_pad_numbers_are_jumpers no)
		(fp_line
			(start 1.3081 2.3749)
			(end 1.3081 -2.3749)
			(stroke
				(width 0.1524)
				(type default)
			)
			(layer "B.SilkS")
		)
		(fp_line
			(start 1.3081 -2.3749)
			(end -1.3081 -2.3749)
			(stroke
				(width 0.1524)
				(type default)
			)
			(layer "B.SilkS")
		)
		(fp_line
			(start -1.3081 2.3749)
			(end 1.3081 2.3749)
			(stroke
				(width 0.1524)
				(type default)
			)
			(layer "B.SilkS")
		)
		(fp_line
			(start -1.3081 -2.3749)
			(end -1.3081 2.3749)
			(stroke
				(width 0.1524)
				(type default)
			)
			(layer "B.SilkS")
		)
		(fp_rect
			(start 0.8001 1.6002)
			(end -0.8001 -1.6002)
			(stroke
				(width 0)
				(type default)
			)
			(fill no)
			(layer "B.CrtYd")
		)
		(fp_poly
			(pts
				(xy 1.5621 2.4511) (xy 1.5621 1.6002) (xy -0.8001 1.6002) (xy -0.8001 -1.6002) (xy 0.8001 -1.6002)
				(xy 0.8001 1.5875) (xy 1.5621 1.5875) (xy 1.5621 -2.4511) (xy -1.5621 -2.4511) (xy -1.5621 2.4511)
			)
			(stroke
				(width 0)
				(type default)
			)
			(fill no)
			(layer "B.CrtYd")
		)
		(fp_rect
			(start 1.5621 2.4511)
			(end -1.5621 -2.4511)
			(stroke
				(width 0)
				(type default)
			)
			(fill no)
			(layer "B.Fab")
		)
		(pad "1" smd rect
			(at 0 -1.392936)
			(size 2.1082 1.4478)
			(layers "B.Cu" "B.Mask" "B.Paste")
			(net "P12V_IN")
		)
		(pad "2" smd rect
			(at 0 1.392936)
			(size 2.1082 1.4478)
			(layers "B.Cu" "B.Mask" "B.Paste")
			(net "GND")
		)
	)
	(footprint ""
		(layer "B.Cu")
		(at 65.945258 -108.876846)
		(property "Reference" "TC12"
			(at 0 0 0)
			(layer "B.SilkS")
			(hide yes)
			(effects
				(font
					(size 1.27 1.27)
				)
				(justify mirror)
			)
		)
		(property "Value" "ST220U10VDM-LGP"
			(at 0 -9.6012 0)
			(unlocked yes)
			(layer "B.Fab")
			(hide yes)
			(effects
				(font
					(size 1.016 1.016)
					(thickness 0.1524)
				)
				(justify mirror)
			)
		)
		(property "Device Type" "CT7343H119"
			(at 0 -11.1252 0)
			(unlocked yes)
			(layer "B.Fab")
			(hide yes)
			(effects
				(font
					(size 1.016 1.016)
					(thickness 0.1524)
				)
				(justify mirror)
			)
		)
		(duplicate_pad_numbers_are_jumpers no)
		(fp_line
			(start -2.286 -4.8768)
			(end 2.286 -4.8768)
			(stroke
				(width 0.1524)
				(type default)
			)
			(layer "B.SilkS")
		)
		(fp_line
			(start -2.286 -2.032)
			(end -2.286 -4.8768)
			(stroke
				(width 0.1524)
				(type default)
			)
			(layer "B.SilkS")
		)
		(fp_line
			(start -2.286 2.032)
			(end -2.286 4.8768)
			(stroke
				(width 0.1524)
				(type default)
			)
			(layer "B.SilkS")
		)
		(fp_line
			(start -2.286 4.8768)
			(end 2.286 4.8768)
			(stroke
				(width 0.1524)
				(type default)
			)
			(layer "B.SilkS")
		)
		(fp_line
			(start -2.1082 -4.699)
			(end 2.1082 -4.699)
			(stroke
				(width 0.508)
				(type default)
			)
			(layer "B.SilkS")
		)
		(fp_line
			(start 2.286 -4.8768)
			(end 2.286 -2.032)
			(stroke
				(width 0.1524)
				(type default)
			)
			(layer "B.SilkS")
		)
		(fp_line
			(start 2.286 4.8768)
			(end 2.286 2.032)
			(stroke
				(width 0.1524)
				(type default)
			)
			(layer "B.SilkS")
		)
		(fp_rect
			(start 2.1463 3.6449)
			(end -2.1463 -3.6449)
			(stroke
				(width 0)
				(type default)
			)
			(fill no)
			(layer "B.CrtYd")
		)
		(fp_poly
			(pts
				(xy 2.54 4.953) (xy 2.54 4.2926) (xy 3.81 4.2926) (xy 3.81 -4.2926) (xy 2.54 -4.2926) (xy 2.54 -4.953)
				(xy -2.54 -4.953) (xy -2.54 -4.2926) (xy -3.81 -4.2926) (xy -3.81 -1.6256) (xy -2.1463 -1.6256)
				(xy -2.1463 -3.6449) (xy 2.1463 -3.6449) (xy 2.1463 3.6449) (xy -2.1463 3.6449) (xy -2.1463 -1.6129)
				(xy -3.81 -1.6129) (xy -3.81 4.2926) (xy -2.54 4.2926) (xy -2.54 4.953)
			)
			(stroke
				(width 0)
				(type default)
			)
			(fill no)
			(layer "B.CrtYd")
		)
		(fp_rect
			(start -2.54 4.2926)
			(end -3.81 -4.2926)
			(stroke
				(width 0)
				(type default)
			)
			(fill no)
			(layer "B.Fab")
		)
		(fp_rect
			(start 2.54 4.953)
			(end -2.54 -4.953)
			(stroke
				(width 0)
				(type default)
			)
			(fill no)
			(layer "B.Fab")
		)
		(fp_rect
			(start 3.81 4.2926)
			(end 2.54 -4.2926)
			(stroke
				(width 0)
				(type default)
			)
			(fill no)
			(layer "B.Fab")
		)
		(pad "1" smd rect
			(at 0 -3.1496 180)
			(size 2.413 2.286)
			(layers "B.Cu" "B.Mask" "B.Paste")
			(net "P5V_B_2")
		)
		(pad "2" smd rect
			(at 0 3.1496 180)
			(size 2.413 2.286)
			(layers "B.Cu" "B.Mask" "B.Paste")
			(net "GND")
		)
		(zone
			(layer "B.Cu")
			(hatch none 0.5)
			(connect_pads
				(clearance 0)
			)
			(min_thickness 0.25)
			(keepout
				(tracks allowed)
				(vias not_allowed)
				(pads allowed)
				(copperpour not_allowed)
				(footprints allowed)
			)
			(placement
				(enabled no)
				(sheetname "")
			)
			(fill
				(thermal_gap 0.5)
				(thermal_bridge_width 0.5)
				(island_removal_mode 0)
			)
			(polygon
				(pts
					(xy 64.433958 -110.565946) (xy 64.433958 -113.474246) (xy 67.456558 -113.474246) (xy 67.456558 -110.578646)
					(xy 67.456558 -110.248446) (xy 64.433958 -110.248446)
				)
			)
		)
		(zone
			(layer "B.Cu")
			(hatch none 0.5)
			(connect_pads
				(clearance 0)
			)
			(min_thickness 0.25)
			(keepout
				(tracks allowed)
				(vias not_allowed)
				(pads allowed)
				(copperpour not_allowed)
				(footprints allowed)
			)
			(placement
				(enabled no)
				(sheetname "")
			)
			(fill
				(thermal_gap 0.5)
				(thermal_bridge_width 0.5)
				(island_removal_mode 0)
			)
			(polygon
				(pts
					(xy 67.456558 -104.279446) (xy 64.433958 -104.279446) (xy 64.433958 -107.175046) (xy 64.433958 -107.505246)
					(xy 67.456558 -107.505246) (xy 67.456558 -107.175046)
				)
			)
		)
	)
	(footprint ""
		(layer "B.Cu")
		(at 44.643802 -228.35235 180)
		(property "Reference" "C632"
			(at 0 0 0)
			(layer "B.SilkS")
			(hide yes)
			(effects
				(font
					(size 1.27 1.27)
				)
				(justify mirror)
			)
		)
		(property "Value" "SC10U16V5KX-7-GP-U"
			(at 0.0762 -6.1214 180)
			(unlocked yes)
			(layer "B.Fab")
			(hide yes)
			(effects
				(font
					(size 1.016 1.016)
					(thickness 0.1524)
				)
				(justify mirror)
			)
		)
		(property "Device Type" "C805H58"
			(at 0.0762 -8.1534 180)
			(unlocked yes)
			(layer "B.Fab")
			(hide yes)
			(effects
				(font
					(size 1.016 1.016)
					(thickness 0.1524)
				)
				(justify mirror)
			)
		)
		(duplicate_pad_numbers_are_jumpers no)
		(fp_line
			(start -0.635 0)
			(end 0.635 0)
			(stroke
				(width 0.508)
				(type default)
			)
			(layer "B.SilkS")
		)
		(fp_rect
			(start 0.9652 1.778)
			(end -0.9652 -1.778)
			(stroke
				(width 0)
				(type default)
			)
			(fill no)
			(layer "B.CrtYd")
		)
		(fp_poly
			(pts
				(xy 0.9652 -1.778) (xy -0.9652 -1.778) (xy -0.9652 1.778) (xy 0.9652 1.778)
			)
			(stroke
				(width 0)
				(type default)
			)
			(fill no)
			(layer "B.Fab")
		)
		(pad "1" smd rect
			(at 0 -0.9652)
			(size 1.397 1.143)
			(layers "B.Cu" "B.Mask" "B.Paste")
			(net "P5V_B_1")
		)
		(pad "2" smd rect
			(at 0 0.9652)
			(size 1.397 1.143)
			(layers "B.Cu" "B.Mask" "B.Paste")
			(net "GND")
		)
	)
	(footprint ""
		(layer "B.Cu")
		(at 201.89952 -353.760786 90)
		(property "Reference" "Q198"
			(at 0 0 90)
			(layer "B.SilkS")
			(hide yes)
			(effects
				(font
					(size 1.27 1.27)
				)
				(justify mirror)
			)
		)
		(property "Value" "IRFH8201TRPBF-GP"
			(at 4.2164 -4.3688 90)
			(unlocked yes)
			(layer "B.Fab")
			(hide yes)
			(effects
				(font
					(size 1.016 1.016)
					(thickness 0.1524)
				)
				(justify mirror)
			)
		)
		(property "Device Type" "PPAK-5PH42"
			(at 4.2164 -5.8928 90)
			(unlocked yes)
			(layer "B.Fab")
			(hide yes)
			(effects
				(font
					(size 1.016 1.016)
					(thickness 0.1524)
				)
				(justify mirror)
			)
		)
		(duplicate_pad_numbers_are_jumpers no)
		(fp_line
			(start 2.8956 -2.794)
			(end -2.8956 -2.794)
			(stroke
				(width 0.1524)
				(type default)
			)
			(layer "B.SilkS")
		)
		(fp_line
			(start -2.8956 -2.794)
			(end -2.8956 4.826)
			(stroke
				(width 0.1524)
				(type default)
			)
			(layer "B.SilkS")
		)
		(fp_line
			(start 2.8956 4.826)
			(end 2.8956 -2.794)
			(stroke
				(width 0.1524)
				(type default)
			)
			(layer "B.SilkS")
		)
		(fp_line
			(start -2.8956 4.826)
			(end 2.8956 4.826)
			(stroke
				(width 0.1524)
				(type default)
			)
			(layer "B.SilkS")
		)
		(fp_line
			(start 3.0353 4.9276)
			(end 3.0353 3.9624)
			(stroke
				(width 0.3302)
				(type default)
			)
			(layer "B.SilkS")
		)
		(fp_line
			(start 1.9431 4.9276)
			(end 3.0353 4.9276)
			(stroke
				(width 0.3302)
				(type default)
			)
			(layer "B.SilkS")
		)
		(fp_poly
			(pts
				(xy 2.3622 5.334) (xy 1.4986 5.334) (xy 1.9304 4.9022)
			)
			(stroke
				(width 0)
				(type default)
			)
			(fill yes)
			(layer "B.SilkS")
		)
		(fp_poly
			(pts
				(xy 2.6416 -0.3556) (xy 0.3556 -0.3556) (xy 0.3556 -2.54) (xy 2.6416 -2.54)
			)
			(stroke
				(width 0)
				(type default)
			)
			(fill yes)
			(layer "B.Paste")
		)
		(fp_poly
			(pts
				(xy -0.3556 -0.3556) (xy -2.6416 -0.3556) (xy -2.6416 -2.54) (xy -0.3556 -2.54)
			)
			(stroke
				(width 0)
				(type default)
			)
			(fill yes)
			(layer "B.Paste")
		)
		(fp_poly
			(pts
				(xy 2.6416 2.54) (xy 0.3556 2.54) (xy 0.3556 0.3556) (xy 2.6416 0.3556)
			)
			(stroke
				(width 0)
				(type default)
			)
			(fill yes)
			(layer "B.Paste")
		)
		(fp_poly
			(pts
				(xy -0.3556 2.54) (xy -2.6416 2.54) (xy -2.6416 0.3556) (xy -0.3556 0.3556)
			)
			(stroke
				(width 0)
				(type default)
			)
			(fill yes)
			(layer "B.Paste")
		)
		(fp_rect
			(start 2.5781 3.9878)
			(end -2.5781 -2.1082)
			(stroke
				(width 0)
				(type default)
			)
			(fill no)
			(layer "B.CrtYd")
		)
		(fp_poly
			(pts
				(xy 3.1496 5.08) (xy 3.1496 -3.048) (xy -3.1496 -3.048) (xy -3.1496 3.9751) (xy -2.5781 3.9751)
				(xy -2.5781 -2.1082) (xy 2.5781 -2.1082) (xy 2.5781 3.9878) (xy -3.1496 3.9878) (xy -3.1496 5.08)
			)
			(stroke
				(width 0)
				(type default)
			)
			(fill no)
			(layer "B.CrtYd")
		)
		(fp_rect
			(start 3.1496 5.08)
			(end -3.1496 -3.048)
			(stroke
				(width 0)
				(type default)
			)
			(fill no)
			(layer "B.Fab")
		)
		(pad "1" smd rect
			(at 1.905 3.81 270)
			(size 0.762 1.524)
			(layers "B.Cu" "B.Mask" "B.Paste")
			(net "P12V_IN")
		)
		(pad "2" smd rect
			(at 0.635 3.81 270)
			(size 0.762 1.524)
			(layers "B.Cu" "B.Mask" "B.Paste")
			(net "P12V_IN")
		)
		(pad "3" smd rect
			(at -0.635 3.81 270)
			(size 0.762 1.524)
			(layers "B.Cu" "B.Mask" "B.Paste")
			(net "P12V_IN")
		)
		(pad "4" smd rect
			(at -1.905 3.81 270)
			(size 0.762 1.524)
			(layers "B.Cu" "B.Mask" "B.Paste")
			(net "MB0_12V_CTRL_GATE5")
		)
		(pad "5" smd rect
			(at 0 0 270)
			(size 5.2832 5.08)
			(layers "B.Cu" "B.Mask" "B.Paste")
			(net "MB0_P12V_IN_R")
		)
		(pad "6" smd rect
			(at -0.635 -2.032 270)
			(size 0.0254 0.0254)
			(layers "B.Cu" "B.Mask" "B.Paste")
			(net "MB0_P12V_IN_R")
		)
		(pad "7" smd rect
			(at 0.635 -2.032 270)
			(size 0.0254 0.0254)
			(layers "B.Cu" "B.Mask" "B.Paste")
			(net "MB0_P12V_IN_R")
		)
		(pad "8" smd rect
			(at 1.905 -2.032 270)
			(size 0.0254 0.0254)
			(layers "B.Cu" "B.Mask" "B.Paste")
			(net "MB0_P12V_IN_R")
		)
	)
	(footprint ""
		(layer "B.Cu")
		(at 47.439072 -118.35892 180)
		(property "Reference" "R1130"
			(at 0 0 0)
			(layer "B.SilkS")
			(hide yes)
			(effects
				(font
					(size 1.27 1.27)
				)
				(justify mirror)
			)
		)
		(property "Value" "10KR2F-2-GP"
			(at -0.064008 -3.993896 180)
			(unlocked yes)
			(layer "B.Fab")
			(hide yes)
			(effects
				(font
					(size 1.016 1.016)
					(thickness 0.1524)
				)
				(justify mirror)
			)
		)
		(property "Device Type" "R402H16"
			(at -0.064008 -5.517896 180)
			(unlocked yes)
			(layer "B.Fab")
			(hide yes)
			(effects
				(font
					(size 1.016 1.016)
					(thickness 0.1524)
				)
				(justify mirror)
			)
		)
		(duplicate_pad_numbers_are_jumpers no)
		(fp_line
			(start 0.508 -0.9398)
			(end 0.508 0.9398)
			(stroke
				(width 0.1524)
				(type default)
			)
			(layer "B.SilkS")
		)
		(fp_line
			(start -0.508 -0.9398)
			(end 0.508 -0.9398)
			(stroke
				(width 0.1524)
				(type default)
			)
			(layer "B.SilkS")
		)
		(fp_rect
			(start 0.508 0.9398)
			(end -0.508 -0.9398)
			(stroke
				(width 0)
				(type default)
			)
			(fill no)
			(layer "B.CrtYd")
		)
		(fp_rect
			(start 0.508 0.9398)
			(end -0.508 -0.9398)
			(stroke
				(width 0)
				(type default)
			)
			(fill no)
			(layer "B.Fab")
		)
		(pad "1" smd custom
			(at 0 -0.4445)
			(size 0.1397 0.1397)
			(layers "B.Cu" "B.Mask" "B.Paste")
			(net "P5V_B_2_VFB")
			(options
				(clearance outline)
				(anchor circle)
			)
			(primitives
				(gr_poly
					(pts
						(arc
							(start -0.1778 0.2794)
							(mid -0.249642 0.249642)
							(end -0.2794 0.1778)
						)
						(arc
							(start -0.2794 -0.1778)
							(mid -0.249642 -0.249642)
							(end -0.1778 -0.2794)
						)
						(arc
							(start 0.1778 -0.2794)
							(mid 0.249642 -0.249642)
							(end 0.2794 -0.1778)
						)
						(arc
							(start 0.2794 0.1778)
							(mid 0.249642 0.249642)
							(end 0.1778 0.2794)
						)
					)
					(width 0)
					(fill yes)
				)
			)
		)
		(pad "2" smd custom
			(at 0 0.4445)
			(size 0.1397 0.1397)
			(layers "B.Cu" "B.Mask" "B.Paste")
			(net "AGND_P5V_B_2")
			(options
				(clearance outline)
				(anchor circle)
			)
			(primitives
				(gr_poly
					(pts
						(arc
							(start -0.1778 0.2794)
							(mid -0.249642 0.249642)
							(end -0.2794 0.1778)
						)
						(arc
							(start -0.2794 -0.1778)
							(mid -0.249642 -0.249642)
							(end -0.1778 -0.2794)
						)
						(arc
							(start 0.1778 -0.2794)
							(mid 0.249642 -0.249642)
							(end 0.2794 -0.1778)
						)
						(arc
							(start 0.2794 0.1778)
							(mid 0.249642 0.249642)
							(end 0.1778 0.2794)
						)
					)
					(width 0)
					(fill yes)
				)
			)
		)
	)
	(footprint ""
		(layer "B.Cu")
		(at 170.04538 -372.364)
		(property "Reference" "C543"
			(at 0 0 0)
			(layer "B.SilkS")
			(hide yes)
			(effects
				(font
					(size 1.27 1.27)
				)
				(justify mirror)
			)
		)
		(property "Value" "SCD015U25V2KX-GP"
			(at -1.1811 -2.7051 0)
			(unlocked yes)
			(layer "B.Fab")
			(hide yes)
			(effects
				(font
					(size 1.016 1.016)
					(thickness 0.1524)
				)
				(justify mirror)
			)
		)
		(property "Device Type" "C402H22"
			(at -1.1811 -4.2291 0)
			(unlocked yes)
			(layer "B.Fab")
			(hide yes)
			(effects
				(font
					(size 1.016 1.016)
					(thickness 0.1524)
				)
				(justify mirror)
			)
		)
		(duplicate_pad_numbers_are_jumpers no)
		(fp_rect
			(start 0.4318 0.9525)
			(end -0.4318 -0.9525)
			(stroke
				(width 0)
				(type default)
			)
			(fill no)
			(layer "B.CrtYd")
		)
		(fp_rect
			(start 0.4318 0.9525)
			(end -0.4318 -0.9525)
			(stroke
				(width 0)
				(type default)
			)
			(fill no)
			(layer "B.Fab")
		)
		(pad "1" smd custom
			(at 0 -0.4445 180)
			(size 0.1524 0.1524)
			(layers "B.Cu" "B.Mask" "B.Paste")
			(net "MB0_CM_SENSE_P")
			(options
				(clearance outline)
				(anchor circle)
			)
			(primitives
				(gr_poly
					(pts
						(arc
							(start 0.3048 0.2032)
							(mid 0.275042 0.275042)
							(end 0.2032 0.3048)
						)
						(arc
							(start -0.2032 0.3048)
							(mid -0.275042 0.275042)
							(end -0.3048 0.2032)
						)
						(arc
							(start -0.3048 -0.2032)
							(mid -0.275042 -0.275042)
							(end -0.2032 -0.3048)
						)
						(arc
							(start 0.2032 -0.3048)
							(mid 0.275042 -0.275042)
							(end 0.3048 -0.2032)
						)
					)
					(width 0)
					(fill yes)
				)
			)
		)
		(pad "2" smd custom
			(at 0 0.4445 180)
			(size 0.1524 0.1524)
			(layers "B.Cu" "B.Mask" "B.Paste")
			(net "MB0_CM_SENSE_N")
			(options
				(clearance outline)
				(anchor circle)
			)
			(primitives
				(gr_poly
					(pts
						(arc
							(start 0.3048 0.2032)
							(mid 0.275042 0.275042)
							(end 0.2032 0.3048)
						)
						(arc
							(start -0.2032 0.3048)
							(mid -0.275042 0.275042)
							(end -0.3048 0.2032)
						)
						(arc
							(start -0.3048 -0.2032)
							(mid -0.275042 -0.275042)
							(end -0.2032 -0.3048)
						)
						(arc
							(start 0.2032 -0.3048)
							(mid 0.275042 -0.275042)
							(end 0.3048 -0.2032)
						)
					)
					(width 0)
					(fill yes)
				)
			)
		)
	)
	(footprint ""
		(layer "B.Cu")
		(at 167.7162 -372.872 90)
		(property "Reference" "R996"
			(at 0 0 90)
			(layer "B.SilkS")
			(hide yes)
			(effects
				(font
					(size 1.27 1.27)
				)
				(justify mirror)
			)
		)
		(property "Value" "10R2F-L-GP"
			(at -0.064008 -3.993896 90)
			(unlocked yes)
			(layer "B.Fab")
			(hide yes)
			(effects
				(font
					(size 1.016 1.016)
					(thickness 0.1524)
				)
				(justify mirror)
			)
		)
		(property "Device Type" "R402H14"
			(at -0.064008 -5.517896 90)
			(unlocked yes)
			(layer "B.Fab")
			(hide yes)
			(effects
				(font
					(size 1.016 1.016)
					(thickness 0.1524)
				)
				(justify mirror)
			)
		)
		(duplicate_pad_numbers_are_jumpers no)
		(fp_line
			(start 0.508 -0.9398)
			(end 0.508 0.9398)
			(stroke
				(width 0.1524)
				(type default)
			)
			(layer "B.SilkS")
		)
		(fp_line
			(start -0.508 -0.9398)
			(end 0.508 -0.9398)
			(stroke
				(width 0.1524)
				(type default)
			)
			(layer "B.SilkS")
		)
		(fp_rect
			(start 0.508 0.9398)
			(end -0.508 -0.9398)
			(stroke
				(width 0)
				(type default)
			)
			(fill no)
			(layer "B.CrtYd")
		)
		(fp_rect
			(start 0.508 0.9398)
			(end -0.508 -0.9398)
			(stroke
				(width 0)
				(type default)
			)
			(fill no)
			(layer "B.Fab")
		)
		(pad "1" smd custom
			(at 0 -0.4445 270)
			(size 0.1397 0.1397)
			(layers "B.Cu" "B.Mask" "B.Paste")
			(net "MB0_CM_SENSE_R1_P")
			(options
				(clearance outline)
				(anchor circle)
			)
			(primitives
				(gr_poly
					(pts
						(arc
							(start -0.1778 0.2794)
							(mid -0.249642 0.249642)
							(end -0.2794 0.1778)
						)
						(arc
							(start -0.2794 -0.1778)
							(mid -0.249642 -0.249642)
							(end -0.1778 -0.2794)
						)
						(arc
							(start 0.1778 -0.2794)
							(mid 0.249642 -0.249642)
							(end 0.2794 -0.1778)
						)
						(arc
							(start 0.2794 0.1778)
							(mid 0.249642 0.249642)
							(end 0.1778 0.2794)
						)
					)
					(width 0)
					(fill yes)
				)
			)
		)
		(pad "2" smd custom
			(at 0 0.4445 270)
			(size 0.1397 0.1397)
			(layers "B.Cu" "B.Mask" "B.Paste")
			(net "MB0_CM_SENSE_P")
			(options
				(clearance outline)
				(anchor circle)
			)
			(primitives
				(gr_poly
					(pts
						(arc
							(start -0.1778 0.2794)
							(mid -0.249642 0.249642)
							(end -0.2794 0.1778)
						)
						(arc
							(start -0.2794 -0.1778)
							(mid -0.249642 -0.249642)
							(end -0.1778 -0.2794)
						)
						(arc
							(start 0.1778 -0.2794)
							(mid 0.249642 -0.249642)
							(end 0.2794 -0.1778)
						)
						(arc
							(start 0.2794 0.1778)
							(mid 0.249642 0.249642)
							(end 0.1778 0.2794)
						)
					)
					(width 0)
					(fill yes)
				)
			)
		)
	)
	(footprint ""
		(layer "B.Cu")
		(at 249.301 -286.2072 90)
		(property "Reference" "C694"
			(at 0 0 90)
			(layer "B.SilkS")
			(hide yes)
			(effects
				(font
					(size 1.27 1.27)
				)
				(justify mirror)
			)
		)
		(property "Value" "SC1U25V3KX-GP"
			(at 0 -2.8194 90)
			(unlocked yes)
			(layer "B.Fab")
			(hide yes)
			(effects
				(font
					(size 1.016 1.016)
					(thickness 0.1524)
				)
				(justify mirror)
			)
		)
		(property "Device Type" "C603H36"
			(at 0 -4.3434 90)
			(unlocked yes)
			(layer "B.Fab")
			(hide yes)
			(effects
				(font
					(size 1.016 1.016)
					(thickness 0.1524)
				)
				(justify mirror)
			)
		)
		(duplicate_pad_numbers_are_jumpers no)
		(fp_line
			(start -0.508 0)
			(end 0.508 0)
			(stroke
				(width 0.2032)
				(type default)
			)
			(layer "B.SilkS")
		)
		(fp_rect
			(start 0.5842 1.3335)
			(end -0.5842 -1.3335)
			(stroke
				(width 0)
				(type default)
			)
			(fill no)
			(layer "B.CrtYd")
		)
		(fp_rect
			(start 0.5842 1.3335)
			(end -0.5842 -1.3335)
			(stroke
				(width 0)
				(type default)
			)
			(fill no)
			(layer "B.Fab")
		)
		(pad "1" smd custom
			(at 0 -0.762 270)
			(size 0.2159 0.2159)
			(layers "B.Cu" "B.Mask" "B.Paste")
			(net "P3V3_STBY_SW")
			(options
				(clearance outline)
				(anchor circle)
			)
			(primitives
				(gr_poly
					(pts
						(arc
							(start -0.3302 0.4318)
							(mid -0.402042 0.402042)
							(end -0.4318 0.3302)
						)
						(arc
							(start -0.4318 -0.3302)
							(mid -0.402042 -0.402042)
							(end -0.3302 -0.4318)
						)
						(arc
							(start 0.3302 -0.4318)
							(mid 0.402042 -0.402042)
							(end 0.4318 -0.3302)
						)
						(arc
							(start 0.4318 0.3302)
							(mid 0.402042 0.402042)
							(end 0.3302 0.4318)
						)
					)
					(width 0)
					(fill yes)
				)
			)
		)
		(pad "2" smd custom
			(at 0 0.762 270)
			(size 0.2159 0.2159)
			(layers "B.Cu" "B.Mask" "B.Paste")
			(net "P3V3_STBY_VBST_RR")
			(options
				(clearance outline)
				(anchor circle)
			)
			(primitives
				(gr_poly
					(pts
						(arc
							(start -0.3302 0.4318)
							(mid -0.402042 0.402042)
							(end -0.4318 0.3302)
						)
						(arc
							(start -0.4318 -0.3302)
							(mid -0.402042 -0.402042)
							(end -0.3302 -0.4318)
						)
						(arc
							(start 0.3302 -0.4318)
							(mid 0.402042 -0.402042)
							(end 0.4318 -0.3302)
						)
						(arc
							(start 0.4318 0.3302)
							(mid 0.402042 0.402042)
							(end 0.3302 0.4318)
						)
					)
					(width 0)
					(fill yes)
				)
			)
		)
	)
	(footprint ""
		(layer "B.Cu")
		(at 24.4602 -229.6922 90)
		(property "Reference" "R1109"
			(at 0 0 90)
			(layer "B.SilkS")
			(hide yes)
			(effects
				(font
					(size 1.27 1.27)
				)
				(justify mirror)
			)
		)
		(property "Value" "71K5R2F-GP"
			(at -0.064008 -3.993896 90)
			(unlocked yes)
			(layer "B.Fab")
			(hide yes)
			(effects
				(font
					(size 1.016 1.016)
					(thickness 0.1524)
				)
				(justify mirror)
			)
		)
		(property "Device Type" "R402H16"
			(at -0.064008 -5.517896 90)
			(unlocked yes)
			(layer "B.Fab")
			(hide yes)
			(effects
				(font
					(size 1.016 1.016)
					(thickness 0.1524)
				)
				(justify mirror)
			)
		)
		(duplicate_pad_numbers_are_jumpers no)
		(fp_line
			(start 0.508 -0.9398)
			(end 0.508 0.9398)
			(stroke
				(width 0.1524)
				(type default)
			)
			(layer "B.SilkS")
		)
		(fp_line
			(start -0.508 -0.9398)
			(end 0.508 -0.9398)
			(stroke
				(width 0.1524)
				(type default)
			)
			(layer "B.SilkS")
		)
		(fp_rect
			(start 0.508 0.9398)
			(end -0.508 -0.9398)
			(stroke
				(width 0)
				(type default)
			)
			(fill no)
			(layer "B.CrtYd")
		)
		(fp_rect
			(start 0.508 0.9398)
			(end -0.508 -0.9398)
			(stroke
				(width 0)
				(type default)
			)
			(fill no)
			(layer "B.Fab")
		)
		(pad "1" smd custom
			(at 0 -0.4445 270)
			(size 0.1397 0.1397)
			(layers "B.Cu" "B.Mask" "B.Paste")
			(net "P5V_B_1_VFB")
			(options
				(clearance outline)
				(anchor circle)
			)
			(primitives
				(gr_poly
					(pts
						(arc
							(start -0.1778 0.2794)
							(mid -0.249642 0.249642)
							(end -0.2794 0.1778)
						)
						(arc
							(start -0.2794 -0.1778)
							(mid -0.249642 -0.249642)
							(end -0.1778 -0.2794)
						)
						(arc
							(start 0.1778 -0.2794)
							(mid 0.249642 -0.249642)
							(end 0.2794 -0.1778)
						)
						(arc
							(start 0.2794 0.1778)
							(mid 0.249642 0.249642)
							(end 0.1778 0.2794)
						)
					)
					(width 0)
					(fill yes)
				)
			)
		)
		(pad "2" smd custom
			(at 0 0.4445 270)
			(size 0.1397 0.1397)
			(layers "B.Cu" "B.Mask" "B.Paste")
			(net "P5V_B_1_VFB_R")
			(options
				(clearance outline)
				(anchor circle)
			)
			(primitives
				(gr_poly
					(pts
						(arc
							(start -0.1778 0.2794)
							(mid -0.249642 0.249642)
							(end -0.2794 0.1778)
						)
						(arc
							(start -0.2794 -0.1778)
							(mid -0.249642 -0.249642)
							(end -0.1778 -0.2794)
						)
						(arc
							(start 0.1778 -0.2794)
							(mid 0.249642 -0.249642)
							(end 0.2794 -0.1778)
						)
						(arc
							(start 0.2794 0.1778)
							(mid 0.249642 0.249642)
							(end 0.1778 0.2794)
						)
					)
					(width 0)
					(fill yes)
				)
			)
		)
	)
	(footprint ""
		(layer "B.Cu")
		(at 167.7162 -370.205 90)
		(property "Reference" "R1032"
			(at 0 0 90)
			(layer "B.SilkS")
			(hide yes)
			(effects
				(font
					(size 1.27 1.27)
				)
				(justify mirror)
			)
		)
		(property "Value" "10R2F-L-GP"
			(at -0.064008 -3.993896 90)
			(unlocked yes)
			(layer "B.Fab")
			(hide yes)
			(effects
				(font
					(size 1.016 1.016)
					(thickness 0.1524)
				)
				(justify mirror)
			)
		)
		(property "Device Type" "R402H14"
			(at -0.064008 -5.517896 90)
			(unlocked yes)
			(layer "B.Fab")
			(hide yes)
			(effects
				(font
					(size 1.016 1.016)
					(thickness 0.1524)
				)
				(justify mirror)
			)
		)
		(duplicate_pad_numbers_are_jumpers no)
		(fp_line
			(start 0.508 -0.9398)
			(end 0.508 0.9398)
			(stroke
				(width 0.1524)
				(type default)
			)
			(layer "B.SilkS")
		)
		(fp_line
			(start -0.508 -0.9398)
			(end 0.508 -0.9398)
			(stroke
				(width 0.1524)
				(type default)
			)
			(layer "B.SilkS")
		)
		(fp_rect
			(start 0.508 0.9398)
			(end -0.508 -0.9398)
			(stroke
				(width 0)
				(type default)
			)
			(fill no)
			(layer "B.CrtYd")
		)
		(fp_rect
			(start 0.508 0.9398)
			(end -0.508 -0.9398)
			(stroke
				(width 0)
				(type default)
			)
			(fill no)
			(layer "B.Fab")
		)
		(pad "1" smd custom
			(at 0 -0.4445 270)
			(size 0.1397 0.1397)
			(layers "B.Cu" "B.Mask" "B.Paste")
			(net "MB0_CM_SENSE_R1_N")
			(options
				(clearance outline)
				(anchor circle)
			)
			(primitives
				(gr_poly
					(pts
						(arc
							(start -0.1778 0.2794)
							(mid -0.249642 0.249642)
							(end -0.2794 0.1778)
						)
						(arc
							(start -0.2794 -0.1778)
							(mid -0.249642 -0.249642)
							(end -0.1778 -0.2794)
						)
						(arc
							(start 0.1778 -0.2794)
							(mid 0.249642 -0.249642)
							(end 0.2794 -0.1778)
						)
						(arc
							(start 0.2794 0.1778)
							(mid 0.249642 0.249642)
							(end 0.1778 0.2794)
						)
					)
					(width 0)
					(fill yes)
				)
			)
		)
		(pad "2" smd custom
			(at 0 0.4445 270)
			(size 0.1397 0.1397)
			(layers "B.Cu" "B.Mask" "B.Paste")
			(net "MB0_HS_SENSE_N")
			(options
				(clearance outline)
				(anchor circle)
			)
			(primitives
				(gr_poly
					(pts
						(arc
							(start -0.1778 0.2794)
							(mid -0.249642 0.249642)
							(end -0.2794 0.1778)
						)
						(arc
							(start -0.2794 -0.1778)
							(mid -0.249642 -0.249642)
							(end -0.1778 -0.2794)
						)
						(arc
							(start 0.1778 -0.2794)
							(mid 0.249642 -0.249642)
							(end 0.2794 -0.1778)
						)
						(arc
							(start 0.2794 0.1778)
							(mid 0.249642 0.249642)
							(end 0.1778 0.2794)
						)
					)
					(width 0)
					(fill yes)
				)
			)
		)
	)
	(footprint ""
		(layer "B.Cu")
		(at 441.162186 -120.321578 90)
		(property "Reference" "C684"
			(at 0 0 90)
			(layer "B.SilkS")
			(hide yes)
			(effects
				(font
					(size 1.27 1.27)
				)
				(justify mirror)
			)
		)
		(property "Value" "SC68P50V2JN-2-GP"
			(at -1.1811 -2.7051 90)
			(unlocked yes)
			(layer "B.Fab")
			(hide yes)
			(effects
				(font
					(size 1.016 1.016)
					(thickness 0.1524)
				)
				(justify mirror)
			)
		)
		(property "Device Type" "C402H22"
			(at -1.1811 -4.2291 90)
			(unlocked yes)
			(layer "B.Fab")
			(hide yes)
			(effects
				(font
					(size 1.016 1.016)
					(thickness 0.1524)
				)
				(justify mirror)
			)
		)
		(duplicate_pad_numbers_are_jumpers no)
		(fp_rect
			(start 0.4318 0.9525)
			(end -0.4318 -0.9525)
			(stroke
				(width 0)
				(type default)
			)
			(fill no)
			(layer "B.CrtYd")
		)
		(fp_rect
			(start 0.4318 0.9525)
			(end -0.4318 -0.9525)
			(stroke
				(width 0)
				(type default)
			)
			(fill no)
			(layer "B.Fab")
		)
		(pad "1" smd custom
			(at 0 -0.4445 270)
			(size 0.1524 0.1524)
			(layers "B.Cu" "B.Mask" "B.Paste")
			(net "P5V_B_4_VFB")
			(options
				(clearance outline)
				(anchor circle)
			)
			(primitives
				(gr_poly
					(pts
						(arc
							(start 0.3048 0.2032)
							(mid 0.275042 0.275042)
							(end 0.2032 0.3048)
						)
						(arc
							(start -0.2032 0.3048)
							(mid -0.275042 0.275042)
							(end -0.3048 0.2032)
						)
						(arc
							(start -0.3048 -0.2032)
							(mid -0.275042 -0.275042)
							(end -0.2032 -0.3048)
						)
						(arc
							(start 0.2032 -0.3048)
							(mid 0.275042 -0.275042)
							(end 0.3048 -0.2032)
						)
					)
					(width 0)
					(fill yes)
				)
			)
		)
		(pad "2" smd custom
			(at 0 0.4445 270)
			(size 0.1524 0.1524)
			(layers "B.Cu" "B.Mask" "B.Paste")
			(net "P5V_B_4_VFB_R")
			(options
				(clearance outline)
				(anchor circle)
			)
			(primitives
				(gr_poly
					(pts
						(arc
							(start 0.3048 0.2032)
							(mid 0.275042 0.275042)
							(end 0.2032 0.3048)
						)
						(arc
							(start -0.2032 0.3048)
							(mid -0.275042 0.275042)
							(end -0.3048 0.2032)
						)
						(arc
							(start -0.3048 -0.2032)
							(mid -0.275042 -0.275042)
							(end -0.2032 -0.3048)
						)
						(arc
							(start 0.2032 -0.3048)
							(mid 0.275042 -0.275042)
							(end 0.3048 -0.2032)
						)
					)
					(width 0)
					(fill yes)
				)
			)
		)
	)
	(footprint ""
		(layer "B.Cu")
		(at 201.836274 -333.39659 90)
		(property "Reference" "Q194"
			(at 0 0 90)
			(layer "B.SilkS")
			(hide yes)
			(effects
				(font
					(size 1.27 1.27)
				)
				(justify mirror)
			)
		)
		(property "Value" "IRFH8201TRPBF-GP"
			(at 4.2164 -4.3688 90)
			(unlocked yes)
			(layer "B.Fab")
			(hide yes)
			(effects
				(font
					(size 1.016 1.016)
					(thickness 0.1524)
				)
				(justify mirror)
			)
		)
		(property "Device Type" "PPAK-5PH42"
			(at 4.2164 -5.8928 90)
			(unlocked yes)
			(layer "B.Fab")
			(hide yes)
			(effects
				(font
					(size 1.016 1.016)
					(thickness 0.1524)
				)
				(justify mirror)
			)
		)
		(duplicate_pad_numbers_are_jumpers no)
		(fp_line
			(start 2.8956 -2.794)
			(end -2.8956 -2.794)
			(stroke
				(width 0.1524)
				(type default)
			)
			(layer "B.SilkS")
		)
		(fp_line
			(start -2.8956 -2.794)
			(end -2.8956 4.826)
			(stroke
				(width 0.1524)
				(type default)
			)
			(layer "B.SilkS")
		)
		(fp_line
			(start 2.8956 4.826)
			(end 2.8956 -2.794)
			(stroke
				(width 0.1524)
				(type default)
			)
			(layer "B.SilkS")
		)
		(fp_line
			(start -2.8956 4.826)
			(end 2.8956 4.826)
			(stroke
				(width 0.1524)
				(type default)
			)
			(layer "B.SilkS")
		)
		(fp_line
			(start 3.0353 4.9276)
			(end 3.0353 3.9624)
			(stroke
				(width 0.3302)
				(type default)
			)
			(layer "B.SilkS")
		)
		(fp_line
			(start 1.9431 4.9276)
			(end 3.0353 4.9276)
			(stroke
				(width 0.3302)
				(type default)
			)
			(layer "B.SilkS")
		)
		(fp_poly
			(pts
				(xy 2.3622 5.334) (xy 1.4986 5.334) (xy 1.9304 4.9022)
			)
			(stroke
				(width 0)
				(type default)
			)
			(fill yes)
			(layer "B.SilkS")
		)
		(fp_poly
			(pts
				(xy 2.6416 -0.3556) (xy 0.3556 -0.3556) (xy 0.3556 -2.54) (xy 2.6416 -2.54)
			)
			(stroke
				(width 0)
				(type default)
			)
			(fill yes)
			(layer "B.Paste")
		)
		(fp_poly
			(pts
				(xy -0.3556 -0.3556) (xy -2.6416 -0.3556) (xy -2.6416 -2.54) (xy -0.3556 -2.54)
			)
			(stroke
				(width 0)
				(type default)
			)
			(fill yes)
			(layer "B.Paste")
		)
		(fp_poly
			(pts
				(xy 2.6416 2.54) (xy 0.3556 2.54) (xy 0.3556 0.3556) (xy 2.6416 0.3556)
			)
			(stroke
				(width 0)
				(type default)
			)
			(fill yes)
			(layer "B.Paste")
		)
		(fp_poly
			(pts
				(xy -0.3556 2.54) (xy -2.6416 2.54) (xy -2.6416 0.3556) (xy -0.3556 0.3556)
			)
			(stroke
				(width 0)
				(type default)
			)
			(fill yes)
			(layer "B.Paste")
		)
		(fp_rect
			(start 2.5781 3.9878)
			(end -2.5781 -2.1082)
			(stroke
				(width 0)
				(type default)
			)
			(fill no)
			(layer "B.CrtYd")
		)
		(fp_poly
			(pts
				(xy 3.1496 5.08) (xy 3.1496 -3.048) (xy -3.1496 -3.048) (xy -3.1496 3.9751) (xy -2.5781 3.9751)
				(xy -2.5781 -2.1082) (xy 2.5781 -2.1082) (xy 2.5781 3.9878) (xy -3.1496 3.9878) (xy -3.1496 5.08)
			)
			(stroke
				(width 0)
				(type default)
			)
			(fill no)
			(layer "B.CrtYd")
		)
		(fp_rect
			(start 3.1496 5.08)
			(end -3.1496 -3.048)
			(stroke
				(width 0)
				(type default)
			)
			(fill no)
			(layer "B.Fab")
		)
		(pad "1" smd rect
			(at 1.905 3.81 270)
			(size 0.762 1.524)
			(layers "B.Cu" "B.Mask" "B.Paste")
			(net "P12V_IN")
		)
		(pad "2" smd rect
			(at 0.635 3.81 270)
			(size 0.762 1.524)
			(layers "B.Cu" "B.Mask" "B.Paste")
			(net "P12V_IN")
		)
		(pad "3" smd rect
			(at -0.635 3.81 270)
			(size 0.762 1.524)
			(layers "B.Cu" "B.Mask" "B.Paste")
			(net "P12V_IN")
		)
		(pad "4" smd rect
			(at -1.905 3.81 270)
			(size 0.762 1.524)
			(layers "B.Cu" "B.Mask" "B.Paste")
			(net "MB0_12V_CTRL_GATE1")
		)
		(pad "5" smd rect
			(at 0 0 270)
			(size 5.2832 5.08)
			(layers "B.Cu" "B.Mask" "B.Paste")
			(net "MB0_P12V_IN_R")
		)
		(pad "6" smd rect
			(at -0.635 -2.032 270)
			(size 0.0254 0.0254)
			(layers "B.Cu" "B.Mask" "B.Paste")
			(net "MB0_P12V_IN_R")
		)
		(pad "7" smd rect
			(at 0.635 -2.032 270)
			(size 0.0254 0.0254)
			(layers "B.Cu" "B.Mask" "B.Paste")
			(net "MB0_P12V_IN_R")
		)
		(pad "8" smd rect
			(at 1.905 -2.032 270)
			(size 0.0254 0.0254)
			(layers "B.Cu" "B.Mask" "B.Paste")
			(net "MB0_P12V_IN_R")
		)
	)
	(footprint ""
		(layer "B.Cu")
		(at 432.653186 -115.114578 90)
		(property "Reference" "C681"
			(at 0 0 90)
			(layer "B.SilkS")
			(hide yes)
			(effects
				(font
					(size 1.27 1.27)
				)
				(justify mirror)
			)
		)
		(property "Value" "SC1U16V3KX-5GP"
			(at 0 -2.8194 90)
			(unlocked yes)
			(layer "B.Fab")
			(hide yes)
			(effects
				(font
					(size 1.016 1.016)
					(thickness 0.1524)
				)
				(justify mirror)
			)
		)
		(property "Device Type" "C603H36"
			(at 0 -4.3434 90)
			(unlocked yes)
			(layer "B.Fab")
			(hide yes)
			(effects
				(font
					(size 1.016 1.016)
					(thickness 0.1524)
				)
				(justify mirror)
			)
		)
		(duplicate_pad_numbers_are_jumpers no)
		(fp_line
			(start -0.508 0)
			(end 0.508 0)
			(stroke
				(width 0.2032)
				(type default)
			)
			(layer "B.SilkS")
		)
		(fp_rect
			(start 0.5842 1.3335)
			(end -0.5842 -1.3335)
			(stroke
				(width 0)
				(type default)
			)
			(fill no)
			(layer "B.CrtYd")
		)
		(fp_rect
			(start 0.5842 1.3335)
			(end -0.5842 -1.3335)
			(stroke
				(width 0)
				(type default)
			)
			(fill no)
			(layer "B.Fab")
		)
		(pad "1" smd custom
			(at 0 -0.762 270)
			(size 0.2159 0.2159)
			(layers "B.Cu" "B.Mask" "B.Paste")
			(net "GND")
			(options
				(clearance outline)
				(anchor circle)
			)
			(primitives
				(gr_poly
					(pts
						(arc
							(start -0.3302 0.4318)
							(mid -0.402042 0.402042)
							(end -0.4318 0.3302)
						)
						(arc
							(start -0.4318 -0.3302)
							(mid -0.402042 -0.402042)
							(end -0.3302 -0.4318)
						)
						(arc
							(start 0.3302 -0.4318)
							(mid 0.402042 -0.402042)
							(end 0.4318 -0.3302)
						)
						(arc
							(start 0.4318 0.3302)
							(mid 0.402042 0.402042)
							(end 0.3302 0.4318)
						)
					)
					(width 0)
					(fill yes)
				)
			)
		)
		(pad "2" smd custom
			(at 0 0.762 270)
			(size 0.2159 0.2159)
			(layers "B.Cu" "B.Mask" "B.Paste")
			(net "P5V_B_4_VREG")
			(options
				(clearance outline)
				(anchor circle)
			)
			(primitives
				(gr_poly
					(pts
						(arc
							(start -0.3302 0.4318)
							(mid -0.402042 0.402042)
							(end -0.4318 0.3302)
						)
						(arc
							(start -0.4318 -0.3302)
							(mid -0.402042 -0.402042)
							(end -0.3302 -0.4318)
						)
						(arc
							(start 0.3302 -0.4318)
							(mid 0.402042 -0.402042)
							(end 0.4318 -0.3302)
						)
						(arc
							(start 0.4318 0.3302)
							(mid 0.402042 0.402042)
							(end 0.3302 0.4318)
						)
					)
					(width 0)
					(fill yes)
				)
			)
		)
	)
	(gr_line
		(start 30.025086 -249.385074)
		(end 31.359602 -249.385074)
		(stroke
			(width 0.0635)
			(type default)
		)
		(layer "F.Cu")
	)
	(gr_line
		(start 30.025086 -248.115074)
		(end 31.359602 -248.115074)
		(stroke
			(width 0.0635)
			(type default)
		)
		(layer "F.Cu")
	)
	(gr_line
		(start 30.025086 -245.575074)
		(end 31.359602 -245.575074)
		(stroke
			(width 0.0635)
			(type default)
		)
		(layer "F.Cu")
	)
	(gr_line
		(start 30.025086 -244.305074)
		(end 31.359602 -244.305074)
		(stroke
			(width 0.0635)
			(type default)
		)
		(layer "F.Cu")
	)
	(gr_line
		(start 30.025086 -134.38505)
		(end 31.359602 -134.38505)
		(stroke
			(width 0.0635)
			(type default)
		)
		(layer "F.Cu")
	)
	(gr_line
		(start 30.025086 -133.11505)
		(end 31.359602 -133.11505)
		(stroke
			(width 0.0635)
			(type default)
		)
		(layer "F.Cu")
	)
	(gr_line
		(start 30.025086 -130.57505)
		(end 31.359602 -130.57505)
		(stroke
			(width 0.0635)
			(type default)
		)
		(layer "F.Cu")
	)
	(gr_line
		(start 30.025086 -129.30505)
		(end 31.359602 -129.30505)
		(stroke
			(width 0.0635)
			(type default)
		)
		(layer "F.Cu")
	)
	(gr_line
		(start 30.025086 -19.385026)
		(end 31.359602 -19.385026)
		(stroke
			(width 0.0635)
			(type default)
		)
		(layer "F.Cu")
	)
	(gr_line
		(start 30.025086 -18.115026)
		(end 31.359602 -18.115026)
		(stroke
			(width 0.0635)
			(type default)
		)
		(layer "F.Cu")
	)
	(gr_line
		(start 30.025086 -15.575026)
		(end 31.359602 -15.575026)
		(stroke
			(width 0.0635)
			(type default)
		)
		(layer "F.Cu")
	)
	(gr_line
		(start 30.025086 -14.305026)
		(end 31.359602 -14.305026)
		(stroke
			(width 0.0635)
			(type default)
		)
		(layer "F.Cu")
	)
	(gr_line
		(start 31.359602 -249.385074)
		(end 31.486602 -249.258074)
		(stroke
			(width 0.0635)
			(type default)
		)
		(layer "F.Cu")
	)
	(gr_line
		(start 31.359602 -248.115074)
		(end 31.486602 -248.242074)
		(stroke
			(width 0.0635)
			(type default)
		)
		(layer "F.Cu")
	)
	(gr_line
		(start 31.359602 -245.575074)
		(end 31.486602 -245.448074)
		(stroke
			(width 0.0635)
			(type default)
		)
		(layer "F.Cu")
	)
	(gr_line
		(start 31.359602 -244.305074)
		(end 31.486602 -244.432074)
		(stroke
			(width 0.0635)
			(type default)
		)
		(layer "F.Cu")
	)
	(gr_line
		(start 31.359602 -134.38505)
		(end 31.486602 -134.25805)
		(stroke
			(width 0.0635)
			(type default)
		)
		(layer "F.Cu")
	)
	(gr_line
		(start 31.359602 -133.11505)
		(end 31.486602 -133.24205)
		(stroke
			(width 0.0635)
			(type default)
		)
		(layer "F.Cu")
	)
	(gr_line
		(start 31.359602 -130.57505)
		(end 31.486602 -130.44805)
		(stroke
			(width 0.0635)
			(type default)
		)
		(layer "F.Cu")
	)
	(gr_line
		(start 31.359602 -129.30505)
		(end 31.486602 -129.43205)
		(stroke
			(width 0.0635)
			(type default)
		)
		(layer "F.Cu")
	)
	(gr_line
		(start 31.359602 -19.385026)
		(end 31.486602 -19.258026)
		(stroke
			(width 0.0635)
			(type default)
		)
		(layer "F.Cu")
	)
	(gr_line
		(start 31.359602 -18.115026)
		(end 31.486602 -18.242026)
		(stroke
			(width 0.0635)
			(type default)
		)
		(layer "F.Cu")
	)
	(gr_line
		(start 31.359602 -15.575026)
		(end 31.486602 -15.448026)
		(stroke
			(width 0.0635)
			(type default)
		)
		(layer "F.Cu")
	)
	(gr_line
		(start 31.359602 -14.305026)
		(end 31.486602 -14.432026)
		(stroke
			(width 0.0635)
			(type default)
		)
		(layer "F.Cu")
	)
	(gr_line
		(start 31.486602 -249.023124)
		(end 31.486602 -249.258074)
		(stroke
			(width 0.0635)
			(type default)
		)
		(layer "F.Cu")
	)
	(gr_line
		(start 31.486602 -249.023124)
		(end 31.551372 -248.958354)
		(stroke
			(width 0.0635)
			(type default)
		)
		(layer "F.Cu")
	)
	(gr_line
		(start 31.486602 -248.477024)
		(end 31.551372 -248.541794)
		(stroke
			(width 0.0635)
			(type default)
		)
		(layer "F.Cu")
	)
	(gr_line
		(start 31.486602 -248.242074)
		(end 31.486602 -248.477024)
		(stroke
			(width 0.0635)
			(type default)
		)
		(layer "F.Cu")
	)
	(gr_line
		(start 31.486602 -245.213124)
		(end 31.486602 -245.448074)
		(stroke
			(width 0.0635)
			(type default)
		)
		(layer "F.Cu")
	)
	(gr_line
		(start 31.486602 -245.213124)
		(end 31.551372 -245.148354)
		(stroke
			(width 0.0635)
			(type default)
		)
		(layer "F.Cu")
	)
	(gr_line
		(start 31.486602 -244.667024)
		(end 31.551372 -244.731794)
		(stroke
			(width 0.0635)
			(type default)
		)
		(layer "F.Cu")
	)
	(gr_line
		(start 31.486602 -244.432074)
		(end 31.486602 -244.667024)
		(stroke
			(width 0.0635)
			(type default)
		)
		(layer "F.Cu")
	)
	(gr_line
		(start 31.486602 -134.0231)
		(end 31.486602 -134.25805)
		(stroke
			(width 0.0635)
			(type default)
		)
		(layer "F.Cu")
	)
	(gr_line
		(start 31.486602 -134.0231)
		(end 31.551372 -133.95833)
		(stroke
			(width 0.0635)
			(type default)
		)
		(layer "F.Cu")
	)
	(gr_line
		(start 31.486602 -133.477)
		(end 31.551372 -133.54177)
		(stroke
			(width 0.0635)
			(type default)
		)
		(layer "F.Cu")
	)
	(gr_line
		(start 31.486602 -133.24205)
		(end 31.486602 -133.477)
		(stroke
			(width 0.0635)
			(type default)
		)
		(layer "F.Cu")
	)
	(gr_line
		(start 31.486602 -130.2131)
		(end 31.486602 -130.44805)
		(stroke
			(width 0.0635)
			(type default)
		)
		(layer "F.Cu")
	)
	(gr_line
		(start 31.486602 -130.2131)
		(end 31.551372 -130.14833)
		(stroke
			(width 0.0635)
			(type default)
		)
		(layer "F.Cu")
	)
	(gr_line
		(start 31.486602 -129.667)
		(end 31.551372 -129.73177)
		(stroke
			(width 0.0635)
			(type default)
		)
		(layer "F.Cu")
	)
	(gr_line
		(start 31.486602 -129.43205)
		(end 31.486602 -129.667)
		(stroke
			(width 0.0635)
			(type default)
		)
		(layer "F.Cu")
	)
	(gr_line
		(start 31.486602 -19.023076)
		(end 31.486602 -19.258026)
		(stroke
			(width 0.0635)
			(type default)
		)
		(layer "F.Cu")
	)
	(gr_line
		(start 31.486602 -19.023076)
		(end 31.551372 -18.958306)
		(stroke
			(width 0.0635)
			(type default)
		)
		(layer "F.Cu")
	)
	(gr_line
		(start 31.486602 -18.476976)
		(end 31.551372 -18.541746)
		(stroke
			(width 0.0635)
			(type default)
		)
		(layer "F.Cu")
	)
	(gr_line
		(start 31.486602 -18.242026)
		(end 31.486602 -18.476976)
		(stroke
			(width 0.0635)
			(type default)
		)
		(layer "F.Cu")
	)
	(gr_line
		(start 31.486602 -15.213076)
		(end 31.486602 -15.448026)
		(stroke
			(width 0.0635)
			(type default)
		)
		(layer "F.Cu")
	)
	(gr_line
		(start 31.486602 -15.213076)
		(end 31.551372 -15.148306)
		(stroke
			(width 0.0635)
			(type default)
		)
		(layer "F.Cu")
	)
	(gr_line
		(start 31.486602 -14.666976)
		(end 31.551372 -14.731746)
		(stroke
			(width 0.0635)
			(type default)
		)
		(layer "F.Cu")
	)
	(gr_line
		(start 31.486602 -14.432026)
		(end 31.486602 -14.666976)
		(stroke
			(width 0.0635)
			(type default)
		)
		(layer "F.Cu")
	)
	(gr_line
		(start 31.728918 -245.095522)
		(end 31.85287 -245.219474)
		(stroke
			(width 0.0635)
			(type default)
		)
		(layer "F.Cu")
	)
	(gr_line
		(start 31.728918 -244.784626)
		(end 31.85287 -244.660674)
		(stroke
			(width 0.0635)
			(type default)
		)
		(layer "F.Cu")
	)
	(gr_line
		(start 31.728918 -130.095498)
		(end 31.85287 -130.21945)
		(stroke
			(width 0.0635)
			(type default)
		)
		(layer "F.Cu")
	)
	(gr_line
		(start 31.728918 -129.784602)
		(end 31.85287 -129.66065)
		(stroke
			(width 0.0635)
			(type default)
		)
		(layer "F.Cu")
	)
	(gr_line
		(start 31.728918 -15.095474)
		(end 31.85287 -15.219426)
		(stroke
			(width 0.0635)
			(type default)
		)
		(layer "F.Cu")
	)
	(gr_line
		(start 31.728918 -14.784578)
		(end 31.85287 -14.660626)
		(stroke
			(width 0.0635)
			(type default)
		)
		(layer "F.Cu")
	)
	(gr_line
		(start 31.85287 -245.219474)
		(end 32.184086 -245.219474)
		(stroke
			(width 0.0635)
			(type default)
		)
		(layer "F.Cu")
	)
	(gr_line
		(start 31.85287 -244.660674)
		(end 32.184086 -244.660674)
		(stroke
			(width 0.0635)
			(type default)
		)
		(layer "F.Cu")
	)
	(gr_line
		(start 31.85287 -130.21945)
		(end 32.184086 -130.21945)
		(stroke
			(width 0.0635)
			(type default)
		)
		(layer "F.Cu")
	)
	(gr_line
		(start 31.85287 -129.66065)
		(end 32.184086 -129.66065)
		(stroke
			(width 0.0635)
			(type default)
		)
		(layer "F.Cu")
	)
	(gr_line
		(start 31.85287 -15.219426)
		(end 32.184086 -15.219426)
		(stroke
			(width 0.0635)
			(type default)
		)
		(layer "F.Cu")
	)
	(gr_line
		(start 31.85287 -14.660626)
		(end 32.184086 -14.660626)
		(stroke
			(width 0.0635)
			(type default)
		)
		(layer "F.Cu")
	)
	(gr_arc
		(start 32.381952 -248.604024)
		(mid 32.471755 -248.566827)
		(end 32.508952 -248.477024)
		(stroke
			(width 0.0635)
			(type default)
		)
		(layer "F.Cu")
	)
	(gr_arc
		(start 32.381952 -133.604)
		(mid 32.471755 -133.566803)
		(end 32.508952 -133.477)
		(stroke
			(width 0.0635)
			(type default)
		)
		(layer "F.Cu")
	)
	(gr_arc
		(start 32.381952 -18.603976)
		(mid 32.471755 -18.566779)
		(end 32.508952 -18.476976)
		(stroke
			(width 0.0635)
			(type default)
		)
		(layer "F.Cu")
	)
	(gr_arc
		(start 32.508952 -249.023124)
		(mid 32.47176 -248.933323)
		(end 32.381952 -248.896124)
		(stroke
			(width 0.0635)
			(type default)
		)
		(layer "F.Cu")
	)
	(gr_line
		(start 32.508952 -249.023124)
		(end 32.508952 -249.385074)
		(stroke
			(width 0.0635)
			(type default)
		)
		(layer "F.Cu")
	)
	(gr_line
		(start 32.508952 -248.115074)
		(end 32.508952 -248.477024)
		(stroke
			(width 0.0635)
			(type default)
		)
		(layer "F.Cu")
	)
	(gr_arc
		(start 32.508952 -134.0231)
		(mid 32.471752 -133.933314)
		(end 32.381952 -133.8961)
		(stroke
			(width 0.0635)
			(type default)
		)
		(layer "F.Cu")
	)
	(gr_line
		(start 32.508952 -134.0231)
		(end 32.508952 -134.38505)
		(stroke
			(width 0.0635)
			(type default)
		)
		(layer "F.Cu")
	)
	(gr_line
		(start 32.508952 -133.11505)
		(end 32.508952 -133.477)
		(stroke
			(width 0.0635)
			(type default)
		)
		(layer "F.Cu")
	)
	(gr_arc
		(start 32.508952 -19.023076)
		(mid 32.471743 -18.933306)
		(end 32.381952 -18.896076)
		(stroke
			(width 0.0635)
			(type default)
		)
		(layer "F.Cu")
	)
	(gr_line
		(start 32.508952 -19.023076)
		(end 32.508952 -19.385026)
		(stroke
			(width 0.0635)
			(type default)
		)
		(layer "F.Cu")
	)
	(gr_line
		(start 32.508952 -18.115026)
		(end 32.508952 -18.476976)
		(stroke
			(width 0.0635)
			(type default)
		)
		(layer "F.Cu")
	)
	(gr_line
		(start 32.742886 -245.219474)
		(end 33.123124 -245.219474)
		(stroke
			(width 0.0635)
			(type default)
		)
		(layer "F.Cu")
	)
	(gr_line
		(start 32.742886 -244.660674)
		(end 33.138872 -244.660674)
		(stroke
			(width 0.0635)
			(type default)
		)
		(layer "F.Cu")
	)
	(gr_line
		(start 32.742886 -130.21945)
		(end 33.123124 -130.21945)
		(stroke
			(width 0.0635)
			(type default)
		)
		(layer "F.Cu")
	)
	(gr_line
		(start 32.742886 -129.66065)
		(end 33.138872 -129.66065)
		(stroke
			(width 0.0635)
			(type default)
		)
		(layer "F.Cu")
	)
	(gr_line
		(start 32.742886 -15.219426)
		(end 33.123124 -15.219426)
		(stroke
			(width 0.0635)
			(type default)
		)
		(layer "F.Cu")
	)
	(gr_line
		(start 32.742886 -14.660626)
		(end 33.138872 -14.660626)
		(stroke
			(width 0.0635)
			(type default)
		)
		(layer "F.Cu")
	)
	(gr_line
		(start 33.123124 -245.219474)
		(end 33.202118 -245.14048)
		(stroke
			(width 0.0635)
			(type default)
		)
		(layer "F.Cu")
	)
	(gr_line
		(start 33.123124 -130.21945)
		(end 33.202118 -130.140456)
		(stroke
			(width 0.0635)
			(type default)
		)
		(layer "F.Cu")
	)
	(gr_line
		(start 33.123124 -15.219426)
		(end 33.202118 -15.140432)
		(stroke
			(width 0.0635)
			(type default)
		)
		(layer "F.Cu")
	)
	(gr_line
		(start 33.138872 -244.660674)
		(end 33.202118 -244.72392)
		(stroke
			(width 0.0635)
			(type default)
		)
		(layer "F.Cu")
	)
	(gr_line
		(start 33.138872 -129.66065)
		(end 33.202118 -129.723896)
		(stroke
			(width 0.0635)
			(type default)
		)
		(layer "F.Cu")
	)
	(gr_line
		(start 33.138872 -14.660626)
		(end 33.202118 -14.723872)
		(stroke
			(width 0.0635)
			(type default)
		)
		(layer "F.Cu")
	)
	(gr_arc
		(start 34.126678 -244.844824)
		(mid 34.239111 -244.798253)
		(end 34.285682 -244.68582)
		(stroke
			(width 0.0635)
			(type default)
		)
		(layer "F.Cu")
	)
	(gr_arc
		(start 34.126678 -129.8448)
		(mid 34.239111 -129.798229)
		(end 34.285682 -129.685796)
		(stroke
			(width 0.0635)
			(type default)
		)
		(layer "F.Cu")
	)
	(gr_arc
		(start 34.126678 -14.844776)
		(mid 34.239111 -14.798205)
		(end 34.285682 -14.685772)
		(stroke
			(width 0.0635)
			(type default)
		)
		(layer "F.Cu")
	)
	(gr_arc
		(start 34.285682 -245.295928)
		(mid 34.239119 -245.183485)
		(end 34.126678 -245.136924)
		(stroke
			(width 0.0635)
			(type default)
		)
		(layer "F.Cu")
	)
	(gr_line
		(start 34.285682 -245.295928)
		(end 34.285682 -245.562374)
		(stroke
			(width 0.0635)
			(type default)
		)
		(layer "F.Cu")
	)
	(gr_line
		(start 34.285682 -244.419374)
		(end 34.285682 -244.68582)
		(stroke
			(width 0.0635)
			(type default)
		)
		(layer "F.Cu")
	)
	(gr_arc
		(start 34.285682 -130.295904)
		(mid 34.239111 -130.183476)
		(end 34.126678 -130.1369)
		(stroke
			(width 0.0635)
			(type default)
		)
		(layer "F.Cu")
	)
	(gr_line
		(start 34.285682 -130.295904)
		(end 34.285682 -130.56235)
		(stroke
			(width 0.0635)
			(type default)
		)
		(layer "F.Cu")
	)
	(gr_line
		(start 34.285682 -129.41935)
		(end 34.285682 -129.685796)
		(stroke
			(width 0.0635)
			(type default)
		)
		(layer "F.Cu")
	)
	(gr_arc
		(start 34.285682 -15.29588)
		(mid 34.239102 -15.183468)
		(end 34.126678 -15.136876)
		(stroke
			(width 0.0635)
			(type default)
		)
		(layer "F.Cu")
	)
	(gr_line
		(start 34.285682 -15.29588)
		(end 34.285682 -15.562326)
		(stroke
			(width 0.0635)
			(type default)
		)
		(layer "F.Cu")
	)
	(gr_line
		(start 34.285682 -14.419326)
		(end 34.285682 -14.685772)
		(stroke
			(width 0.0635)
			(type default)
		)
		(layer "F.Cu")
	)
	(gr_line
		(start 61.574934 -249.385074)
		(end 62.90945 -249.385074)
		(stroke
			(width 0.0635)
			(type default)
		)
		(layer "F.Cu")
	)
	(gr_line
		(start 61.574934 -248.115074)
		(end 62.90945 -248.115074)
		(stroke
			(width 0.0635)
			(type default)
		)
		(layer "F.Cu")
	)
	(gr_line
		(start 61.574934 -245.575074)
		(end 62.90945 -245.575074)
		(stroke
			(width 0.0635)
			(type default)
		)
		(layer "F.Cu")
	)
	(gr_line
		(start 61.574934 -244.305074)
		(end 62.90945 -244.305074)
		(stroke
			(width 0.0635)
			(type default)
		)
		(layer "F.Cu")
	)
	(gr_line
		(start 61.574934 -134.38505)
		(end 62.90945 -134.38505)
		(stroke
			(width 0.0635)
			(type default)
		)
		(layer "F.Cu")
	)
	(gr_line
		(start 61.574934 -133.11505)
		(end 62.90945 -133.11505)
		(stroke
			(width 0.0635)
			(type default)
		)
		(layer "F.Cu")
	)
	(gr_line
		(start 61.574934 -130.57505)
		(end 62.90945 -130.57505)
		(stroke
			(width 0.0635)
			(type default)
		)
		(layer "F.Cu")
	)
	(gr_line
		(start 61.574934 -129.30505)
		(end 62.90945 -129.30505)
		(stroke
			(width 0.0635)
			(type default)
		)
		(layer "F.Cu")
	)
	(gr_line
		(start 61.574934 -19.385026)
		(end 62.90945 -19.385026)
		(stroke
			(width 0.0635)
			(type default)
		)
		(layer "F.Cu")
	)
	(gr_line
		(start 61.574934 -18.115026)
		(end 62.90945 -18.115026)
		(stroke
			(width 0.0635)
			(type default)
		)
		(layer "F.Cu")
	)
	(gr_line
		(start 61.574934 -15.575026)
		(end 62.90945 -15.575026)
		(stroke
			(width 0.0635)
			(type default)
		)
		(layer "F.Cu")
	)
	(gr_line
		(start 61.574934 -14.305026)
		(end 62.90945 -14.305026)
		(stroke
			(width 0.0635)
			(type default)
		)
		(layer "F.Cu")
	)
	(gr_line
		(start 62.90945 -249.385074)
		(end 63.03645 -249.258074)
		(stroke
			(width 0.0635)
			(type default)
		)
		(layer "F.Cu")
	)
	(gr_line
		(start 62.90945 -248.115074)
		(end 63.03645 -248.242074)
		(stroke
			(width 0.0635)
			(type default)
		)
		(layer "F.Cu")
	)
	(gr_line
		(start 62.90945 -245.575074)
		(end 63.03645 -245.448074)
		(stroke
			(width 0.0635)
			(type default)
		)
		(layer "F.Cu")
	)
	(gr_line
		(start 62.90945 -244.305074)
		(end 63.03645 -244.432074)
		(stroke
			(width 0.0635)
			(type default)
		)
		(layer "F.Cu")
	)
	(gr_line
		(start 62.90945 -134.38505)
		(end 63.03645 -134.25805)
		(stroke
			(width 0.0635)
			(type default)
		)
		(layer "F.Cu")
	)
	(gr_line
		(start 62.90945 -133.11505)
		(end 63.03645 -133.24205)
		(stroke
			(width 0.0635)
			(type default)
		)
		(layer "F.Cu")
	)
	(gr_line
		(start 62.90945 -130.57505)
		(end 63.03645 -130.44805)
		(stroke
			(width 0.0635)
			(type default)
		)
		(layer "F.Cu")
	)
	(gr_line
		(start 62.90945 -129.30505)
		(end 63.03645 -129.43205)
		(stroke
			(width 0.0635)
			(type default)
		)
		(layer "F.Cu")
	)
	(gr_line
		(start 62.90945 -19.385026)
		(end 63.03645 -19.258026)
		(stroke
			(width 0.0635)
			(type default)
		)
		(layer "F.Cu")
	)
	(gr_line
		(start 62.90945 -18.115026)
		(end 63.03645 -18.242026)
		(stroke
			(width 0.0635)
			(type default)
		)
		(layer "F.Cu")
	)
	(gr_line
		(start 62.90945 -15.575026)
		(end 63.03645 -15.448026)
		(stroke
			(width 0.0635)
			(type default)
		)
		(layer "F.Cu")
	)
	(gr_line
		(start 62.90945 -14.305026)
		(end 63.03645 -14.432026)
		(stroke
			(width 0.0635)
			(type default)
		)
		(layer "F.Cu")
	)
	(gr_line
		(start 63.03645 -249.023124)
		(end 63.03645 -249.258074)
		(stroke
			(width 0.0635)
			(type default)
		)
		(layer "F.Cu")
	)
	(gr_line
		(start 63.03645 -249.023124)
		(end 63.11138 -248.948194)
		(stroke
			(width 0.0635)
			(type default)
		)
		(layer "F.Cu")
	)
	(gr_line
		(start 63.03645 -248.45645)
		(end 63.11138 -248.53138)
		(stroke
			(width 0.0635)
			(type default)
		)
		(layer "F.Cu")
	)
	(gr_line
		(start 63.03645 -248.242074)
		(end 63.03645 -248.45645)
		(stroke
			(width 0.0635)
			(type default)
		)
		(layer "F.Cu")
	)
	(gr_line
		(start 63.03645 -245.213124)
		(end 63.03645 -245.448074)
		(stroke
			(width 0.0635)
			(type default)
		)
		(layer "F.Cu")
	)
	(gr_line
		(start 63.03645 -245.213124)
		(end 63.10122 -245.148354)
		(stroke
			(width 0.0635)
			(type default)
		)
		(layer "F.Cu")
	)
	(gr_line
		(start 63.03645 -244.667024)
		(end 63.10122 -244.731794)
		(stroke
			(width 0.0635)
			(type default)
		)
		(layer "F.Cu")
	)
	(gr_line
		(start 63.03645 -244.432074)
		(end 63.03645 -244.667024)
		(stroke
			(width 0.0635)
			(type default)
		)
		(layer "F.Cu")
	)
	(gr_line
		(start 63.03645 -133.99135)
		(end 63.03645 -134.25805)
		(stroke
			(width 0.0635)
			(type default)
		)
		(layer "F.Cu")
	)
	(gr_line
		(start 63.03645 -133.99135)
		(end 63.085218 -133.942582)
		(stroke
			(width 0.0635)
			(type default)
		)
		(layer "F.Cu")
	)
	(gr_line
		(start 63.03645 -133.477)
		(end 63.085218 -133.525768)
		(stroke
			(width 0.0635)
			(type default)
		)
		(layer "F.Cu")
	)
	(gr_line
		(start 63.03645 -133.24205)
		(end 63.03645 -133.477)
		(stroke
			(width 0.0635)
			(type default)
		)
		(layer "F.Cu")
	)
	(gr_line
		(start 63.03645 -130.2131)
		(end 63.03645 -130.44805)
		(stroke
			(width 0.0635)
			(type default)
		)
		(layer "F.Cu")
	)
	(gr_line
		(start 63.03645 -130.2131)
		(end 63.10122 -130.14833)
		(stroke
			(width 0.0635)
			(type default)
		)
		(layer "F.Cu")
	)
	(gr_line
		(start 63.03645 -129.667)
		(end 63.10122 -129.73177)
		(stroke
			(width 0.0635)
			(type default)
		)
		(layer "F.Cu")
	)
	(gr_line
		(start 63.03645 -129.43205)
		(end 63.03645 -129.667)
		(stroke
			(width 0.0635)
			(type default)
		)
		(layer "F.Cu")
	)
	(gr_line
		(start 63.03645 -19.023076)
		(end 63.03645 -19.258026)
		(stroke
			(width 0.0635)
			(type default)
		)
		(layer "F.Cu")
	)
	(gr_line
		(start 63.03645 -19.023076)
		(end 63.10122 -18.958306)
		(stroke
			(width 0.0635)
			(type default)
		)
		(layer "F.Cu")
	)
	(gr_line
		(start 63.03645 -18.476976)
		(end 63.10122 -18.541746)
		(stroke
			(width 0.0635)
			(type default)
		)
		(layer "F.Cu")
	)
	(gr_line
		(start 63.03645 -18.242026)
		(end 63.03645 -18.476976)
		(stroke
			(width 0.0635)
			(type default)
		)
		(layer "F.Cu")
	)
	(gr_line
		(start 63.03645 -15.213076)
		(end 63.03645 -15.448026)
		(stroke
			(width 0.0635)
			(type default)
		)
		(layer "F.Cu")
	)
	(gr_line
		(start 63.03645 -15.213076)
		(end 63.10122 -15.148306)
		(stroke
			(width 0.0635)
			(type default)
		)
		(layer "F.Cu")
	)
	(gr_line
		(start 63.03645 -14.666976)
		(end 63.10122 -14.731746)
		(stroke
			(width 0.0635)
			(type default)
		)
		(layer "F.Cu")
	)
	(gr_line
		(start 63.03645 -14.432026)
		(end 63.03645 -14.666976)
		(stroke
			(width 0.0635)
			(type default)
		)
		(layer "F.Cu")
	)
	(gr_line
		(start 63.278766 -245.095522)
		(end 63.402718 -245.219474)
		(stroke
			(width 0.0635)
			(type default)
		)
		(layer "F.Cu")
	)
	(gr_line
		(start 63.278766 -244.784626)
		(end 63.402718 -244.660674)
		(stroke
			(width 0.0635)
			(type default)
		)
		(layer "F.Cu")
	)
	(gr_line
		(start 63.278766 -130.095498)
		(end 63.402718 -130.21945)
		(stroke
			(width 0.0635)
			(type default)
		)
		(layer "F.Cu")
	)
	(gr_line
		(start 63.278766 -129.784602)
		(end 63.402718 -129.66065)
		(stroke
			(width 0.0635)
			(type default)
		)
		(layer "F.Cu")
	)
	(gr_line
		(start 63.278766 -15.095474)
		(end 63.402718 -15.219426)
		(stroke
			(width 0.0635)
			(type default)
		)
		(layer "F.Cu")
	)
	(gr_line
		(start 63.278766 -14.784578)
		(end 63.402718 -14.660626)
		(stroke
			(width 0.0635)
			(type default)
		)
		(layer "F.Cu")
	)
	(gr_line
		(start 63.402718 -245.219474)
		(end 63.733934 -245.219474)
		(stroke
			(width 0.0635)
			(type default)
		)
		(layer "F.Cu")
	)
	(gr_line
		(start 63.402718 -244.660674)
		(end 63.733934 -244.660674)
		(stroke
			(width 0.0635)
			(type default)
		)
		(layer "F.Cu")
	)
	(gr_line
		(start 63.402718 -130.21945)
		(end 63.733934 -130.21945)
		(stroke
			(width 0.0635)
			(type default)
		)
		(layer "F.Cu")
	)
	(gr_line
		(start 63.402718 -129.66065)
		(end 63.733934 -129.66065)
		(stroke
			(width 0.0635)
			(type default)
		)
		(layer "F.Cu")
	)
	(gr_line
		(start 63.402718 -15.219426)
		(end 63.733934 -15.219426)
		(stroke
			(width 0.0635)
			(type default)
		)
		(layer "F.Cu")
	)
	(gr_line
		(start 63.402718 -14.660626)
		(end 63.733934 -14.660626)
		(stroke
			(width 0.0635)
			(type default)
		)
		(layer "F.Cu")
	)
	(gr_arc
		(start 63.9318 -248.604024)
		(mid 64.021603 -248.566827)
		(end 64.0588 -248.477024)
		(stroke
			(width 0.0635)
			(type default)
		)
		(layer "F.Cu")
	)
	(gr_arc
		(start 63.9318 -133.604)
		(mid 64.021603 -133.566803)
		(end 64.0588 -133.477)
		(stroke
			(width 0.0635)
			(type default)
		)
		(layer "F.Cu")
	)
	(gr_arc
		(start 63.9318 -18.603976)
		(mid 64.021603 -18.566779)
		(end 64.0588 -18.476976)
		(stroke
			(width 0.0635)
			(type default)
		)
		(layer "F.Cu")
	)
	(gr_arc
		(start 64.0588 -249.023124)
		(mid 64.021611 -248.933306)
		(end 63.9318 -248.896124)
		(stroke
			(width 0.0635)
			(type default)
		)
		(layer "F.Cu")
	)
	(gr_line
		(start 64.0588 -249.023124)
		(end 64.0588 -249.385074)
		(stroke
			(width 0.0635)
			(type default)
		)
		(layer "F.Cu")
	)
	(gr_line
		(start 64.0588 -248.115074)
		(end 64.0588 -248.477024)
		(stroke
			(width 0.0635)
			(type default)
		)
		(layer "F.Cu")
	)
	(gr_arc
		(start 64.0588 -134.0231)
		(mid 64.021603 -133.933297)
		(end 63.9318 -133.8961)
		(stroke
			(width 0.0635)
			(type default)
		)
		(layer "F.Cu")
	)
	(gr_line
		(start 64.0588 -134.0231)
		(end 64.0588 -134.38505)
		(stroke
			(width 0.0635)
			(type default)
		)
		(layer "F.Cu")
	)
	(gr_line
		(start 64.0588 -133.11505)
		(end 64.0588 -133.477)
		(stroke
			(width 0.0635)
			(type default)
		)
		(layer "F.Cu")
	)
	(gr_arc
		(start 64.0588 -19.023076)
		(mid 64.021594 -18.933289)
		(end 63.9318 -18.896076)
		(stroke
			(width 0.0635)
			(type default)
		)
		(layer "F.Cu")
	)
	(gr_line
		(start 64.0588 -19.023076)
		(end 64.0588 -19.385026)
		(stroke
			(width 0.0635)
			(type default)
		)
		(layer "F.Cu")
	)
	(gr_line
		(start 64.0588 -18.115026)
		(end 64.0588 -18.476976)
		(stroke
			(width 0.0635)
			(type default)
		)
		(layer "F.Cu")
	)
	(gr_line
		(start 64.292734 -245.219474)
		(end 64.672972 -245.219474)
		(stroke
			(width 0.0635)
			(type default)
		)
		(layer "F.Cu")
	)
	(gr_line
		(start 64.292734 -244.660674)
		(end 64.68872 -244.660674)
		(stroke
			(width 0.0635)
			(type default)
		)
		(layer "F.Cu")
	)
	(gr_line
		(start 64.292734 -130.21945)
		(end 64.672972 -130.21945)
		(stroke
			(width 0.0635)
			(type default)
		)
		(layer "F.Cu")
	)
	(gr_line
		(start 64.292734 -129.66065)
		(end 64.68872 -129.66065)
		(stroke
			(width 0.0635)
			(type default)
		)
		(layer "F.Cu")
	)
	(gr_line
		(start 64.292734 -15.219426)
		(end 64.672972 -15.219426)
		(stroke
			(width 0.0635)
			(type default)
		)
		(layer "F.Cu")
	)
	(gr_line
		(start 64.292734 -14.660626)
		(end 64.68872 -14.660626)
		(stroke
			(width 0.0635)
			(type default)
		)
		(layer "F.Cu")
	)
	(gr_line
		(start 64.672972 -245.219474)
		(end 64.751966 -245.14048)
		(stroke
			(width 0.0635)
			(type default)
		)
		(layer "F.Cu")
	)
	(gr_line
		(start 64.672972 -130.21945)
		(end 64.751966 -130.140456)
		(stroke
			(width 0.0635)
			(type default)
		)
		(layer "F.Cu")
	)
	(gr_line
		(start 64.672972 -15.219426)
		(end 64.751966 -15.140432)
		(stroke
			(width 0.0635)
			(type default)
		)
		(layer "F.Cu")
	)
	(gr_line
		(start 64.68872 -244.660674)
		(end 64.751966 -244.72392)
		(stroke
			(width 0.0635)
			(type default)
		)
		(layer "F.Cu")
	)
	(gr_line
		(start 64.68872 -129.66065)
		(end 64.751966 -129.723896)
		(stroke
			(width 0.0635)
			(type default)
		)
		(layer "F.Cu")
	)
	(gr_line
		(start 64.68872 -14.660626)
		(end 64.751966 -14.723872)
		(stroke
			(width 0.0635)
			(type default)
		)
		(layer "F.Cu")
	)
	(gr_arc
		(start 65.676526 -244.844824)
		(mid 65.788959 -244.798253)
		(end 65.83553 -244.68582)
		(stroke
			(width 0.0635)
			(type default)
		)
		(layer "F.Cu")
	)
	(gr_arc
		(start 65.676526 -129.8448)
		(mid 65.788959 -129.798229)
		(end 65.83553 -129.685796)
		(stroke
			(width 0.0635)
			(type default)
		)
		(layer "F.Cu")
	)
	(gr_arc
		(start 65.676526 -14.844776)
		(mid 65.788959 -14.798205)
		(end 65.83553 -14.685772)
		(stroke
			(width 0.0635)
			(type default)
		)
		(layer "F.Cu")
	)
	(gr_arc
		(start 65.83553 -245.295928)
		(mid 65.78897 -245.183468)
		(end 65.676526 -245.136924)
		(stroke
			(width 0.0635)
			(type default)
		)
		(layer "F.Cu")
	)
	(gr_line
		(start 65.83553 -245.295928)
		(end 65.83553 -245.562374)
		(stroke
			(width 0.0635)
			(type default)
		)
		(layer "F.Cu")
	)
	(gr_line
		(start 65.83553 -244.419374)
		(end 65.83553 -244.68582)
		(stroke
			(width 0.0635)
			(type default)
		)
		(layer "F.Cu")
	)
	(gr_arc
		(start 65.83553 -130.295904)
		(mid 65.788962 -130.183459)
		(end 65.676526 -130.1369)
		(stroke
			(width 0.0635)
			(type default)
		)
		(layer "F.Cu")
	)
	(gr_line
		(start 65.83553 -130.295904)
		(end 65.83553 -130.56235)
		(stroke
			(width 0.0635)
			(type default)
		)
		(layer "F.Cu")
	)
	(gr_line
		(start 65.83553 -129.41935)
		(end 65.83553 -129.685796)
		(stroke
			(width 0.0635)
			(type default)
		)
		(layer "F.Cu")
	)
	(gr_arc
		(start 65.83553 -15.29588)
		(mid 65.788953 -15.183451)
		(end 65.676526 -15.136876)
		(stroke
			(width 0.0635)
			(type default)
		)
		(layer "F.Cu")
	)
	(gr_line
		(start 65.83553 -15.29588)
		(end 65.83553 -15.562326)
		(stroke
			(width 0.0635)
			(type default)
		)
		(layer "F.Cu")
	)
	(gr_line
		(start 65.83553 -14.419326)
		(end 65.83553 -14.685772)
		(stroke
			(width 0.0635)
			(type default)
		)
		(layer "F.Cu")
	)
	(gr_line
		(start 93.125036 -249.385074)
		(end 94.459552 -249.385074)
		(stroke
			(width 0.0635)
			(type default)
		)
		(layer "F.Cu")
	)
	(gr_line
		(start 93.125036 -248.115074)
		(end 94.459552 -248.115074)
		(stroke
			(width 0.0635)
			(type default)
		)
		(layer "F.Cu")
	)
	(gr_line
		(start 93.125036 -245.575074)
		(end 94.459552 -245.575074)
		(stroke
			(width 0.0635)
			(type default)
		)
		(layer "F.Cu")
	)
	(gr_line
		(start 93.125036 -244.305074)
		(end 94.459552 -244.305074)
		(stroke
			(width 0.0635)
			(type default)
		)
		(layer "F.Cu")
	)
	(gr_line
		(start 93.125036 -134.38505)
		(end 94.459552 -134.38505)
		(stroke
			(width 0.0635)
			(type default)
		)
		(layer "F.Cu")
	)
	(gr_line
		(start 93.125036 -133.11505)
		(end 94.459552 -133.11505)
		(stroke
			(width 0.0635)
			(type default)
		)
		(layer "F.Cu")
	)
	(gr_line
		(start 93.125036 -130.57505)
		(end 94.459552 -130.57505)
		(stroke
			(width 0.0635)
			(type default)
		)
		(layer "F.Cu")
	)
	(gr_line
		(start 93.125036 -129.30505)
		(end 94.459552 -129.30505)
		(stroke
			(width 0.0635)
			(type default)
		)
		(layer "F.Cu")
	)
	(gr_line
		(start 93.125036 -19.385026)
		(end 94.483174 -19.385026)
		(stroke
			(width 0.0635)
			(type default)
		)
		(layer "F.Cu")
	)
	(gr_line
		(start 93.125036 -18.115026)
		(end 94.442026 -18.115026)
		(stroke
			(width 0.0635)
			(type default)
		)
		(layer "F.Cu")
	)
	(gr_line
		(start 93.125036 -15.575026)
		(end 94.459552 -15.575026)
		(stroke
			(width 0.0635)
			(type default)
		)
		(layer "F.Cu")
	)
	(gr_line
		(start 93.125036 -14.305026)
		(end 94.459552 -14.305026)
		(stroke
			(width 0.0635)
			(type default)
		)
		(layer "F.Cu")
	)
	(gr_line
		(start 94.442026 -18.115026)
		(end 94.586552 -18.259552)
		(stroke
			(width 0.0635)
			(type default)
		)
		(layer "F.Cu")
	)
	(gr_line
		(start 94.459552 -249.385074)
		(end 94.586552 -249.258074)
		(stroke
			(width 0.0635)
			(type default)
		)
		(layer "F.Cu")
	)
	(gr_line
		(start 94.459552 -248.115074)
		(end 94.586552 -248.242074)
		(stroke
			(width 0.0635)
			(type default)
		)
		(layer "F.Cu")
	)
	(gr_line
		(start 94.459552 -245.575074)
		(end 94.586552 -245.448074)
		(stroke
			(width 0.0635)
			(type default)
		)
		(layer "F.Cu")
	)
	(gr_line
		(start 94.459552 -244.305074)
		(end 94.586552 -244.432074)
		(stroke
			(width 0.0635)
			(type default)
		)
		(layer "F.Cu")
	)
	(gr_line
		(start 94.459552 -134.38505)
		(end 94.586552 -134.25805)
		(stroke
			(width 0.0635)
			(type default)
		)
		(layer "F.Cu")
	)
	(gr_line
		(start 94.459552 -133.11505)
		(end 94.586552 -133.24205)
		(stroke
			(width 0.0635)
			(type default)
		)
		(layer "F.Cu")
	)
	(gr_line
		(start 94.459552 -130.57505)
		(end 94.586552 -130.44805)
		(stroke
			(width 0.0635)
			(type default)
		)
		(layer "F.Cu")
	)
	(gr_line
		(start 94.459552 -129.30505)
		(end 94.586552 -129.43205)
		(stroke
			(width 0.0635)
			(type default)
		)
		(layer "F.Cu")
	)
	(gr_line
		(start 94.459552 -15.575026)
		(end 94.586552 -15.448026)
		(stroke
			(width 0.0635)
			(type default)
		)
		(layer "F.Cu")
	)
	(gr_line
		(start 94.459552 -14.305026)
		(end 94.586552 -14.432026)
		(stroke
			(width 0.0635)
			(type default)
		)
		(layer "F.Cu")
	)
	(gr_line
		(start 94.483174 -19.385026)
		(end 94.586552 -19.281648)
		(stroke
			(width 0.0635)
			(type default)
		)
		(layer "F.Cu")
	)
	(gr_line
		(start 94.586552 -249.023124)
		(end 94.586552 -249.258074)
		(stroke
			(width 0.0635)
			(type default)
		)
		(layer "F.Cu")
	)
	(gr_line
		(start 94.586552 -249.023124)
		(end 94.651322 -248.958354)
		(stroke
			(width 0.0635)
			(type default)
		)
		(layer "F.Cu")
	)
	(gr_line
		(start 94.586552 -248.477024)
		(end 94.651322 -248.541794)
		(stroke
			(width 0.0635)
			(type default)
		)
		(layer "F.Cu")
	)
	(gr_line
		(start 94.586552 -248.242074)
		(end 94.586552 -248.477024)
		(stroke
			(width 0.0635)
			(type default)
		)
		(layer "F.Cu")
	)
	(gr_line
		(start 94.586552 -245.213124)
		(end 94.586552 -245.448074)
		(stroke
			(width 0.0635)
			(type default)
		)
		(layer "F.Cu")
	)
	(gr_line
		(start 94.586552 -245.213124)
		(end 94.651322 -245.148354)
		(stroke
			(width 0.0635)
			(type default)
		)
		(layer "F.Cu")
	)
	(gr_line
		(start 94.586552 -244.667024)
		(end 94.651322 -244.731794)
		(stroke
			(width 0.0635)
			(type default)
		)
		(layer "F.Cu")
	)
	(gr_line
		(start 94.586552 -244.432074)
		(end 94.586552 -244.667024)
		(stroke
			(width 0.0635)
			(type default)
		)
		(layer "F.Cu")
	)
	(gr_line
		(start 94.586552 -134.0231)
		(end 94.586552 -134.25805)
		(stroke
			(width 0.0635)
			(type default)
		)
		(layer "F.Cu")
	)
	(gr_line
		(start 94.586552 -134.0231)
		(end 94.651322 -133.95833)
		(stroke
			(width 0.0635)
			(type default)
		)
		(layer "F.Cu")
	)
	(gr_line
		(start 94.586552 -133.477)
		(end 94.651322 -133.54177)
		(stroke
			(width 0.0635)
			(type default)
		)
		(layer "F.Cu")
	)
	(gr_line
		(start 94.586552 -133.24205)
		(end 94.586552 -133.477)
		(stroke
			(width 0.0635)
			(type default)
		)
		(layer "F.Cu")
	)
	(gr_line
		(start 94.586552 -130.2131)
		(end 94.586552 -130.44805)
		(stroke
			(width 0.0635)
			(type default)
		)
		(layer "F.Cu")
	)
	(gr_line
		(start 94.586552 -130.2131)
		(end 94.651322 -130.14833)
		(stroke
			(width 0.0635)
			(type default)
		)
		(layer "F.Cu")
	)
	(gr_line
		(start 94.586552 -129.667)
		(end 94.651322 -129.73177)
		(stroke
			(width 0.0635)
			(type default)
		)
		(layer "F.Cu")
	)
	(gr_line
		(start 94.586552 -129.43205)
		(end 94.586552 -129.667)
		(stroke
			(width 0.0635)
			(type default)
		)
		(layer "F.Cu")
	)
	(gr_line
		(start 94.586552 -19.023076)
		(end 94.586552 -19.281648)
		(stroke
			(width 0.0635)
			(type default)
		)
		(layer "F.Cu")
	)
	(gr_line
		(start 94.586552 -19.023076)
		(end 94.651322 -18.958306)
		(stroke
			(width 0.0635)
			(type default)
		)
		(layer "F.Cu")
	)
	(gr_line
		(start 94.586552 -18.476976)
		(end 94.651322 -18.541746)
		(stroke
			(width 0.0635)
			(type default)
		)
		(layer "F.Cu")
	)
	(gr_line
		(start 94.586552 -18.259552)
		(end 94.586552 -18.476976)
		(stroke
			(width 0.0635)
			(type default)
		)
		(layer "F.Cu")
	)
	(gr_line
		(start 94.586552 -15.213076)
		(end 94.586552 -15.448026)
		(stroke
			(width 0.0635)
			(type default)
		)
		(layer "F.Cu")
	)
	(gr_line
		(start 94.586552 -15.213076)
		(end 94.651322 -15.148306)
		(stroke
			(width 0.0635)
			(type default)
		)
		(layer "F.Cu")
	)
	(gr_line
		(start 94.586552 -14.666976)
		(end 94.651322 -14.731746)
		(stroke
			(width 0.0635)
			(type default)
		)
		(layer "F.Cu")
	)
	(gr_line
		(start 94.586552 -14.432026)
		(end 94.586552 -14.666976)
		(stroke
			(width 0.0635)
			(type default)
		)
		(layer "F.Cu")
	)
	(gr_line
		(start 94.828868 -245.095522)
		(end 94.95282 -245.219474)
		(stroke
			(width 0.0635)
			(type default)
		)
		(layer "F.Cu")
	)
	(gr_line
		(start 94.828868 -244.784626)
		(end 94.95282 -244.660674)
		(stroke
			(width 0.0635)
			(type default)
		)
		(layer "F.Cu")
	)
	(gr_line
		(start 94.828868 -130.095498)
		(end 94.95282 -130.21945)
		(stroke
			(width 0.0635)
			(type default)
		)
		(layer "F.Cu")
	)
	(gr_line
		(start 94.828868 -129.784602)
		(end 94.95282 -129.66065)
		(stroke
			(width 0.0635)
			(type default)
		)
		(layer "F.Cu")
	)
	(gr_line
		(start 94.828868 -15.095474)
		(end 94.95282 -15.219426)
		(stroke
			(width 0.0635)
			(type default)
		)
		(layer "F.Cu")
	)
	(gr_line
		(start 94.828868 -14.784578)
		(end 94.95282 -14.660626)
		(stroke
			(width 0.0635)
			(type default)
		)
		(layer "F.Cu")
	)
	(gr_line
		(start 94.95282 -245.219474)
		(end 95.284036 -245.219474)
		(stroke
			(width 0.0635)
			(type default)
		)
		(layer "F.Cu")
	)
	(gr_line
		(start 94.95282 -244.660674)
		(end 95.284036 -244.660674)
		(stroke
			(width 0.0635)
			(type default)
		)
		(layer "F.Cu")
	)
	(gr_line
		(start 94.95282 -130.21945)
		(end 95.284036 -130.21945)
		(stroke
			(width 0.0635)
			(type default)
		)
		(layer "F.Cu")
	)
	(gr_line
		(start 94.95282 -129.66065)
		(end 95.284036 -129.66065)
		(stroke
			(width 0.0635)
			(type default)
		)
		(layer "F.Cu")
	)
	(gr_line
		(start 94.95282 -15.219426)
		(end 95.284036 -15.219426)
		(stroke
			(width 0.0635)
			(type default)
		)
		(layer "F.Cu")
	)
	(gr_line
		(start 94.95282 -14.660626)
		(end 95.284036 -14.660626)
		(stroke
			(width 0.0635)
			(type default)
		)
		(layer "F.Cu")
	)
	(gr_arc
		(start 95.481902 -248.604024)
		(mid 95.571705 -248.566827)
		(end 95.608902 -248.477024)
		(stroke
			(width 0.0635)
			(type default)
		)
		(layer "F.Cu")
	)
	(gr_arc
		(start 95.481902 -133.604)
		(mid 95.571705 -133.566803)
		(end 95.608902 -133.477)
		(stroke
			(width 0.0635)
			(type default)
		)
		(layer "F.Cu")
	)
	(gr_arc
		(start 95.481902 -18.603976)
		(mid 95.571705 -18.566779)
		(end 95.608902 -18.476976)
		(stroke
			(width 0.0635)
			(type default)
		)
		(layer "F.Cu")
	)
	(gr_arc
		(start 95.608902 -249.023124)
		(mid 95.571713 -248.933305)
		(end 95.481902 -248.896124)
		(stroke
			(width 0.0635)
			(type default)
		)
		(layer "F.Cu")
	)
	(gr_line
		(start 95.608902 -249.023124)
		(end 95.608902 -249.385074)
		(stroke
			(width 0.0635)
			(type default)
		)
		(layer "F.Cu")
	)
	(gr_line
		(start 95.608902 -248.115074)
		(end 95.608902 -248.477024)
		(stroke
			(width 0.0635)
			(type default)
		)
		(layer "F.Cu")
	)
	(gr_arc
		(start 95.608902 -134.0231)
		(mid 95.571705 -133.933297)
		(end 95.481902 -133.8961)
		(stroke
			(width 0.0635)
			(type default)
		)
		(layer "F.Cu")
	)
	(gr_line
		(start 95.608902 -134.0231)
		(end 95.608902 -134.38505)
		(stroke
			(width 0.0635)
			(type default)
		)
		(layer "F.Cu")
	)
	(gr_line
		(start 95.608902 -133.11505)
		(end 95.608902 -133.477)
		(stroke
			(width 0.0635)
			(type default)
		)
		(layer "F.Cu")
	)
	(gr_arc
		(start 95.608902 -19.023076)
		(mid 95.571696 -18.933288)
		(end 95.481902 -18.896076)
		(stroke
			(width 0.0635)
			(type default)
		)
		(layer "F.Cu")
	)
	(gr_line
		(start 95.608902 -19.023076)
		(end 95.608902 -19.385026)
		(stroke
			(width 0.0635)
			(type default)
		)
		(layer "F.Cu")
	)
	(gr_line
		(start 95.608902 -18.115026)
		(end 95.608902 -18.476976)
		(stroke
			(width 0.0635)
			(type default)
		)
		(layer "F.Cu")
	)
	(gr_line
		(start 95.842836 -245.219474)
		(end 96.223074 -245.219474)
		(stroke
			(width 0.0635)
			(type default)
		)
		(layer "F.Cu")
	)
	(gr_line
		(start 95.842836 -244.660674)
		(end 96.238822 -244.660674)
		(stroke
			(width 0.0635)
			(type default)
		)
		(layer "F.Cu")
	)
	(gr_line
		(start 95.842836 -130.21945)
		(end 96.223074 -130.21945)
		(stroke
			(width 0.0635)
			(type default)
		)
		(layer "F.Cu")
	)
	(gr_line
		(start 95.842836 -129.66065)
		(end 96.238822 -129.66065)
		(stroke
			(width 0.0635)
			(type default)
		)
		(layer "F.Cu")
	)
	(gr_line
		(start 95.842836 -15.219426)
		(end 96.223074 -15.219426)
		(stroke
			(width 0.0635)
			(type default)
		)
		(layer "F.Cu")
	)
	(gr_line
		(start 95.842836 -14.660626)
		(end 96.238822 -14.660626)
		(stroke
			(width 0.0635)
			(type default)
		)
		(layer "F.Cu")
	)
	(gr_line
		(start 96.223074 -245.219474)
		(end 96.302068 -245.14048)
		(stroke
			(width 0.0635)
			(type default)
		)
		(layer "F.Cu")
	)
	(gr_line
		(start 96.223074 -130.21945)
		(end 96.302068 -130.140456)
		(stroke
			(width 0.0635)
			(type default)
		)
		(layer "F.Cu")
	)
	(gr_line
		(start 96.223074 -15.219426)
		(end 96.302068 -15.140432)
		(stroke
			(width 0.0635)
			(type default)
		)
		(layer "F.Cu")
	)
	(gr_line
		(start 96.238822 -244.660674)
		(end 96.302068 -244.72392)
		(stroke
			(width 0.0635)
			(type default)
		)
		(layer "F.Cu")
	)
	(gr_line
		(start 96.238822 -129.66065)
		(end 96.302068 -129.723896)
		(stroke
			(width 0.0635)
			(type default)
		)
		(layer "F.Cu")
	)
	(gr_line
		(start 96.238822 -14.660626)
		(end 96.302068 -14.723872)
		(stroke
			(width 0.0635)
			(type default)
		)
		(layer "F.Cu")
	)
	(gr_arc
		(start 97.226628 -244.844824)
		(mid 97.339061 -244.798253)
		(end 97.385632 -244.68582)
		(stroke
			(width 0.0635)
			(type default)
		)
		(layer "F.Cu")
	)
	(gr_arc
		(start 97.226628 -129.8448)
		(mid 97.339061 -129.798229)
		(end 97.385632 -129.685796)
		(stroke
			(width 0.0635)
			(type default)
		)
		(layer "F.Cu")
	)
	(gr_arc
		(start 97.226628 -14.844776)
		(mid 97.339061 -14.798205)
		(end 97.385632 -14.685772)
		(stroke
			(width 0.0635)
			(type default)
		)
		(layer "F.Cu")
	)
	(gr_arc
		(start 97.385632 -245.295928)
		(mid 97.339072 -245.183467)
		(end 97.226628 -245.136924)
		(stroke
			(width 0.0635)
			(type default)
		)
		(layer "F.Cu")
	)
	(gr_line
		(start 97.385632 -245.295928)
		(end 97.385632 -245.562374)
		(stroke
			(width 0.0635)
			(type default)
		)
		(layer "F.Cu")
	)
	(gr_line
		(start 97.385632 -244.419374)
		(end 97.385632 -244.68582)
		(stroke
			(width 0.0635)
			(type default)
		)
		(layer "F.Cu")
	)
	(gr_arc
		(start 97.385632 -130.295904)
		(mid 97.339064 -130.183459)
		(end 97.226628 -130.1369)
		(stroke
			(width 0.0635)
			(type default)
		)
		(layer "F.Cu")
	)
	(gr_line
		(start 97.385632 -130.295904)
		(end 97.385632 -130.56235)
		(stroke
			(width 0.0635)
			(type default)
		)
		(layer "F.Cu")
	)
	(gr_line
		(start 97.385632 -129.41935)
		(end 97.385632 -129.685796)
		(stroke
			(width 0.0635)
			(type default)
		)
		(layer "F.Cu")
	)
	(gr_arc
		(start 97.385632 -15.29588)
		(mid 97.339055 -15.18345)
		(end 97.226628 -15.136876)
		(stroke
			(width 0.0635)
			(type default)
		)
		(layer "F.Cu")
	)
	(gr_line
		(start 97.385632 -15.29588)
		(end 97.385632 -15.562326)
		(stroke
			(width 0.0635)
			(type default)
		)
		(layer "F.Cu")
	)
	(gr_line
		(start 97.385632 -14.419326)
		(end 97.385632 -14.685772)
		(stroke
			(width 0.0635)
			(type default)
		)
		(layer "F.Cu")
	)
	(gr_line
		(start 124.674884 -249.385074)
		(end 126.0094 -249.385074)
		(stroke
			(width 0.0635)
			(type default)
		)
		(layer "F.Cu")
	)
	(gr_line
		(start 124.674884 -248.115074)
		(end 126.0094 -248.115074)
		(stroke
			(width 0.0635)
			(type default)
		)
		(layer "F.Cu")
	)
	(gr_line
		(start 124.674884 -245.575074)
		(end 126.0094 -245.575074)
		(stroke
			(width 0.0635)
			(type default)
		)
		(layer "F.Cu")
	)
	(gr_line
		(start 124.674884 -244.305074)
		(end 126.0094 -244.305074)
		(stroke
			(width 0.0635)
			(type default)
		)
		(layer "F.Cu")
	)
	(gr_line
		(start 124.674884 -134.38505)
		(end 126.0094 -134.38505)
		(stroke
			(width 0.0635)
			(type default)
		)
		(layer "F.Cu")
	)
	(gr_line
		(start 124.674884 -133.11505)
		(end 126.0094 -133.11505)
		(stroke
			(width 0.0635)
			(type default)
		)
		(layer "F.Cu")
	)
	(gr_line
		(start 124.674884 -130.57505)
		(end 126.0094 -130.57505)
		(stroke
			(width 0.0635)
			(type default)
		)
		(layer "F.Cu")
	)
	(gr_line
		(start 124.674884 -129.30505)
		(end 126.0094 -129.30505)
		(stroke
			(width 0.0635)
			(type default)
		)
		(layer "F.Cu")
	)
	(gr_line
		(start 124.674884 -19.385026)
		(end 126.0094 -19.385026)
		(stroke
			(width 0.0635)
			(type default)
		)
		(layer "F.Cu")
	)
	(gr_line
		(start 124.674884 -18.115026)
		(end 126.0094 -18.115026)
		(stroke
			(width 0.0635)
			(type default)
		)
		(layer "F.Cu")
	)
	(gr_line
		(start 124.674884 -15.575026)
		(end 126.0094 -15.575026)
		(stroke
			(width 0.0635)
			(type default)
		)
		(layer "F.Cu")
	)
	(gr_line
		(start 124.674884 -14.305026)
		(end 126.0094 -14.305026)
		(stroke
			(width 0.0635)
			(type default)
		)
		(layer "F.Cu")
	)
	(gr_line
		(start 126.0094 -249.385074)
		(end 126.1364 -249.258074)
		(stroke
			(width 0.0635)
			(type default)
		)
		(layer "F.Cu")
	)
	(gr_line
		(start 126.0094 -248.115074)
		(end 126.1364 -248.242074)
		(stroke
			(width 0.0635)
			(type default)
		)
		(layer "F.Cu")
	)
	(gr_line
		(start 126.0094 -245.575074)
		(end 126.1364 -245.448074)
		(stroke
			(width 0.0635)
			(type default)
		)
		(layer "F.Cu")
	)
	(gr_line
		(start 126.0094 -244.305074)
		(end 126.1364 -244.432074)
		(stroke
			(width 0.0635)
			(type default)
		)
		(layer "F.Cu")
	)
	(gr_line
		(start 126.0094 -134.38505)
		(end 126.1364 -134.25805)
		(stroke
			(width 0.0635)
			(type default)
		)
		(layer "F.Cu")
	)
	(gr_line
		(start 126.0094 -133.11505)
		(end 126.1364 -133.24205)
		(stroke
			(width 0.0635)
			(type default)
		)
		(layer "F.Cu")
	)
	(gr_line
		(start 126.0094 -130.57505)
		(end 126.1364 -130.44805)
		(stroke
			(width 0.0635)
			(type default)
		)
		(layer "F.Cu")
	)
	(gr_line
		(start 126.0094 -129.30505)
		(end 126.1364 -129.43205)
		(stroke
			(width 0.0635)
			(type default)
		)
		(layer "F.Cu")
	)
	(gr_line
		(start 126.0094 -19.385026)
		(end 126.1364 -19.258026)
		(stroke
			(width 0.0635)
			(type default)
		)
		(layer "F.Cu")
	)
	(gr_line
		(start 126.0094 -18.115026)
		(end 126.1364 -18.242026)
		(stroke
			(width 0.0635)
			(type default)
		)
		(layer "F.Cu")
	)
	(gr_line
		(start 126.0094 -15.575026)
		(end 126.1364 -15.448026)
		(stroke
			(width 0.0635)
			(type default)
		)
		(layer "F.Cu")
	)
	(gr_line
		(start 126.0094 -14.305026)
		(end 126.1364 -14.432026)
		(stroke
			(width 0.0635)
			(type default)
		)
		(layer "F.Cu")
	)
	(gr_line
		(start 126.1364 -249.023124)
		(end 126.1364 -249.258074)
		(stroke
			(width 0.0635)
			(type default)
		)
		(layer "F.Cu")
	)
	(gr_line
		(start 126.1364 -249.023124)
		(end 126.20117 -248.958354)
		(stroke
			(width 0.0635)
			(type default)
		)
		(layer "F.Cu")
	)
	(gr_line
		(start 126.1364 -248.477024)
		(end 126.20117 -248.541794)
		(stroke
			(width 0.0635)
			(type default)
		)
		(layer "F.Cu")
	)
	(gr_line
		(start 126.1364 -248.242074)
		(end 126.1364 -248.477024)
		(stroke
			(width 0.0635)
			(type default)
		)
		(layer "F.Cu")
	)
	(gr_line
		(start 126.1364 -245.213124)
		(end 126.1364 -245.448074)
		(stroke
			(width 0.0635)
			(type default)
		)
		(layer "F.Cu")
	)
	(gr_line
		(start 126.1364 -245.213124)
		(end 126.20117 -245.148354)
		(stroke
			(width 0.0635)
			(type default)
		)
		(layer "F.Cu")
	)
	(gr_line
		(start 126.1364 -244.667024)
		(end 126.20117 -244.731794)
		(stroke
			(width 0.0635)
			(type default)
		)
		(layer "F.Cu")
	)
	(gr_line
		(start 126.1364 -244.432074)
		(end 126.1364 -244.667024)
		(stroke
			(width 0.0635)
			(type default)
		)
		(layer "F.Cu")
	)
	(gr_line
		(start 126.1364 -134.0231)
		(end 126.1364 -134.25805)
		(stroke
			(width 0.0635)
			(type default)
		)
		(layer "F.Cu")
	)
	(gr_line
		(start 126.1364 -134.0231)
		(end 126.20117 -133.95833)
		(stroke
			(width 0.0635)
			(type default)
		)
		(layer "F.Cu")
	)
	(gr_line
		(start 126.1364 -133.477)
		(end 126.20117 -133.54177)
		(stroke
			(width 0.0635)
			(type default)
		)
		(layer "F.Cu")
	)
	(gr_line
		(start 126.1364 -133.24205)
		(end 126.1364 -133.477)
		(stroke
			(width 0.0635)
			(type default)
		)
		(layer "F.Cu")
	)
	(gr_line
		(start 126.1364 -130.2131)
		(end 126.1364 -130.44805)
		(stroke
			(width 0.0635)
			(type default)
		)
		(layer "F.Cu")
	)
	(gr_line
		(start 126.1364 -130.2131)
		(end 126.20117 -130.14833)
		(stroke
			(width 0.0635)
			(type default)
		)
		(layer "F.Cu")
	)
	(gr_line
		(start 126.1364 -129.667)
		(end 126.20117 -129.73177)
		(stroke
			(width 0.0635)
			(type default)
		)
		(layer "F.Cu")
	)
	(gr_line
		(start 126.1364 -129.43205)
		(end 126.1364 -129.667)
		(stroke
			(width 0.0635)
			(type default)
		)
		(layer "F.Cu")
	)
	(gr_line
		(start 126.1364 -19.023076)
		(end 126.1364 -19.258026)
		(stroke
			(width 0.0635)
			(type default)
		)
		(layer "F.Cu")
	)
	(gr_line
		(start 126.1364 -19.023076)
		(end 126.20117 -18.958306)
		(stroke
			(width 0.0635)
			(type default)
		)
		(layer "F.Cu")
	)
	(gr_line
		(start 126.1364 -18.476976)
		(end 126.20117 -18.541746)
		(stroke
			(width 0.0635)
			(type default)
		)
		(layer "F.Cu")
	)
	(gr_line
		(start 126.1364 -18.242026)
		(end 126.1364 -18.476976)
		(stroke
			(width 0.0635)
			(type default)
		)
		(layer "F.Cu")
	)
	(gr_line
		(start 126.1364 -15.213076)
		(end 126.1364 -15.448026)
		(stroke
			(width 0.0635)
			(type default)
		)
		(layer "F.Cu")
	)
	(gr_line
		(start 126.1364 -15.213076)
		(end 126.20117 -15.148306)
		(stroke
			(width 0.0635)
			(type default)
		)
		(layer "F.Cu")
	)
	(gr_line
		(start 126.1364 -14.666976)
		(end 126.20117 -14.731746)
		(stroke
			(width 0.0635)
			(type default)
		)
		(layer "F.Cu")
	)
	(gr_line
		(start 126.1364 -14.432026)
		(end 126.1364 -14.666976)
		(stroke
			(width 0.0635)
			(type default)
		)
		(layer "F.Cu")
	)
	(gr_line
		(start 126.378716 -245.095522)
		(end 126.502668 -245.219474)
		(stroke
			(width 0.0635)
			(type default)
		)
		(layer "F.Cu")
	)
	(gr_line
		(start 126.378716 -244.784626)
		(end 126.502668 -244.660674)
		(stroke
			(width 0.0635)
			(type default)
		)
		(layer "F.Cu")
	)
	(gr_line
		(start 126.378716 -130.095498)
		(end 126.502668 -130.21945)
		(stroke
			(width 0.0635)
			(type default)
		)
		(layer "F.Cu")
	)
	(gr_line
		(start 126.378716 -129.784602)
		(end 126.502668 -129.66065)
		(stroke
			(width 0.0635)
			(type default)
		)
		(layer "F.Cu")
	)
	(gr_line
		(start 126.378716 -15.095474)
		(end 126.502668 -15.219426)
		(stroke
			(width 0.0635)
			(type default)
		)
		(layer "F.Cu")
	)
	(gr_line
		(start 126.378716 -14.784578)
		(end 126.502668 -14.660626)
		(stroke
			(width 0.0635)
			(type default)
		)
		(layer "F.Cu")
	)
	(gr_line
		(start 126.502668 -245.219474)
		(end 126.833884 -245.219474)
		(stroke
			(width 0.0635)
			(type default)
		)
		(layer "F.Cu")
	)
	(gr_line
		(start 126.502668 -244.660674)
		(end 126.833884 -244.660674)
		(stroke
			(width 0.0635)
			(type default)
		)
		(layer "F.Cu")
	)
	(gr_line
		(start 126.502668 -130.21945)
		(end 126.833884 -130.21945)
		(stroke
			(width 0.0635)
			(type default)
		)
		(layer "F.Cu")
	)
	(gr_line
		(start 126.502668 -129.66065)
		(end 126.833884 -129.66065)
		(stroke
			(width 0.0635)
			(type default)
		)
		(layer "F.Cu")
	)
	(gr_line
		(start 126.502668 -15.219426)
		(end 126.833884 -15.219426)
		(stroke
			(width 0.0635)
			(type default)
		)
		(layer "F.Cu")
	)
	(gr_line
		(start 126.502668 -14.660626)
		(end 126.833884 -14.660626)
		(stroke
			(width 0.0635)
			(type default)
		)
		(layer "F.Cu")
	)
	(gr_arc
		(start 127.03175 -248.604024)
		(mid 127.121553 -248.566827)
		(end 127.15875 -248.477024)
		(stroke
			(width 0.0635)
			(type default)
		)
		(layer "F.Cu")
	)
	(gr_arc
		(start 127.03175 -133.604)
		(mid 127.121553 -133.566803)
		(end 127.15875 -133.477)
		(stroke
			(width 0.0635)
			(type default)
		)
		(layer "F.Cu")
	)
	(gr_arc
		(start 127.03175 -18.603976)
		(mid 127.121553 -18.566779)
		(end 127.15875 -18.476976)
		(stroke
			(width 0.0635)
			(type default)
		)
		(layer "F.Cu")
	)
	(gr_arc
		(start 127.15875 -249.023124)
		(mid 127.121558 -248.933324)
		(end 127.03175 -248.896124)
		(stroke
			(width 0.0635)
			(type default)
		)
		(layer "F.Cu")
	)
	(gr_line
		(start 127.15875 -249.023124)
		(end 127.15875 -249.385074)
		(stroke
			(width 0.0635)
			(type default)
		)
		(layer "F.Cu")
	)
	(gr_line
		(start 127.15875 -248.115074)
		(end 127.15875 -248.477024)
		(stroke
			(width 0.0635)
			(type default)
		)
		(layer "F.Cu")
	)
	(gr_arc
		(start 127.15875 -134.0231)
		(mid 127.12155 -133.933315)
		(end 127.03175 -133.8961)
		(stroke
			(width 0.0635)
			(type default)
		)
		(layer "F.Cu")
	)
	(gr_line
		(start 127.15875 -134.0231)
		(end 127.15875 -134.38505)
		(stroke
			(width 0.0635)
			(type default)
		)
		(layer "F.Cu")
	)
	(gr_line
		(start 127.15875 -133.11505)
		(end 127.15875 -133.477)
		(stroke
			(width 0.0635)
			(type default)
		)
		(layer "F.Cu")
	)
	(gr_arc
		(start 127.15875 -19.023076)
		(mid 127.121541 -18.933307)
		(end 127.03175 -18.896076)
		(stroke
			(width 0.0635)
			(type default)
		)
		(layer "F.Cu")
	)
	(gr_line
		(start 127.15875 -19.023076)
		(end 127.15875 -19.385026)
		(stroke
			(width 0.0635)
			(type default)
		)
		(layer "F.Cu")
	)
	(gr_line
		(start 127.15875 -18.115026)
		(end 127.15875 -18.476976)
		(stroke
			(width 0.0635)
			(type default)
		)
		(layer "F.Cu")
	)
	(gr_line
		(start 127.392684 -245.219474)
		(end 127.772922 -245.219474)
		(stroke
			(width 0.0635)
			(type default)
		)
		(layer "F.Cu")
	)
	(gr_line
		(start 127.392684 -244.660674)
		(end 127.78867 -244.660674)
		(stroke
			(width 0.0635)
			(type default)
		)
		(layer "F.Cu")
	)
	(gr_line
		(start 127.392684 -130.21945)
		(end 127.772922 -130.21945)
		(stroke
			(width 0.0635)
			(type default)
		)
		(layer "F.Cu")
	)
	(gr_line
		(start 127.392684 -129.66065)
		(end 127.78867 -129.66065)
		(stroke
			(width 0.0635)
			(type default)
		)
		(layer "F.Cu")
	)
	(gr_line
		(start 127.392684 -15.219426)
		(end 127.772922 -15.219426)
		(stroke
			(width 0.0635)
			(type default)
		)
		(layer "F.Cu")
	)
	(gr_line
		(start 127.392684 -14.660626)
		(end 127.78867 -14.660626)
		(stroke
			(width 0.0635)
			(type default)
		)
		(layer "F.Cu")
	)
	(gr_line
		(start 127.772922 -245.219474)
		(end 127.851916 -245.14048)
		(stroke
			(width 0.0635)
			(type default)
		)
		(layer "F.Cu")
	)
	(gr_line
		(start 127.772922 -130.21945)
		(end 127.851916 -130.140456)
		(stroke
			(width 0.0635)
			(type default)
		)
		(layer "F.Cu")
	)
	(gr_line
		(start 127.772922 -15.219426)
		(end 127.851916 -15.140432)
		(stroke
			(width 0.0635)
			(type default)
		)
		(layer "F.Cu")
	)
	(gr_line
		(start 127.78867 -244.660674)
		(end 127.851916 -244.72392)
		(stroke
			(width 0.0635)
			(type default)
		)
		(layer "F.Cu")
	)
	(gr_line
		(start 127.78867 -129.66065)
		(end 127.851916 -129.723896)
		(stroke
			(width 0.0635)
			(type default)
		)
		(layer "F.Cu")
	)
	(gr_line
		(start 127.78867 -14.660626)
		(end 127.851916 -14.723872)
		(stroke
			(width 0.0635)
			(type default)
		)
		(layer "F.Cu")
	)
	(gr_arc
		(start 128.776476 -244.844824)
		(mid 128.888909 -244.798253)
		(end 128.93548 -244.68582)
		(stroke
			(width 0.0635)
			(type default)
		)
		(layer "F.Cu")
	)
	(gr_arc
		(start 128.776476 -129.8448)
		(mid 128.888909 -129.798229)
		(end 128.93548 -129.685796)
		(stroke
			(width 0.0635)
			(type default)
		)
		(layer "F.Cu")
	)
	(gr_arc
		(start 128.776476 -14.844776)
		(mid 128.888909 -14.798205)
		(end 128.93548 -14.685772)
		(stroke
			(width 0.0635)
			(type default)
		)
		(layer "F.Cu")
	)
	(gr_arc
		(start 128.93548 -245.295928)
		(mid 128.888917 -245.183486)
		(end 128.776476 -245.136924)
		(stroke
			(width 0.0635)
			(type default)
		)
		(layer "F.Cu")
	)
	(gr_line
		(start 128.93548 -245.295928)
		(end 128.93548 -245.562374)
		(stroke
			(width 0.0635)
			(type default)
		)
		(layer "F.Cu")
	)
	(gr_line
		(start 128.93548 -244.419374)
		(end 128.93548 -244.68582)
		(stroke
			(width 0.0635)
			(type default)
		)
		(layer "F.Cu")
	)
	(gr_arc
		(start 128.93548 -130.295904)
		(mid 128.888909 -130.183477)
		(end 128.776476 -130.1369)
		(stroke
			(width 0.0635)
			(type default)
		)
		(layer "F.Cu")
	)
	(gr_line
		(start 128.93548 -130.295904)
		(end 128.93548 -130.56235)
		(stroke
			(width 0.0635)
			(type default)
		)
		(layer "F.Cu")
	)
	(gr_line
		(start 128.93548 -129.41935)
		(end 128.93548 -129.685796)
		(stroke
			(width 0.0635)
			(type default)
		)
		(layer "F.Cu")
	)
	(gr_arc
		(start 128.93548 -15.29588)
		(mid 128.8889 -15.183469)
		(end 128.776476 -15.136876)
		(stroke
			(width 0.0635)
			(type default)
		)
		(layer "F.Cu")
	)
	(gr_line
		(start 128.93548 -15.29588)
		(end 128.93548 -15.562326)
		(stroke
			(width 0.0635)
			(type default)
		)
		(layer "F.Cu")
	)
	(gr_line
		(start 128.93548 -14.419326)
		(end 128.93548 -14.685772)
		(stroke
			(width 0.0635)
			(type default)
		)
		(layer "F.Cu")
	)
	(gr_line
		(start 156.224986 -249.385074)
		(end 157.559502 -249.385074)
		(stroke
			(width 0.0635)
			(type default)
		)
		(layer "F.Cu")
	)
	(gr_line
		(start 156.224986 -248.115074)
		(end 157.559502 -248.115074)
		(stroke
			(width 0.0635)
			(type default)
		)
		(layer "F.Cu")
	)
	(gr_line
		(start 156.224986 -245.575074)
		(end 157.559502 -245.575074)
		(stroke
			(width 0.0635)
			(type default)
		)
		(layer "F.Cu")
	)
	(gr_line
		(start 156.224986 -244.305074)
		(end 157.559502 -244.305074)
		(stroke
			(width 0.0635)
			(type default)
		)
		(layer "F.Cu")
	)
	(gr_line
		(start 156.224986 -134.38505)
		(end 157.56255 -134.38505)
		(stroke
			(width 0.0635)
			(type default)
		)
		(layer "F.Cu")
	)
	(gr_line
		(start 156.224986 -133.11505)
		(end 157.559502 -133.11505)
		(stroke
			(width 0.0635)
			(type default)
		)
		(layer "F.Cu")
	)
	(gr_line
		(start 156.224986 -130.57505)
		(end 157.559502 -130.57505)
		(stroke
			(width 0.0635)
			(type default)
		)
		(layer "F.Cu")
	)
	(gr_line
		(start 156.224986 -129.30505)
		(end 157.559502 -129.30505)
		(stroke
			(width 0.0635)
			(type default)
		)
		(layer "F.Cu")
	)
	(gr_line
		(start 156.224986 -19.385026)
		(end 157.559502 -19.385026)
		(stroke
			(width 0.0635)
			(type default)
		)
		(layer "F.Cu")
	)
	(gr_line
		(start 156.224986 -18.115026)
		(end 157.559502 -18.115026)
		(stroke
			(width 0.0635)
			(type default)
		)
		(layer "F.Cu")
	)
	(gr_line
		(start 156.224986 -15.575026)
		(end 157.559502 -15.575026)
		(stroke
			(width 0.0635)
			(type default)
		)
		(layer "F.Cu")
	)
	(gr_line
		(start 156.224986 -14.305026)
		(end 157.559502 -14.305026)
		(stroke
			(width 0.0635)
			(type default)
		)
		(layer "F.Cu")
	)
	(gr_line
		(start 157.559502 -249.385074)
		(end 157.6832 -249.261376)
		(stroke
			(width 0.0635)
			(type default)
		)
		(layer "F.Cu")
	)
	(gr_line
		(start 157.559502 -248.115074)
		(end 157.686502 -248.242074)
		(stroke
			(width 0.0635)
			(type default)
		)
		(layer "F.Cu")
	)
	(gr_line
		(start 157.559502 -245.575074)
		(end 157.686502 -245.448074)
		(stroke
			(width 0.0635)
			(type default)
		)
		(layer "F.Cu")
	)
	(gr_line
		(start 157.559502 -244.305074)
		(end 157.686502 -244.432074)
		(stroke
			(width 0.0635)
			(type default)
		)
		(layer "F.Cu")
	)
	(gr_line
		(start 157.559502 -133.11505)
		(end 157.686502 -133.24205)
		(stroke
			(width 0.0635)
			(type default)
		)
		(layer "F.Cu")
	)
	(gr_line
		(start 157.559502 -130.57505)
		(end 157.686502 -130.44805)
		(stroke
			(width 0.0635)
			(type default)
		)
		(layer "F.Cu")
	)
	(gr_line
		(start 157.559502 -129.30505)
		(end 157.686502 -129.43205)
		(stroke
			(width 0.0635)
			(type default)
		)
		(layer "F.Cu")
	)
	(gr_line
		(start 157.559502 -19.385026)
		(end 157.686502 -19.258026)
		(stroke
			(width 0.0635)
			(type default)
		)
		(layer "F.Cu")
	)
	(gr_line
		(start 157.559502 -18.115026)
		(end 157.686502 -18.242026)
		(stroke
			(width 0.0635)
			(type default)
		)
		(layer "F.Cu")
	)
	(gr_line
		(start 157.559502 -15.575026)
		(end 157.686502 -15.448026)
		(stroke
			(width 0.0635)
			(type default)
		)
		(layer "F.Cu")
	)
	(gr_line
		(start 157.559502 -14.305026)
		(end 157.686502 -14.432026)
		(stroke
			(width 0.0635)
			(type default)
		)
		(layer "F.Cu")
	)
	(gr_line
		(start 157.56255 -134.38505)
		(end 157.6832 -134.2644)
		(stroke
			(width 0.0635)
			(type default)
		)
		(layer "F.Cu")
	)
	(gr_line
		(start 157.6832 -249.026426)
		(end 157.6832 -249.261376)
		(stroke
			(width 0.0635)
			(type default)
		)
		(layer "F.Cu")
	)
	(gr_line
		(start 157.6832 -249.026426)
		(end 157.751272 -248.958354)
		(stroke
			(width 0.0635)
			(type default)
		)
		(layer "F.Cu")
	)
	(gr_line
		(start 157.6832 -134.0104)
		(end 157.6832 -134.2644)
		(stroke
			(width 0.0635)
			(type default)
		)
		(layer "F.Cu")
	)
	(gr_line
		(start 157.6832 -134.0104)
		(end 157.743144 -133.950456)
		(stroke
			(width 0.0635)
			(type default)
		)
		(layer "F.Cu")
	)
	(gr_line
		(start 157.686502 -248.477024)
		(end 157.751272 -248.541794)
		(stroke
			(width 0.0635)
			(type default)
		)
		(layer "F.Cu")
	)
	(gr_line
		(start 157.686502 -248.242074)
		(end 157.686502 -248.477024)
		(stroke
			(width 0.0635)
			(type default)
		)
		(layer "F.Cu")
	)
	(gr_line
		(start 157.686502 -245.213124)
		(end 157.686502 -245.448074)
		(stroke
			(width 0.0635)
			(type default)
		)
		(layer "F.Cu")
	)
	(gr_line
		(start 157.686502 -245.213124)
		(end 157.751272 -245.148354)
		(stroke
			(width 0.0635)
			(type default)
		)
		(layer "F.Cu")
	)
	(gr_line
		(start 157.686502 -244.667024)
		(end 157.751272 -244.731794)
		(stroke
			(width 0.0635)
			(type default)
		)
		(layer "F.Cu")
	)
	(gr_line
		(start 157.686502 -244.432074)
		(end 157.686502 -244.667024)
		(stroke
			(width 0.0635)
			(type default)
		)
		(layer "F.Cu")
	)
	(gr_line
		(start 157.686502 -133.477)
		(end 157.743144 -133.533642)
		(stroke
			(width 0.0635)
			(type default)
		)
		(layer "F.Cu")
	)
	(gr_line
		(start 157.686502 -133.24205)
		(end 157.686502 -133.477)
		(stroke
			(width 0.0635)
			(type default)
		)
		(layer "F.Cu")
	)
	(gr_line
		(start 157.686502 -130.2131)
		(end 157.686502 -130.44805)
		(stroke
			(width 0.0635)
			(type default)
		)
		(layer "F.Cu")
	)
	(gr_line
		(start 157.686502 -130.2131)
		(end 157.751272 -130.14833)
		(stroke
			(width 0.0635)
			(type default)
		)
		(layer "F.Cu")
	)
	(gr_line
		(start 157.686502 -129.667)
		(end 157.751272 -129.73177)
		(stroke
			(width 0.0635)
			(type default)
		)
		(layer "F.Cu")
	)
	(gr_line
		(start 157.686502 -129.43205)
		(end 157.686502 -129.667)
		(stroke
			(width 0.0635)
			(type default)
		)
		(layer "F.Cu")
	)
	(gr_line
		(start 157.686502 -19.023076)
		(end 157.686502 -19.258026)
		(stroke
			(width 0.0635)
			(type default)
		)
		(layer "F.Cu")
	)
	(gr_line
		(start 157.686502 -19.023076)
		(end 157.751272 -18.958306)
		(stroke
			(width 0.0635)
			(type default)
		)
		(layer "F.Cu")
	)
	(gr_line
		(start 157.686502 -18.476976)
		(end 157.751272 -18.541746)
		(stroke
			(width 0.0635)
			(type default)
		)
		(layer "F.Cu")
	)
	(gr_line
		(start 157.686502 -18.242026)
		(end 157.686502 -18.476976)
		(stroke
			(width 0.0635)
			(type default)
		)
		(layer "F.Cu")
	)
	(gr_line
		(start 157.686502 -15.213076)
		(end 157.686502 -15.448026)
		(stroke
			(width 0.0635)
			(type default)
		)
		(layer "F.Cu")
	)
	(gr_line
		(start 157.686502 -15.213076)
		(end 157.751272 -15.148306)
		(stroke
			(width 0.0635)
			(type default)
		)
		(layer "F.Cu")
	)
	(gr_line
		(start 157.686502 -14.666976)
		(end 157.751272 -14.731746)
		(stroke
			(width 0.0635)
			(type default)
		)
		(layer "F.Cu")
	)
	(gr_line
		(start 157.686502 -14.432026)
		(end 157.686502 -14.666976)
		(stroke
			(width 0.0635)
			(type default)
		)
		(layer "F.Cu")
	)
	(gr_line
		(start 157.928818 -245.095522)
		(end 158.05277 -245.219474)
		(stroke
			(width 0.0635)
			(type default)
		)
		(layer "F.Cu")
	)
	(gr_line
		(start 157.928818 -244.784626)
		(end 158.05277 -244.660674)
		(stroke
			(width 0.0635)
			(type default)
		)
		(layer "F.Cu")
	)
	(gr_line
		(start 157.928818 -130.095498)
		(end 158.05277 -130.21945)
		(stroke
			(width 0.0635)
			(type default)
		)
		(layer "F.Cu")
	)
	(gr_line
		(start 157.928818 -129.784602)
		(end 158.05277 -129.66065)
		(stroke
			(width 0.0635)
			(type default)
		)
		(layer "F.Cu")
	)
	(gr_line
		(start 157.928818 -15.095474)
		(end 158.05277 -15.219426)
		(stroke
			(width 0.0635)
			(type default)
		)
		(layer "F.Cu")
	)
	(gr_line
		(start 157.928818 -14.784578)
		(end 158.05277 -14.660626)
		(stroke
			(width 0.0635)
			(type default)
		)
		(layer "F.Cu")
	)
	(gr_line
		(start 158.05277 -245.219474)
		(end 158.383986 -245.219474)
		(stroke
			(width 0.0635)
			(type default)
		)
		(layer "F.Cu")
	)
	(gr_line
		(start 158.05277 -244.660674)
		(end 158.383986 -244.660674)
		(stroke
			(width 0.0635)
			(type default)
		)
		(layer "F.Cu")
	)
	(gr_line
		(start 158.05277 -130.21945)
		(end 158.383986 -130.21945)
		(stroke
			(width 0.0635)
			(type default)
		)
		(layer "F.Cu")
	)
	(gr_line
		(start 158.05277 -129.66065)
		(end 158.383986 -129.66065)
		(stroke
			(width 0.0635)
			(type default)
		)
		(layer "F.Cu")
	)
	(gr_line
		(start 158.05277 -15.219426)
		(end 158.383986 -15.219426)
		(stroke
			(width 0.0635)
			(type default)
		)
		(layer "F.Cu")
	)
	(gr_line
		(start 158.05277 -14.660626)
		(end 158.383986 -14.660626)
		(stroke
			(width 0.0635)
			(type default)
		)
		(layer "F.Cu")
	)
	(gr_arc
		(start 158.581852 -248.604024)
		(mid 158.671655 -248.566827)
		(end 158.708852 -248.477024)
		(stroke
			(width 0.0635)
			(type default)
		)
		(layer "F.Cu")
	)
	(gr_arc
		(start 158.581852 -133.604)
		(mid 158.671655 -133.566803)
		(end 158.708852 -133.477)
		(stroke
			(width 0.0635)
			(type default)
		)
		(layer "F.Cu")
	)
	(gr_arc
		(start 158.581852 -18.603976)
		(mid 158.671655 -18.566779)
		(end 158.708852 -18.476976)
		(stroke
			(width 0.0635)
			(type default)
		)
		(layer "F.Cu")
	)
	(gr_arc
		(start 158.708852 -249.023124)
		(mid 158.67166 -248.933323)
		(end 158.581852 -248.896124)
		(stroke
			(width 0.0635)
			(type default)
		)
		(layer "F.Cu")
	)
	(gr_line
		(start 158.708852 -249.023124)
		(end 158.708852 -249.385074)
		(stroke
			(width 0.0635)
			(type default)
		)
		(layer "F.Cu")
	)
	(gr_line
		(start 158.708852 -248.115074)
		(end 158.708852 -248.477024)
		(stroke
			(width 0.0635)
			(type default)
		)
		(layer "F.Cu")
	)
	(gr_arc
		(start 158.708852 -134.0231)
		(mid 158.671652 -133.933314)
		(end 158.581852 -133.8961)
		(stroke
			(width 0.0635)
			(type default)
		)
		(layer "F.Cu")
	)
	(gr_line
		(start 158.708852 -134.0231)
		(end 158.708852 -134.38505)
		(stroke
			(width 0.0635)
			(type default)
		)
		(layer "F.Cu")
	)
	(gr_line
		(start 158.708852 -133.11505)
		(end 158.708852 -133.477)
		(stroke
			(width 0.0635)
			(type default)
		)
		(layer "F.Cu")
	)
	(gr_arc
		(start 158.708852 -19.023076)
		(mid 158.671643 -18.933306)
		(end 158.581852 -18.896076)
		(stroke
			(width 0.0635)
			(type default)
		)
		(layer "F.Cu")
	)
	(gr_line
		(start 158.708852 -19.023076)
		(end 158.708852 -19.385026)
		(stroke
			(width 0.0635)
			(type default)
		)
		(layer "F.Cu")
	)
	(gr_line
		(start 158.708852 -18.115026)
		(end 158.708852 -18.476976)
		(stroke
			(width 0.0635)
			(type default)
		)
		(layer "F.Cu")
	)
	(gr_line
		(start 158.942786 -245.219474)
		(end 159.323024 -245.219474)
		(stroke
			(width 0.0635)
			(type default)
		)
		(layer "F.Cu")
	)
	(gr_line
		(start 158.942786 -244.660674)
		(end 159.338772 -244.660674)
		(stroke
			(width 0.0635)
			(type default)
		)
		(layer "F.Cu")
	)
	(gr_line
		(start 158.942786 -130.21945)
		(end 159.323024 -130.21945)
		(stroke
			(width 0.0635)
			(type default)
		)
		(layer "F.Cu")
	)
	(gr_line
		(start 158.942786 -129.66065)
		(end 159.338772 -129.66065)
		(stroke
			(width 0.0635)
			(type default)
		)
		(layer "F.Cu")
	)
	(gr_line
		(start 158.942786 -15.219426)
		(end 159.323024 -15.219426)
		(stroke
			(width 0.0635)
			(type default)
		)
		(layer "F.Cu")
	)
	(gr_line
		(start 158.942786 -14.660626)
		(end 159.338772 -14.660626)
		(stroke
			(width 0.0635)
			(type default)
		)
		(layer "F.Cu")
	)
	(gr_line
		(start 159.323024 -245.219474)
		(end 159.402018 -245.14048)
		(stroke
			(width 0.0635)
			(type default)
		)
		(layer "F.Cu")
	)
	(gr_line
		(start 159.323024 -130.21945)
		(end 159.402018 -130.140456)
		(stroke
			(width 0.0635)
			(type default)
		)
		(layer "F.Cu")
	)
	(gr_line
		(start 159.323024 -15.219426)
		(end 159.402018 -15.140432)
		(stroke
			(width 0.0635)
			(type default)
		)
		(layer "F.Cu")
	)
	(gr_line
		(start 159.338772 -244.660674)
		(end 159.402018 -244.72392)
		(stroke
			(width 0.0635)
			(type default)
		)
		(layer "F.Cu")
	)
	(gr_line
		(start 159.338772 -129.66065)
		(end 159.402018 -129.723896)
		(stroke
			(width 0.0635)
			(type default)
		)
		(layer "F.Cu")
	)
	(gr_line
		(start 159.338772 -14.660626)
		(end 159.402018 -14.723872)
		(stroke
			(width 0.0635)
			(type default)
		)
		(layer "F.Cu")
	)
	(gr_line
		(start 159.384746 -359.454704)
		(end 162.9918 -359.454704)
		(stroke
			(width 0.127)
			(type default)
		)
		(layer "F.Cu")
	)
	(gr_line
		(start 159.384746 -327.793096)
		(end 162.9918 -327.793096)
		(stroke
			(width 0.127)
			(type default)
		)
		(layer "F.Cu")
	)
	(gr_arc
		(start 160.326578 -244.844824)
		(mid 160.439011 -244.798253)
		(end 160.485582 -244.68582)
		(stroke
			(width 0.0635)
			(type default)
		)
		(layer "F.Cu")
	)
	(gr_arc
		(start 160.326578 -129.8448)
		(mid 160.439011 -129.798229)
		(end 160.485582 -129.685796)
		(stroke
			(width 0.0635)
			(type default)
		)
		(layer "F.Cu")
	)
	(gr_arc
		(start 160.326578 -14.844776)
		(mid 160.439011 -14.798205)
		(end 160.485582 -14.685772)
		(stroke
			(width 0.0635)
			(type default)
		)
		(layer "F.Cu")
	)
	(gr_arc
		(start 160.485582 -245.295928)
		(mid 160.439019 -245.183485)
		(end 160.326578 -245.136924)
		(stroke
			(width 0.0635)
			(type default)
		)
		(layer "F.Cu")
	)
	(gr_line
		(start 160.485582 -245.295928)
		(end 160.485582 -245.562374)
		(stroke
			(width 0.0635)
			(type default)
		)
		(layer "F.Cu")
	)
	(gr_line
		(start 160.485582 -244.419374)
		(end 160.485582 -244.68582)
		(stroke
			(width 0.0635)
			(type default)
		)
		(layer "F.Cu")
	)
	(gr_arc
		(start 160.485582 -130.295904)
		(mid 160.439011 -130.183476)
		(end 160.326578 -130.1369)
		(stroke
			(width 0.0635)
			(type default)
		)
		(layer "F.Cu")
	)
	(gr_line
		(start 160.485582 -130.295904)
		(end 160.485582 -130.56235)
		(stroke
			(width 0.0635)
			(type default)
		)
		(layer "F.Cu")
	)
	(gr_line
		(start 160.485582 -129.41935)
		(end 160.485582 -129.685796)
		(stroke
			(width 0.0635)
			(type default)
		)
		(layer "F.Cu")
	)
	(gr_arc
		(start 160.485582 -15.29588)
		(mid 160.439002 -15.183468)
		(end 160.326578 -15.136876)
		(stroke
			(width 0.0635)
			(type default)
		)
		(layer "F.Cu")
	)
	(gr_line
		(start 160.485582 -15.29588)
		(end 160.485582 -15.562326)
		(stroke
			(width 0.0635)
			(type default)
		)
		(layer "F.Cu")
	)
	(gr_line
		(start 160.485582 -14.419326)
		(end 160.485582 -14.685772)
		(stroke
			(width 0.0635)
			(type default)
		)
		(layer "F.Cu")
	)
	(gr_line
		(start 162.839908 -335.7245)
		(end 163.113974 -335.450434)
		(stroke
			(width 0.127)
			(type default)
		)
		(layer "F.Cu")
	)
	(gr_line
		(start 162.8648 -360.826304)
		(end 163.138866 -360.552238)
		(stroke
			(width 0.127)
			(type default)
		)
		(layer "F.Cu")
	)
	(gr_line
		(start 162.9918 -359.454704)
		(end 163.138866 -359.60177)
		(stroke
			(width 0.127)
			(type default)
		)
		(layer "F.Cu")
	)
	(gr_line
		(start 162.9918 -327.793096)
		(end 163.138866 -327.940162)
		(stroke
			(width 0.127)
			(type default)
		)
		(layer "F.Cu")
	)
	(gr_line
		(start 163.835842 -335.450434)
		(end 164.109908 -335.7245)
		(stroke
			(width 0.127)
			(type default)
		)
		(layer "F.Cu")
	)
	(gr_line
		(start 163.860734 -360.552238)
		(end 164.1348 -360.826304)
		(stroke
			(width 0.127)
			(type default)
		)
		(layer "F.Cu")
	)
	(gr_line
		(start 163.860734 -359.60177)
		(end 164.0078 -359.454704)
		(stroke
			(width 0.127)
			(type default)
		)
		(layer "F.Cu")
	)
	(gr_line
		(start 163.860734 -327.940162)
		(end 164.0078 -327.793096)
		(stroke
			(width 0.127)
			(type default)
		)
		(layer "F.Cu")
	)
	(gr_line
		(start 164.0078 -359.454704)
		(end 167.614854 -359.454704)
		(stroke
			(width 0.127)
			(type default)
		)
		(layer "F.Cu")
	)
	(gr_line
		(start 164.0078 -327.793096)
		(end 167.614854 -327.793096)
		(stroke
			(width 0.127)
			(type default)
		)
		(layer "F.Cu")
	)
	(gr_line
		(start 164.966142 -370.057934)
		(end 165.1 -370.191792)
		(stroke
			(width 0.127)
			(type default)
		)
		(layer "F.Cu")
	)
	(gr_line
		(start 164.966142 -369.336066)
		(end 165.1 -369.202208)
		(stroke
			(width 0.127)
			(type default)
		)
		(layer "F.Cu")
	)
	(gr_line
		(start 167.124634 -372.724934)
		(end 167.2717 -372.872)
		(stroke
			(width 0.127)
			(type default)
		)
		(layer "F.Cu")
	)
	(gr_line
		(start 167.124634 -372.003066)
		(end 167.2717 -371.856)
		(stroke
			(width 0.127)
			(type default)
		)
		(layer "F.Cu")
	)
	(gr_line
		(start 168.1607 -372.872)
		(end 168.307766 -372.724934)
		(stroke
			(width 0.127)
			(type default)
		)
		(layer "F.Cu")
	)
	(gr_line
		(start 168.1607 -371.856)
		(end 168.307766 -372.003066)
		(stroke
			(width 0.127)
			(type default)
		)
		(layer "F.Cu")
	)
	(gr_line
		(start 168.813734 -372.724934)
		(end 169.0878 -372.999)
		(stroke
			(width 0.127)
			(type default)
		)
		(layer "F.Cu")
	)
	(gr_line
		(start 168.813734 -372.003066)
		(end 169.0878 -371.729)
		(stroke
			(width 0.127)
			(type default)
		)
		(layer "F.Cu")
	)
	(gr_line
		(start 169.0878 -370.332)
		(end 169.361866 -370.057934)
		(stroke
			(width 0.127)
			(type default)
		)
		(layer "F.Cu")
	)
	(gr_line
		(start 169.0878 -369.062)
		(end 169.361866 -369.336066)
		(stroke
			(width 0.127)
			(type default)
		)
		(layer "F.Cu")
	)
	(gr_line
		(start 169.809668 -369.443)
		(end 169.928794 -369.443)
		(stroke
			(width 0.127)
			(type default)
		)
		(layer "F.Cu")
	)
	(gr_line
		(start 170.035728 -370.057934)
		(end 170.119294 -370.1415)
		(stroke
			(width 0.127)
			(type default)
		)
		(layer "F.Cu")
	)
	(gr_line
		(start 170.035728 -369.336066)
		(end 170.119294 -369.2525)
		(stroke
			(width 0.127)
			(type default)
		)
		(layer "F.Cu")
	)
	(gr_line
		(start 170.119294 -370.1415)
		(end 170.20286 -370.057934)
		(stroke
			(width 0.127)
			(type default)
		)
		(layer "F.Cu")
	)
	(gr_line
		(start 170.119294 -369.2525)
		(end 170.20286 -369.336066)
		(stroke
			(width 0.127)
			(type default)
		)
		(layer "F.Cu")
	)
	(gr_line
		(start 170.317668 -369.943126)
		(end 170.436794 -369.943126)
		(stroke
			(width 0.127)
			(type default)
		)
		(layer "F.Cu")
	)
	(gr_line
		(start 171.312078 -369.943126)
		(end 171.816268 -369.943126)
		(stroke
			(width 0.127)
			(type default)
		)
		(layer "F.Cu")
	)
	(gr_line
		(start 171.312332 -369.435126)
		(end 171.816268 -369.435126)
		(stroke
			(width 0.127)
			(type default)
		)
		(layer "F.Cu")
	)
	(gr_line
		(start 171.5897 -370.515134)
		(end 171.6659 -370.438934)
		(stroke
			(width 0.127)
			(type default)
		)
		(layer "F.Cu")
	)
	(gr_line
		(start 171.5897 -368.862864)
		(end 171.6659 -368.939064)
		(stroke
			(width 0.127)
			(type default)
		)
		(layer "F.Cu")
	)
	(gr_line
		(start 171.6659 -370.438934)
		(end 172.7835 -370.438934)
		(stroke
			(width 0.127)
			(type default)
		)
		(layer "F.Cu")
	)
	(gr_line
		(start 171.6659 -368.939064)
		(end 172.7835 -368.939064)
		(stroke
			(width 0.127)
			(type default)
		)
		(layer "F.Cu")
	)
	(gr_line
		(start 171.816268 -369.943126)
		(end 171.820332 -369.939062)
		(stroke
			(width 0.127)
			(type default)
		)
		(layer "F.Cu")
	)
	(gr_line
		(start 171.816268 -369.435126)
		(end 171.820078 -369.438936)
		(stroke
			(width 0.127)
			(type default)
		)
		(layer "F.Cu")
	)
	(gr_line
		(start 171.820078 -369.438936)
		(end 172.7835 -369.438936)
		(stroke
			(width 0.127)
			(type default)
		)
		(layer "F.Cu")
	)
	(gr_line
		(start 171.820332 -369.939062)
		(end 172.7835 -369.939062)
		(stroke
			(width 0.127)
			(type default)
		)
		(layer "F.Cu")
	)
	(gr_line
		(start 187.775088 -249.385074)
		(end 189.109604 -249.385074)
		(stroke
			(width 0.0635)
			(type default)
		)
		(layer "F.Cu")
	)
	(gr_line
		(start 187.775088 -248.115074)
		(end 189.109604 -248.115074)
		(stroke
			(width 0.0635)
			(type default)
		)
		(layer "F.Cu")
	)
	(gr_line
		(start 187.775088 -245.575074)
		(end 189.109604 -245.575074)
		(stroke
			(width 0.0635)
			(type default)
		)
		(layer "F.Cu")
	)
	(gr_line
		(start 187.775088 -244.305074)
		(end 189.109604 -244.305074)
		(stroke
			(width 0.0635)
			(type default)
		)
		(layer "F.Cu")
	)
	(gr_line
		(start 187.775088 -134.38505)
		(end 189.109604 -134.38505)
		(stroke
			(width 0.0635)
			(type default)
		)
		(layer "F.Cu")
	)
	(gr_line
		(start 187.775088 -133.11505)
		(end 189.109604 -133.11505)
		(stroke
			(width 0.0635)
			(type default)
		)
		(layer "F.Cu")
	)
	(gr_line
		(start 187.775088 -130.57505)
		(end 189.109604 -130.57505)
		(stroke
			(width 0.0635)
			(type default)
		)
		(layer "F.Cu")
	)
	(gr_line
		(start 187.775088 -129.30505)
		(end 189.109604 -129.30505)
		(stroke
			(width 0.0635)
			(type default)
		)
		(layer "F.Cu")
	)
	(gr_line
		(start 187.775088 -19.385026)
		(end 189.109604 -19.385026)
		(stroke
			(width 0.0635)
			(type default)
		)
		(layer "F.Cu")
	)
	(gr_line
		(start 187.775088 -18.115026)
		(end 189.109604 -18.115026)
		(stroke
			(width 0.0635)
			(type default)
		)
		(layer "F.Cu")
	)
	(gr_line
		(start 187.775088 -15.575026)
		(end 189.109604 -15.575026)
		(stroke
			(width 0.0635)
			(type default)
		)
		(layer "F.Cu")
	)
	(gr_line
		(start 187.775088 -14.305026)
		(end 189.109604 -14.305026)
		(stroke
			(width 0.0635)
			(type default)
		)
		(layer "F.Cu")
	)
	(gr_line
		(start 189.109604 -249.385074)
		(end 189.236604 -249.258074)
		(stroke
			(width 0.0635)
			(type default)
		)
		(layer "F.Cu")
	)
	(gr_line
		(start 189.109604 -248.115074)
		(end 189.236604 -248.242074)
		(stroke
			(width 0.0635)
			(type default)
		)
		(layer "F.Cu")
	)
	(gr_line
		(start 189.109604 -245.575074)
		(end 189.236604 -245.448074)
		(stroke
			(width 0.0635)
			(type default)
		)
		(layer "F.Cu")
	)
	(gr_line
		(start 189.109604 -244.305074)
		(end 189.236604 -244.432074)
		(stroke
			(width 0.0635)
			(type default)
		)
		(layer "F.Cu")
	)
	(gr_line
		(start 189.109604 -134.38505)
		(end 189.236604 -134.25805)
		(stroke
			(width 0.0635)
			(type default)
		)
		(layer "F.Cu")
	)
	(gr_line
		(start 189.109604 -133.11505)
		(end 189.236604 -133.24205)
		(stroke
			(width 0.0635)
			(type default)
		)
		(layer "F.Cu")
	)
	(gr_line
		(start 189.109604 -130.57505)
		(end 189.236604 -130.44805)
		(stroke
			(width 0.0635)
			(type default)
		)
		(layer "F.Cu")
	)
	(gr_line
		(start 189.109604 -129.30505)
		(end 189.236604 -129.43205)
		(stroke
			(width 0.0635)
			(type default)
		)
		(layer "F.Cu")
	)
	(gr_line
		(start 189.109604 -19.385026)
		(end 189.236604 -19.258026)
		(stroke
			(width 0.0635)
			(type default)
		)
		(layer "F.Cu")
	)
	(gr_line
		(start 189.109604 -18.115026)
		(end 189.236604 -18.242026)
		(stroke
			(width 0.0635)
			(type default)
		)
		(layer "F.Cu")
	)
	(gr_line
		(start 189.109604 -15.575026)
		(end 189.236604 -15.448026)
		(stroke
			(width 0.0635)
			(type default)
		)
		(layer "F.Cu")
	)
	(gr_line
		(start 189.109604 -14.305026)
		(end 189.236604 -14.432026)
		(stroke
			(width 0.0635)
			(type default)
		)
		(layer "F.Cu")
	)
	(gr_line
		(start 189.236604 -248.989596)
		(end 189.236604 -249.258074)
		(stroke
			(width 0.0635)
			(type default)
		)
		(layer "F.Cu")
	)
	(gr_line
		(start 189.236604 -248.989596)
		(end 189.28461 -248.94159)
		(stroke
			(width 0.0635)
			(type default)
		)
		(layer "F.Cu")
	)
	(gr_line
		(start 189.236604 -248.477024)
		(end 189.28461 -248.52503)
		(stroke
			(width 0.0635)
			(type default)
		)
		(layer "F.Cu")
	)
	(gr_line
		(start 189.236604 -248.242074)
		(end 189.236604 -248.477024)
		(stroke
			(width 0.0635)
			(type default)
		)
		(layer "F.Cu")
	)
	(gr_line
		(start 189.236604 -245.213124)
		(end 189.236604 -245.448074)
		(stroke
			(width 0.0635)
			(type default)
		)
		(layer "F.Cu")
	)
	(gr_line
		(start 189.236604 -245.213124)
		(end 189.301374 -245.148354)
		(stroke
			(width 0.0635)
			(type default)
		)
		(layer "F.Cu")
	)
	(gr_line
		(start 189.236604 -244.667024)
		(end 189.301374 -244.731794)
		(stroke
			(width 0.0635)
			(type default)
		)
		(layer "F.Cu")
	)
	(gr_line
		(start 189.236604 -244.432074)
		(end 189.236604 -244.667024)
		(stroke
			(width 0.0635)
			(type default)
		)
		(layer "F.Cu")
	)
	(gr_line
		(start 189.236604 -134.0231)
		(end 189.236604 -134.25805)
		(stroke
			(width 0.0635)
			(type default)
		)
		(layer "F.Cu")
	)
	(gr_line
		(start 189.236604 -134.0231)
		(end 189.301374 -133.95833)
		(stroke
			(width 0.0635)
			(type default)
		)
		(layer "F.Cu")
	)
	(gr_line
		(start 189.236604 -133.477)
		(end 189.301374 -133.54177)
		(stroke
			(width 0.0635)
			(type default)
		)
		(layer "F.Cu")
	)
	(gr_line
		(start 189.236604 -133.24205)
		(end 189.236604 -133.477)
		(stroke
			(width 0.0635)
			(type default)
		)
		(layer "F.Cu")
	)
	(gr_line
		(start 189.236604 -130.2131)
		(end 189.236604 -130.44805)
		(stroke
			(width 0.0635)
			(type default)
		)
		(layer "F.Cu")
	)
	(gr_line
		(start 189.236604 -130.2131)
		(end 189.301374 -130.14833)
		(stroke
			(width 0.0635)
			(type default)
		)
		(layer "F.Cu")
	)
	(gr_line
		(start 189.236604 -129.667)
		(end 189.301374 -129.73177)
		(stroke
			(width 0.0635)
			(type default)
		)
		(layer "F.Cu")
	)
	(gr_line
		(start 189.236604 -129.43205)
		(end 189.236604 -129.667)
		(stroke
			(width 0.0635)
			(type default)
		)
		(layer "F.Cu")
	)
	(gr_line
		(start 189.236604 -18.992596)
		(end 189.236604 -19.258026)
		(stroke
			(width 0.0635)
			(type default)
		)
		(layer "F.Cu")
	)
	(gr_line
		(start 189.236604 -18.992596)
		(end 189.286134 -18.943066)
		(stroke
			(width 0.0635)
			(type default)
		)
		(layer "F.Cu")
	)
	(gr_line
		(start 189.236604 -18.476976)
		(end 189.286134 -18.526506)
		(stroke
			(width 0.0635)
			(type default)
		)
		(layer "F.Cu")
	)
	(gr_line
		(start 189.236604 -18.242026)
		(end 189.236604 -18.476976)
		(stroke
			(width 0.0635)
			(type default)
		)
		(layer "F.Cu")
	)
	(gr_line
		(start 189.236604 -15.213076)
		(end 189.236604 -15.448026)
		(stroke
			(width 0.0635)
			(type default)
		)
		(layer "F.Cu")
	)
	(gr_line
		(start 189.236604 -15.213076)
		(end 189.301374 -15.148306)
		(stroke
			(width 0.0635)
			(type default)
		)
		(layer "F.Cu")
	)
	(gr_line
		(start 189.236604 -14.666976)
		(end 189.301374 -14.731746)
		(stroke
			(width 0.0635)
			(type default)
		)
		(layer "F.Cu")
	)
	(gr_line
		(start 189.236604 -14.432026)
		(end 189.236604 -14.666976)
		(stroke
			(width 0.0635)
			(type default)
		)
		(layer "F.Cu")
	)
	(gr_line
		(start 189.47892 -245.095522)
		(end 189.602872 -245.219474)
		(stroke
			(width 0.0635)
			(type default)
		)
		(layer "F.Cu")
	)
	(gr_line
		(start 189.47892 -244.784626)
		(end 189.602872 -244.660674)
		(stroke
			(width 0.0635)
			(type default)
		)
		(layer "F.Cu")
	)
	(gr_line
		(start 189.47892 -130.095498)
		(end 189.602872 -130.21945)
		(stroke
			(width 0.0635)
			(type default)
		)
		(layer "F.Cu")
	)
	(gr_line
		(start 189.47892 -129.784602)
		(end 189.602872 -129.66065)
		(stroke
			(width 0.0635)
			(type default)
		)
		(layer "F.Cu")
	)
	(gr_line
		(start 189.47892 -15.095474)
		(end 189.602872 -15.219426)
		(stroke
			(width 0.0635)
			(type default)
		)
		(layer "F.Cu")
	)
	(gr_line
		(start 189.47892 -14.784578)
		(end 189.602872 -14.660626)
		(stroke
			(width 0.0635)
			(type default)
		)
		(layer "F.Cu")
	)
	(gr_line
		(start 189.602872 -245.219474)
		(end 189.934088 -245.219474)
		(stroke
			(width 0.0635)
			(type default)
		)
		(layer "F.Cu")
	)
	(gr_line
		(start 189.602872 -244.660674)
		(end 189.934088 -244.660674)
		(stroke
			(width 0.0635)
			(type default)
		)
		(layer "F.Cu")
	)
	(gr_line
		(start 189.602872 -130.21945)
		(end 189.934088 -130.21945)
		(stroke
			(width 0.0635)
			(type default)
		)
		(layer "F.Cu")
	)
	(gr_line
		(start 189.602872 -129.66065)
		(end 189.934088 -129.66065)
		(stroke
			(width 0.0635)
			(type default)
		)
		(layer "F.Cu")
	)
	(gr_line
		(start 189.602872 -15.219426)
		(end 189.934088 -15.219426)
		(stroke
			(width 0.0635)
			(type default)
		)
		(layer "F.Cu")
	)
	(gr_line
		(start 189.602872 -14.660626)
		(end 189.934088 -14.660626)
		(stroke
			(width 0.0635)
			(type default)
		)
		(layer "F.Cu")
	)
	(gr_arc
		(start 190.131954 -248.604024)
		(mid 190.221757 -248.566827)
		(end 190.258954 -248.477024)
		(stroke
			(width 0.0635)
			(type default)
		)
		(layer "F.Cu")
	)
	(gr_arc
		(start 190.131954 -133.604)
		(mid 190.221757 -133.566803)
		(end 190.258954 -133.477)
		(stroke
			(width 0.0635)
			(type default)
		)
		(layer "F.Cu")
	)
	(gr_arc
		(start 190.131954 -18.603976)
		(mid 190.221757 -18.566779)
		(end 190.258954 -18.476976)
		(stroke
			(width 0.0635)
			(type default)
		)
		(layer "F.Cu")
	)
	(gr_arc
		(start 190.258954 -249.023124)
		(mid 190.221762 -248.933322)
		(end 190.131954 -248.896124)
		(stroke
			(width 0.0635)
			(type default)
		)
		(layer "F.Cu")
	)
	(gr_line
		(start 190.258954 -249.023124)
		(end 190.258954 -249.385074)
		(stroke
			(width 0.0635)
			(type default)
		)
		(layer "F.Cu")
	)
	(gr_line
		(start 190.258954 -248.115074)
		(end 190.258954 -248.477024)
		(stroke
			(width 0.0635)
			(type default)
		)
		(layer "F.Cu")
	)
	(gr_arc
		(start 190.258954 -134.0231)
		(mid 190.221754 -133.933314)
		(end 190.131954 -133.8961)
		(stroke
			(width 0.0635)
			(type default)
		)
		(layer "F.Cu")
	)
	(gr_line
		(start 190.258954 -134.0231)
		(end 190.258954 -134.38505)
		(stroke
			(width 0.0635)
			(type default)
		)
		(layer "F.Cu")
	)
	(gr_line
		(start 190.258954 -133.11505)
		(end 190.258954 -133.477)
		(stroke
			(width 0.0635)
			(type default)
		)
		(layer "F.Cu")
	)
	(gr_arc
		(start 190.258954 -19.023076)
		(mid 190.221745 -18.933305)
		(end 190.131954 -18.896076)
		(stroke
			(width 0.0635)
			(type default)
		)
		(layer "F.Cu")
	)
	(gr_line
		(start 190.258954 -19.023076)
		(end 190.258954 -19.385026)
		(stroke
			(width 0.0635)
			(type default)
		)
		(layer "F.Cu")
	)
	(gr_line
		(start 190.258954 -18.115026)
		(end 190.258954 -18.476976)
		(stroke
			(width 0.0635)
			(type default)
		)
		(layer "F.Cu")
	)
	(gr_line
		(start 190.492888 -245.219474)
		(end 190.873126 -245.219474)
		(stroke
			(width 0.0635)
			(type default)
		)
		(layer "F.Cu")
	)
	(gr_line
		(start 190.492888 -244.660674)
		(end 190.888874 -244.660674)
		(stroke
			(width 0.0635)
			(type default)
		)
		(layer "F.Cu")
	)
	(gr_line
		(start 190.492888 -130.21945)
		(end 190.873126 -130.21945)
		(stroke
			(width 0.0635)
			(type default)
		)
		(layer "F.Cu")
	)
	(gr_line
		(start 190.492888 -129.66065)
		(end 190.888874 -129.66065)
		(stroke
			(width 0.0635)
			(type default)
		)
		(layer "F.Cu")
	)
	(gr_line
		(start 190.492888 -15.219426)
		(end 190.873126 -15.219426)
		(stroke
			(width 0.0635)
			(type default)
		)
		(layer "F.Cu")
	)
	(gr_line
		(start 190.492888 -14.660626)
		(end 190.888874 -14.660626)
		(stroke
			(width 0.0635)
			(type default)
		)
		(layer "F.Cu")
	)
	(gr_line
		(start 190.873126 -245.219474)
		(end 190.95212 -245.14048)
		(stroke
			(width 0.0635)
			(type default)
		)
		(layer "F.Cu")
	)
	(gr_line
		(start 190.873126 -130.21945)
		(end 190.95212 -130.140456)
		(stroke
			(width 0.0635)
			(type default)
		)
		(layer "F.Cu")
	)
	(gr_line
		(start 190.873126 -15.219426)
		(end 190.95212 -15.140432)
		(stroke
			(width 0.0635)
			(type default)
		)
		(layer "F.Cu")
	)
	(gr_line
		(start 190.888874 -244.660674)
		(end 190.95212 -244.72392)
		(stroke
			(width 0.0635)
			(type default)
		)
		(layer "F.Cu")
	)
	(gr_line
		(start 190.888874 -129.66065)
		(end 190.95212 -129.723896)
		(stroke
			(width 0.0635)
			(type default)
		)
		(layer "F.Cu")
	)
	(gr_line
		(start 190.888874 -14.660626)
		(end 190.95212 -14.723872)
		(stroke
			(width 0.0635)
			(type default)
		)
		(layer "F.Cu")
	)
	(gr_arc
		(start 191.87668 -244.844824)
		(mid 191.989113 -244.798253)
		(end 192.035684 -244.68582)
		(stroke
			(width 0.0635)
			(type default)
		)
		(layer "F.Cu")
	)
	(gr_arc
		(start 191.87668 -129.8448)
		(mid 191.989113 -129.798229)
		(end 192.035684 -129.685796)
		(stroke
			(width 0.0635)
			(type default)
		)
		(layer "F.Cu")
	)
	(gr_arc
		(start 191.87668 -14.844776)
		(mid 191.989113 -14.798205)
		(end 192.035684 -14.685772)
		(stroke
			(width 0.0635)
			(type default)
		)
		(layer "F.Cu")
	)
	(gr_arc
		(start 192.035684 -245.295928)
		(mid 191.989121 -245.183484)
		(end 191.87668 -245.136924)
		(stroke
			(width 0.0635)
			(type default)
		)
		(layer "F.Cu")
	)
	(gr_line
		(start 192.035684 -245.295928)
		(end 192.035684 -245.562374)
		(stroke
			(width 0.0635)
			(type default)
		)
		(layer "F.Cu")
	)
	(gr_line
		(start 192.035684 -244.419374)
		(end 192.035684 -244.68582)
		(stroke
			(width 0.0635)
			(type default)
		)
		(layer "F.Cu")
	)
	(gr_arc
		(start 192.035684 -130.295904)
		(mid 191.989113 -130.183476)
		(end 191.87668 -130.1369)
		(stroke
			(width 0.0635)
			(type default)
		)
		(layer "F.Cu")
	)
	(gr_line
		(start 192.035684 -130.295904)
		(end 192.035684 -130.56235)
		(stroke
			(width 0.0635)
			(type default)
		)
		(layer "F.Cu")
	)
	(gr_line
		(start 192.035684 -129.41935)
		(end 192.035684 -129.685796)
		(stroke
			(width 0.0635)
			(type default)
		)
		(layer "F.Cu")
	)
	(gr_arc
		(start 192.035684 -15.29588)
		(mid 191.989105 -15.183467)
		(end 191.87668 -15.136876)
		(stroke
			(width 0.0635)
			(type default)
		)
		(layer "F.Cu")
	)
	(gr_line
		(start 192.035684 -15.29588)
		(end 192.035684 -15.562326)
		(stroke
			(width 0.0635)
			(type default)
		)
		(layer "F.Cu")
	)
	(gr_line
		(start 192.035684 -14.419326)
		(end 192.035684 -14.685772)
		(stroke
			(width 0.0635)
			(type default)
		)
		(layer "F.Cu")
	)
	(gr_line
		(start 239.155986 -357.682292)
		(end 239.430052 -357.408226)
		(stroke
			(width 0.127)
			(type default)
		)
		(layer "F.Cu")
	)
	(gr_line
		(start 239.155986 -356.412292)
		(end 239.430052 -356.686358)
		(stroke
			(width 0.127)
			(type default)
		)
		(layer "F.Cu")
	)
	(gr_line
		(start 240.817146 -344.671904)
		(end 243.624862 -344.671904)
		(stroke
			(width 0.127)
			(type default)
		)
		(layer "F.Cu")
	)
	(gr_line
		(start 241.491516 -355.687884)
		(end 241.660172 -355.519228)
		(stroke
			(width 0.127)
			(type default)
		)
		(layer "F.Cu")
	)
	(gr_line
		(start 241.59591 -356.305612)
		(end 241.698526 -356.408228)
		(stroke
			(width 0.127)
			(type default)
		)
		(layer "F.Cu")
	)
	(gr_line
		(start 241.660172 -355.519228)
		(end 241.698526 -355.519228)
		(stroke
			(width 0.127)
			(type default)
		)
		(layer "F.Cu")
	)
	(gr_line
		(start 241.698526 -356.408228)
		(end 242.144296 -356.408228)
		(stroke
			(width 0.127)
			(type default)
		)
		(layer "F.Cu")
	)
	(gr_line
		(start 241.698526 -355.519228)
		(end 242.094766 -355.519228)
		(stroke
			(width 0.127)
			(type default)
		)
		(layer "F.Cu")
	)
	(gr_line
		(start 242.094766 -355.519228)
		(end 242.166394 -355.4476)
		(stroke
			(width 0.127)
			(type default)
		)
		(layer "F.Cu")
	)
	(gr_line
		(start 242.144296 -356.408228)
		(end 242.199668 -356.4636)
		(stroke
			(width 0.127)
			(type default)
		)
		(layer "F.Cu")
	)
	(gr_line
		(start 242.166394 -355.4476)
		(end 242.6462 -355.4476)
		(stroke
			(width 0.127)
			(type default)
		)
		(layer "F.Cu")
	)
	(gr_line
		(start 242.199668 -356.4636)
		(end 242.6462 -356.4636)
		(stroke
			(width 0.127)
			(type default)
		)
		(layer "F.Cu")
	)
	(gr_line
		(start 243.624862 -344.671904)
		(end 244.568218 -345.61526)
		(stroke
			(width 0.127)
			(type default)
		)
		(layer "F.Cu")
	)
	(gr_line
		(start 244.311678 -354.0506)
		(end 244.602 -353.760278)
		(stroke
			(width 0.127)
			(type default)
		)
		(layer "F.Cu")
	)
	(gr_line
		(start 244.316758 -367.118138)
		(end 244.450616 -366.98428)
		(stroke
			(width 0.127)
			(type default)
		)
		(layer "F.Cu")
	)
	(gr_line
		(start 244.316758 -366.128554)
		(end 244.450616 -366.262412)
		(stroke
			(width 0.127)
			(type default)
		)
		(layer "F.Cu")
	)
	(gr_line
		(start 244.986556 -366.98428)
		(end 245.133622 -367.131346)
		(stroke
			(width 0.127)
			(type default)
		)
		(layer "F.Cu")
	)
	(gr_line
		(start 244.986556 -366.262412)
		(end 245.133622 -366.115346)
		(stroke
			(width 0.127)
			(type default)
		)
		(layer "F.Cu")
	)
	(gr_line
		(start 245.29034 -345.61526)
		(end 246.233696 -344.671904)
		(stroke
			(width 0.127)
			(type default)
		)
		(layer "F.Cu")
	)
	(gr_line
		(start 245.323868 -353.760278)
		(end 245.61419 -354.0506)
		(stroke
			(width 0.127)
			(type default)
		)
		(layer "F.Cu")
	)
	(gr_line
		(start 246.022622 -367.131346)
		(end 246.169688 -366.98428)
		(stroke
			(width 0.127)
			(type default)
		)
		(layer "F.Cu")
	)
	(gr_line
		(start 246.022622 -366.115346)
		(end 246.169688 -366.262412)
		(stroke
			(width 0.127)
			(type default)
		)
		(layer "F.Cu")
	)
	(gr_line
		(start 246.233696 -344.671904)
		(end 249.047254 -344.671904)
		(stroke
			(width 0.127)
			(type default)
		)
		(layer "F.Cu")
	)
	(gr_line
		(start 247.024652 -366.987582)
		(end 247.298718 -367.261648)
		(stroke
			(width 0.127)
			(type default)
		)
		(layer "F.Cu")
	)
	(gr_line
		(start 247.024652 -366.265714)
		(end 247.298718 -365.991648)
		(stroke
			(width 0.127)
			(type default)
		)
		(layer "F.Cu")
	)
	(gr_line
		(start 247.298718 -367.261648)
		(end 247.572784 -366.987582)
		(stroke
			(width 0.127)
			(type default)
		)
		(layer "F.Cu")
	)
	(gr_line
		(start 247.298718 -365.991648)
		(end 247.572784 -366.265714)
		(stroke
			(width 0.127)
			(type default)
		)
		(layer "F.Cu")
	)
	(gr_line
		(start 248.080276 -366.9792)
		(end 248.168922 -367.067846)
		(stroke
			(width 0.127)
			(type default)
		)
		(layer "F.Cu")
	)
	(gr_line
		(start 248.080276 -366.257078)
		(end 248.158508 -366.178846)
		(stroke
			(width 0.127)
			(type default)
		)
		(layer "F.Cu")
	)
	(gr_line
		(start 248.158508 -366.178846)
		(end 248.524522 -366.178846)
		(stroke
			(width 0.127)
			(type default)
		)
		(layer "F.Cu")
	)
	(gr_line
		(start 248.168922 -367.067846)
		(end 248.524522 -367.067846)
		(stroke
			(width 0.127)
			(type default)
		)
		(layer "F.Cu")
	)
	(gr_line
		(start 248.524522 -367.067846)
		(end 248.608088 -366.98428)
		(stroke
			(width 0.127)
			(type default)
		)
		(layer "F.Cu")
	)
	(gr_line
		(start 248.524522 -366.178846)
		(end 248.608088 -366.262412)
		(stroke
			(width 0.127)
			(type default)
		)
		(layer "F.Cu")
	)
	(gr_line
		(start 249.473466 -366.865408)
		(end 250.874022 -366.865408)
		(stroke
			(width 0.127)
			(type default)
		)
		(layer "F.Cu")
	)
	(gr_line
		(start 249.515122 -367.44148)
		(end 249.591322 -367.36528)
		(stroke
			(width 0.127)
			(type default)
		)
		(layer "F.Cu")
	)
	(gr_line
		(start 249.515122 -365.78921)
		(end 249.591322 -365.86541)
		(stroke
			(width 0.127)
			(type default)
		)
		(layer "F.Cu")
	)
	(gr_line
		(start 249.591322 -367.36528)
		(end 250.874022 -367.36528)
		(stroke
			(width 0.127)
			(type default)
		)
		(layer "F.Cu")
	)
	(gr_line
		(start 249.591322 -365.86541)
		(end 250.874022 -365.86541)
		(stroke
			(width 0.127)
			(type default)
		)
		(layer "F.Cu")
	)
	(gr_line
		(start 249.973592 -366.357408)
		(end 249.981466 -366.365282)
		(stroke
			(width 0.127)
			(type default)
		)
		(layer "F.Cu")
	)
	(gr_line
		(start 249.981466 -366.365282)
		(end 250.874022 -366.365282)
		(stroke
			(width 0.127)
			(type default)
		)
		(layer "F.Cu")
	)
	(gr_line
		(start 319.2145 -128.627124)
		(end 319.482724 -128.627124)
		(stroke
			(width 0.0635)
			(type default)
		)
		(layer "F.Cu")
	)
	(gr_line
		(start 319.2145 -13.6271)
		(end 319.4685 -13.6271)
		(stroke
			(width 0.0635)
			(type default)
		)
		(layer "F.Cu")
	)
	(gr_line
		(start 319.40246 -245.208044)
		(end 319.40246 -245.455694)
		(stroke
			(width 0.0635)
			(type default)
		)
		(layer "F.Cu")
	)
	(gr_arc
		(start 319.40246 -244.560344)
		(mid 319.45455 -244.686053)
		(end 319.58026 -244.738144)
		(stroke
			(width 0.0635)
			(type default)
		)
		(layer "F.Cu")
	)
	(gr_line
		(start 319.40246 -244.312694)
		(end 319.40246 -244.560344)
		(stroke
			(width 0.0635)
			(type default)
		)
		(layer "F.Cu")
	)
	(gr_arc
		(start 319.58026 -245.030244)
		(mid 319.454536 -245.08232)
		(end 319.40246 -245.208044)
		(stroke
			(width 0.0635)
			(type default)
		)
		(layer "F.Cu")
	)
	(gr_arc
		(start 319.63995 -128.78435)
		(mid 319.5939 -128.673174)
		(end 319.482724 -128.627124)
		(stroke
			(width 0.0635)
			(type default)
		)
		(layer "F.Cu")
	)
	(gr_arc
		(start 319.63995 -13.79855)
		(mid 319.589733 -13.677317)
		(end 319.4685 -13.6271)
		(stroke
			(width 0.0635)
			(type default)
		)
		(layer "F.Cu")
	)
	(gr_arc
		(start 320.089276 -128.627124)
		(mid 319.978134 -128.673186)
		(end 319.93205 -128.78435)
		(stroke
			(width 0.0635)
			(type default)
		)
		(layer "F.Cu")
	)
	(gr_line
		(start 320.089276 -128.627124)
		(end 320.3575 -128.627124)
		(stroke
			(width 0.0635)
			(type default)
		)
		(layer "F.Cu")
	)
	(gr_arc
		(start 320.1035 -13.6271)
		(mid 319.982249 -13.677314)
		(end 319.93205 -13.79855)
		(stroke
			(width 0.0635)
			(type default)
		)
		(layer "F.Cu")
	)
	(gr_line
		(start 320.1035 -13.6271)
		(end 320.3575 -13.6271)
		(stroke
			(width 0.0635)
			(type default)
		)
		(layer "F.Cu")
	)
	(gr_line
		(start 320.952876 -245.148354)
		(end 321.023996 -245.219474)
		(stroke
			(width 0.0635)
			(type default)
		)
		(layer "F.Cu")
	)
	(gr_line
		(start 320.952876 -244.731794)
		(end 321.023996 -244.660674)
		(stroke
			(width 0.0635)
			(type default)
		)
		(layer "F.Cu")
	)
	(gr_line
		(start 320.952876 -130.14833)
		(end 321.023996 -130.21945)
		(stroke
			(width 0.0635)
			(type default)
		)
		(layer "F.Cu")
	)
	(gr_line
		(start 320.952876 -129.73177)
		(end 321.023996 -129.66065)
		(stroke
			(width 0.0635)
			(type default)
		)
		(layer "F.Cu")
	)
	(gr_line
		(start 320.952876 -15.148306)
		(end 321.023996 -15.219426)
		(stroke
			(width 0.0635)
			(type default)
		)
		(layer "F.Cu")
	)
	(gr_line
		(start 320.952876 -14.731746)
		(end 321.023996 -14.660626)
		(stroke
			(width 0.0635)
			(type default)
		)
		(layer "F.Cu")
	)
	(gr_line
		(start 321.023996 -245.219474)
		(end 321.355212 -245.219474)
		(stroke
			(width 0.0635)
			(type default)
		)
		(layer "F.Cu")
	)
	(gr_line
		(start 321.023996 -244.660674)
		(end 321.355212 -244.660674)
		(stroke
			(width 0.0635)
			(type default)
		)
		(layer "F.Cu")
	)
	(gr_line
		(start 321.023996 -130.21945)
		(end 321.355212 -130.21945)
		(stroke
			(width 0.0635)
			(type default)
		)
		(layer "F.Cu")
	)
	(gr_line
		(start 321.023996 -129.66065)
		(end 321.355212 -129.66065)
		(stroke
			(width 0.0635)
			(type default)
		)
		(layer "F.Cu")
	)
	(gr_line
		(start 321.023996 -15.219426)
		(end 321.355212 -15.219426)
		(stroke
			(width 0.0635)
			(type default)
		)
		(layer "F.Cu")
	)
	(gr_line
		(start 321.023996 -14.660626)
		(end 321.355212 -14.660626)
		(stroke
			(width 0.0635)
			(type default)
		)
		(layer "F.Cu")
	)
	(gr_line
		(start 321.914012 -245.219474)
		(end 322.292726 -245.219474)
		(stroke
			(width 0.0635)
			(type default)
		)
		(layer "F.Cu")
	)
	(gr_line
		(start 321.914012 -244.660674)
		(end 322.333874 -244.660674)
		(stroke
			(width 0.0635)
			(type default)
		)
		(layer "F.Cu")
	)
	(gr_line
		(start 321.914012 -130.21945)
		(end 322.509388 -130.21945)
		(stroke
			(width 0.0635)
			(type default)
		)
		(layer "F.Cu")
	)
	(gr_line
		(start 321.914012 -129.66065)
		(end 322.5546 -129.66065)
		(stroke
			(width 0.0635)
			(type default)
		)
		(layer "F.Cu")
	)
	(gr_line
		(start 321.914012 -15.219426)
		(end 322.28155 -15.219426)
		(stroke
			(width 0.0635)
			(type default)
		)
		(layer "F.Cu")
	)
	(gr_line
		(start 321.914012 -14.660626)
		(end 322.273422 -14.660626)
		(stroke
			(width 0.0635)
			(type default)
		)
		(layer "F.Cu")
	)
	(gr_line
		(start 322.273422 -14.660626)
		(end 322.348606 -14.73581)
		(stroke
			(width 0.0635)
			(type default)
		)
		(layer "F.Cu")
	)
	(gr_line
		(start 322.28155 -15.219426)
		(end 322.348606 -15.15237)
		(stroke
			(width 0.0635)
			(type default)
		)
		(layer "F.Cu")
	)
	(gr_line
		(start 322.292726 -245.219474)
		(end 322.38442 -245.12778)
		(stroke
			(width 0.0635)
			(type default)
		)
		(layer "F.Cu")
	)
	(gr_line
		(start 322.333874 -244.660674)
		(end 322.38442 -244.71122)
		(stroke
			(width 0.0635)
			(type default)
		)
		(layer "F.Cu")
	)
	(gr_line
		(start 322.509388 -130.21945)
		(end 322.603114 -130.125724)
		(stroke
			(width 0.0635)
			(type default)
		)
		(layer "F.Cu")
	)
	(gr_line
		(start 322.5546 -129.66065)
		(end 322.603114 -129.709164)
		(stroke
			(width 0.0635)
			(type default)
		)
		(layer "F.Cu")
	)
	(gr_line
		(start 322.6816 -132.437124)
		(end 322.987924 -132.437124)
		(stroke
			(width 0.0635)
			(type default)
		)
		(layer "F.Cu")
	)
	(gr_line
		(start 322.6816 -17.4371)
		(end 322.9991 -17.4371)
		(stroke
			(width 0.0635)
			(type default)
		)
		(layer "F.Cu")
	)
	(gr_arc
		(start 323.17055 -132.61975)
		(mid 323.11706 -132.490614)
		(end 322.987924 -132.437124)
		(stroke
			(width 0.0635)
			(type default)
		)
		(layer "F.Cu")
	)
	(gr_arc
		(start 323.17055 -17.60855)
		(mid 323.120333 -17.487317)
		(end 322.9991 -17.4371)
		(stroke
			(width 0.0635)
			(type default)
		)
		(layer "F.Cu")
	)
	(gr_line
		(start 323.58965 -249.023124)
		(end 323.58965 -249.385074)
		(stroke
			(width 0.0635)
			(type default)
		)
		(layer "F.Cu")
	)
	(gr_arc
		(start 323.58965 -248.477024)
		(mid 323.626859 -248.566793)
		(end 323.71665 -248.604024)
		(stroke
			(width 0.0635)
			(type default)
		)
		(layer "F.Cu")
	)
	(gr_line
		(start 323.58965 -248.115074)
		(end 323.58965 -248.477024)
		(stroke
			(width 0.0635)
			(type default)
		)
		(layer "F.Cu")
	)
	(gr_arc
		(start 323.6341 -17.4371)
		(mid 323.512849 -17.487314)
		(end 323.46265 -17.60855)
		(stroke
			(width 0.0635)
			(type default)
		)
		(layer "F.Cu")
	)
	(gr_line
		(start 323.6341 -17.4371)
		(end 323.9516 -17.4371)
		(stroke
			(width 0.0635)
			(type default)
		)
		(layer "F.Cu")
	)
	(gr_arc
		(start 323.645276 -132.437124)
		(mid 323.516138 -132.490619)
		(end 323.46265 -132.61975)
		(stroke
			(width 0.0635)
			(type default)
		)
		(layer "F.Cu")
	)
	(gr_line
		(start 323.645276 -132.437124)
		(end 323.9516 -132.437124)
		(stroke
			(width 0.0635)
			(type default)
		)
		(layer "F.Cu")
	)
	(gr_arc
		(start 323.71665 -248.896124)
		(mid 323.626847 -248.933321)
		(end 323.58965 -249.023124)
		(stroke
			(width 0.0635)
			(type default)
		)
		(layer "F.Cu")
	)
	(gr_line
		(start 325.832978 -133.942582)
		(end 325.913496 -134.0231)
		(stroke
			(width 0.0635)
			(type default)
		)
		(layer "F.Cu")
	)
	(gr_line
		(start 325.832978 -133.526022)
		(end 325.913496 -133.445504)
		(stroke
			(width 0.0635)
			(type default)
		)
		(layer "F.Cu")
	)
	(gr_line
		(start 325.83374 -248.97334)
		(end 325.913496 -249.053096)
		(stroke
			(width 0.0635)
			(type default)
		)
		(layer "F.Cu")
	)
	(gr_line
		(start 325.83374 -248.55678)
		(end 325.913496 -248.477024)
		(stroke
			(width 0.0635)
			(type default)
		)
		(layer "F.Cu")
	)
	(gr_line
		(start 325.848726 -245.148354)
		(end 325.913496 -245.213124)
		(stroke
			(width 0.0635)
			(type default)
		)
		(layer "F.Cu")
	)
	(gr_line
		(start 325.848726 -244.731794)
		(end 325.913496 -244.667024)
		(stroke
			(width 0.0635)
			(type default)
		)
		(layer "F.Cu")
	)
	(gr_line
		(start 325.848726 -130.14833)
		(end 325.913496 -130.2131)
		(stroke
			(width 0.0635)
			(type default)
		)
		(layer "F.Cu")
	)
	(gr_line
		(start 325.848726 -129.73177)
		(end 325.913496 -129.667)
		(stroke
			(width 0.0635)
			(type default)
		)
		(layer "F.Cu")
	)
	(gr_line
		(start 325.848726 -18.958306)
		(end 325.913496 -19.023076)
		(stroke
			(width 0.0635)
			(type default)
		)
		(layer "F.Cu")
	)
	(gr_line
		(start 325.848726 -18.541746)
		(end 325.913496 -18.476976)
		(stroke
			(width 0.0635)
			(type default)
		)
		(layer "F.Cu")
	)
	(gr_line
		(start 325.848726 -15.148306)
		(end 325.913496 -15.213076)
		(stroke
			(width 0.0635)
			(type default)
		)
		(layer "F.Cu")
	)
	(gr_line
		(start 325.848726 -14.731746)
		(end 325.913496 -14.666976)
		(stroke
			(width 0.0635)
			(type default)
		)
		(layer "F.Cu")
	)
	(gr_line
		(start 325.913496 -249.258074)
		(end 326.040496 -249.385074)
		(stroke
			(width 0.0635)
			(type default)
		)
		(layer "F.Cu")
	)
	(gr_line
		(start 325.913496 -249.053096)
		(end 325.913496 -249.258074)
		(stroke
			(width 0.0635)
			(type default)
		)
		(layer "F.Cu")
	)
	(gr_line
		(start 325.913496 -248.242074)
		(end 325.913496 -248.477024)
		(stroke
			(width 0.0635)
			(type default)
		)
		(layer "F.Cu")
	)
	(gr_line
		(start 325.913496 -248.242074)
		(end 326.040496 -248.115074)
		(stroke
			(width 0.0635)
			(type default)
		)
		(layer "F.Cu")
	)
	(gr_line
		(start 325.913496 -245.448074)
		(end 326.040496 -245.575074)
		(stroke
			(width 0.0635)
			(type default)
		)
		(layer "F.Cu")
	)
	(gr_line
		(start 325.913496 -245.213124)
		(end 325.913496 -245.448074)
		(stroke
			(width 0.0635)
			(type default)
		)
		(layer "F.Cu")
	)
	(gr_line
		(start 325.913496 -244.432074)
		(end 325.913496 -244.667024)
		(stroke
			(width 0.0635)
			(type default)
		)
		(layer "F.Cu")
	)
	(gr_line
		(start 325.913496 -244.432074)
		(end 326.040496 -244.305074)
		(stroke
			(width 0.0635)
			(type default)
		)
		(layer "F.Cu")
	)
	(gr_line
		(start 325.913496 -134.270496)
		(end 326.02805 -134.38505)
		(stroke
			(width 0.0635)
			(type default)
		)
		(layer "F.Cu")
	)
	(gr_line
		(start 325.913496 -134.0231)
		(end 325.913496 -134.270496)
		(stroke
			(width 0.0635)
			(type default)
		)
		(layer "F.Cu")
	)
	(gr_line
		(start 325.913496 -133.24205)
		(end 325.913496 -133.445504)
		(stroke
			(width 0.0635)
			(type default)
		)
		(layer "F.Cu")
	)
	(gr_line
		(start 325.913496 -133.24205)
		(end 326.040496 -133.11505)
		(stroke
			(width 0.0635)
			(type default)
		)
		(layer "F.Cu")
	)
	(gr_line
		(start 325.913496 -130.44805)
		(end 326.040496 -130.57505)
		(stroke
			(width 0.0635)
			(type default)
		)
		(layer "F.Cu")
	)
	(gr_line
		(start 325.913496 -130.2131)
		(end 325.913496 -130.44805)
		(stroke
			(width 0.0635)
			(type default)
		)
		(layer "F.Cu")
	)
	(gr_line
		(start 325.913496 -129.43205)
		(end 325.913496 -129.667)
		(stroke
			(width 0.0635)
			(type default)
		)
		(layer "F.Cu")
	)
	(gr_line
		(start 325.913496 -129.43205)
		(end 326.040496 -129.30505)
		(stroke
			(width 0.0635)
			(type default)
		)
		(layer "F.Cu")
	)
	(gr_line
		(start 325.913496 -19.258026)
		(end 326.040496 -19.385026)
		(stroke
			(width 0.0635)
			(type default)
		)
		(layer "F.Cu")
	)
	(gr_line
		(start 325.913496 -19.023076)
		(end 325.913496 -19.258026)
		(stroke
			(width 0.0635)
			(type default)
		)
		(layer "F.Cu")
	)
	(gr_line
		(start 325.913496 -18.242026)
		(end 325.913496 -18.476976)
		(stroke
			(width 0.0635)
			(type default)
		)
		(layer "F.Cu")
	)
	(gr_line
		(start 325.913496 -18.242026)
		(end 326.040496 -18.115026)
		(stroke
			(width 0.0635)
			(type default)
		)
		(layer "F.Cu")
	)
	(gr_line
		(start 325.913496 -15.448026)
		(end 326.040496 -15.575026)
		(stroke
			(width 0.0635)
			(type default)
		)
		(layer "F.Cu")
	)
	(gr_line
		(start 325.913496 -15.213076)
		(end 325.913496 -15.448026)
		(stroke
			(width 0.0635)
			(type default)
		)
		(layer "F.Cu")
	)
	(gr_line
		(start 325.913496 -14.432026)
		(end 325.913496 -14.666976)
		(stroke
			(width 0.0635)
			(type default)
		)
		(layer "F.Cu")
	)
	(gr_line
		(start 325.913496 -14.432026)
		(end 326.040496 -14.305026)
		(stroke
			(width 0.0635)
			(type default)
		)
		(layer "F.Cu")
	)
	(gr_line
		(start 326.02805 -134.38505)
		(end 327.375012 -134.38505)
		(stroke
			(width 0.0635)
			(type default)
		)
		(layer "F.Cu")
	)
	(gr_line
		(start 326.040496 -249.385074)
		(end 327.375012 -249.385074)
		(stroke
			(width 0.0635)
			(type default)
		)
		(layer "F.Cu")
	)
	(gr_line
		(start 326.040496 -248.115074)
		(end 327.375012 -248.115074)
		(stroke
			(width 0.0635)
			(type default)
		)
		(layer "F.Cu")
	)
	(gr_line
		(start 326.040496 -245.575074)
		(end 327.375012 -245.575074)
		(stroke
			(width 0.0635)
			(type default)
		)
		(layer "F.Cu")
	)
	(gr_line
		(start 326.040496 -244.305074)
		(end 327.375012 -244.305074)
		(stroke
			(width 0.0635)
			(type default)
		)
		(layer "F.Cu")
	)
	(gr_line
		(start 326.040496 -133.11505)
		(end 327.375012 -133.11505)
		(stroke
			(width 0.0635)
			(type default)
		)
		(layer "F.Cu")
	)
	(gr_line
		(start 326.040496 -130.57505)
		(end 327.375012 -130.57505)
		(stroke
			(width 0.0635)
			(type default)
		)
		(layer "F.Cu")
	)
	(gr_line
		(start 326.040496 -129.30505)
		(end 327.375012 -129.30505)
		(stroke
			(width 0.0635)
			(type default)
		)
		(layer "F.Cu")
	)
	(gr_line
		(start 326.040496 -19.385026)
		(end 327.375012 -19.385026)
		(stroke
			(width 0.0635)
			(type default)
		)
		(layer "F.Cu")
	)
	(gr_line
		(start 326.040496 -18.115026)
		(end 327.375012 -18.115026)
		(stroke
			(width 0.0635)
			(type default)
		)
		(layer "F.Cu")
	)
	(gr_line
		(start 326.040496 -15.575026)
		(end 327.375012 -15.575026)
		(stroke
			(width 0.0635)
			(type default)
		)
		(layer "F.Cu")
	)
	(gr_line
		(start 326.040496 -14.305026)
		(end 327.375012 -14.305026)
		(stroke
			(width 0.0635)
			(type default)
		)
		(layer "F.Cu")
	)
	(gr_line
		(start 350.764602 -128.627124)
		(end 351.029524 -128.627124)
		(stroke
			(width 0.0635)
			(type default)
		)
		(layer "F.Cu")
	)
	(gr_line
		(start 350.764602 -13.6271)
		(end 351.0153 -13.6271)
		(stroke
			(width 0.0635)
			(type default)
		)
		(layer "F.Cu")
	)
	(gr_line
		(start 350.942402 -245.209822)
		(end 350.942402 -245.460774)
		(stroke
			(width 0.0635)
			(type default)
		)
		(layer "F.Cu")
	)
	(gr_arc
		(start 350.942402 -244.568726)
		(mid 350.99352 -244.692098)
		(end 351.1169 -244.743224)
		(stroke
			(width 0.0635)
			(type default)
		)
		(layer "F.Cu")
	)
	(gr_line
		(start 350.942402 -244.317774)
		(end 350.942402 -244.568726)
		(stroke
			(width 0.0635)
			(type default)
		)
		(layer "F.Cu")
	)
	(gr_arc
		(start 351.1169 -245.035324)
		(mid 350.993511 -245.086433)
		(end 350.942402 -245.209822)
		(stroke
			(width 0.0635)
			(type default)
		)
		(layer "F.Cu")
	)
	(gr_arc
		(start 351.190052 -128.787652)
		(mid 351.143034 -128.674142)
		(end 351.029524 -128.627124)
		(stroke
			(width 0.0635)
			(type default)
		)
		(layer "F.Cu")
	)
	(gr_arc
		(start 351.190052 -13.801852)
		(mid 351.138868 -13.678284)
		(end 351.0153 -13.6271)
		(stroke
			(width 0.0635)
			(type default)
		)
		(layer "F.Cu")
	)
	(gr_arc
		(start 351.64268 -128.627124)
		(mid 351.529166 -128.674146)
		(end 351.482152 -128.787652)
		(stroke
			(width 0.0635)
			(type default)
		)
		(layer "F.Cu")
	)
	(gr_line
		(start 351.64268 -128.627124)
		(end 351.907602 -128.627124)
		(stroke
			(width 0.0635)
			(type default)
		)
		(layer "F.Cu")
	)
	(gr_arc
		(start 351.656904 -13.6271)
		(mid 351.533316 -13.678279)
		(end 351.482152 -13.801852)
		(stroke
			(width 0.0635)
			(type default)
		)
		(layer "F.Cu")
	)
	(gr_line
		(start 351.656904 -13.6271)
		(end 351.907602 -13.6271)
		(stroke
			(width 0.0635)
			(type default)
		)
		(layer "F.Cu")
	)
	(gr_line
		(start 352.37801 -15.023338)
		(end 352.574098 -15.219426)
		(stroke
			(width 0.0635)
			(type default)
		)
		(layer "F.Cu")
	)
	(gr_line
		(start 352.502978 -245.148354)
		(end 352.574098 -245.219474)
		(stroke
			(width 0.0635)
			(type default)
		)
		(layer "F.Cu")
	)
	(gr_line
		(start 352.502978 -244.731794)
		(end 352.574098 -244.660674)
		(stroke
			(width 0.0635)
			(type default)
		)
		(layer "F.Cu")
	)
	(gr_line
		(start 352.502978 -130.14833)
		(end 352.574098 -130.21945)
		(stroke
			(width 0.0635)
			(type default)
		)
		(layer "F.Cu")
	)
	(gr_line
		(start 352.502978 -129.73177)
		(end 352.574098 -129.66065)
		(stroke
			(width 0.0635)
			(type default)
		)
		(layer "F.Cu")
	)
	(gr_line
		(start 352.506026 -14.728698)
		(end 352.574098 -14.660626)
		(stroke
			(width 0.0635)
			(type default)
		)
		(layer "F.Cu")
	)
	(gr_line
		(start 352.574098 -245.219474)
		(end 352.905314 -245.219474)
		(stroke
			(width 0.0635)
			(type default)
		)
		(layer "F.Cu")
	)
	(gr_line
		(start 352.574098 -244.660674)
		(end 352.905314 -244.660674)
		(stroke
			(width 0.0635)
			(type default)
		)
		(layer "F.Cu")
	)
	(gr_line
		(start 352.574098 -130.21945)
		(end 352.905314 -130.21945)
		(stroke
			(width 0.0635)
			(type default)
		)
		(layer "F.Cu")
	)
	(gr_line
		(start 352.574098 -129.66065)
		(end 352.905314 -129.66065)
		(stroke
			(width 0.0635)
			(type default)
		)
		(layer "F.Cu")
	)
	(gr_line
		(start 352.574098 -15.219426)
		(end 352.905314 -15.219426)
		(stroke
			(width 0.0635)
			(type default)
		)
		(layer "F.Cu")
	)
	(gr_line
		(start 352.574098 -14.660626)
		(end 352.905314 -14.660626)
		(stroke
			(width 0.0635)
			(type default)
		)
		(layer "F.Cu")
	)
	(gr_line
		(start 353.464114 -245.219474)
		(end 353.839526 -245.219474)
		(stroke
			(width 0.0635)
			(type default)
		)
		(layer "F.Cu")
	)
	(gr_line
		(start 353.464114 -244.660674)
		(end 353.829874 -244.660674)
		(stroke
			(width 0.0635)
			(type default)
		)
		(layer "F.Cu")
	)
	(gr_line
		(start 353.464114 -130.21945)
		(end 353.89185 -130.21945)
		(stroke
			(width 0.0635)
			(type default)
		)
		(layer "F.Cu")
	)
	(gr_line
		(start 353.464114 -129.66065)
		(end 353.949 -129.66065)
		(stroke
			(width 0.0635)
			(type default)
		)
		(layer "F.Cu")
	)
	(gr_line
		(start 353.464114 -15.219426)
		(end 353.82835 -15.219426)
		(stroke
			(width 0.0635)
			(type default)
		)
		(layer "F.Cu")
	)
	(gr_line
		(start 353.464114 -14.660626)
		(end 353.846638 -14.660626)
		(stroke
			(width 0.0635)
			(type default)
		)
		(layer "F.Cu")
	)
	(gr_line
		(start 353.82835 -15.219426)
		(end 353.908614 -15.139162)
		(stroke
			(width 0.0635)
			(type default)
		)
		(layer "F.Cu")
	)
	(gr_line
		(start 353.829874 -244.660674)
		(end 353.90582 -244.73662)
		(stroke
			(width 0.0635)
			(type default)
		)
		(layer "F.Cu")
	)
	(gr_line
		(start 353.839526 -245.219474)
		(end 353.90582 -245.15318)
		(stroke
			(width 0.0635)
			(type default)
		)
		(layer "F.Cu")
	)
	(gr_line
		(start 353.846638 -14.660626)
		(end 353.908614 -14.722602)
		(stroke
			(width 0.0635)
			(type default)
		)
		(layer "F.Cu")
	)
	(gr_line
		(start 353.89185 -130.21945)
		(end 353.991418 -130.119882)
		(stroke
			(width 0.0635)
			(type default)
		)
		(layer "F.Cu")
	)
	(gr_line
		(start 353.949 -129.66065)
		(end 353.991418 -129.703068)
		(stroke
			(width 0.0635)
			(type default)
		)
		(layer "F.Cu")
	)
	(gr_line
		(start 354.231702 -132.437124)
		(end 354.534724 -132.437124)
		(stroke
			(width 0.0635)
			(type default)
		)
		(layer "F.Cu")
	)
	(gr_line
		(start 354.231702 -17.4371)
		(end 354.5459 -17.4371)
		(stroke
			(width 0.0635)
			(type default)
		)
		(layer "F.Cu")
	)
	(gr_arc
		(start 354.720652 -132.623052)
		(mid 354.666195 -132.491581)
		(end 354.534724 -132.437124)
		(stroke
			(width 0.0635)
			(type default)
		)
		(layer "F.Cu")
	)
	(gr_arc
		(start 354.720652 -17.611852)
		(mid 354.669468 -17.488284)
		(end 354.5459 -17.4371)
		(stroke
			(width 0.0635)
			(type default)
		)
		(layer "F.Cu")
	)
	(gr_line
		(start 355.139752 -249.023124)
		(end 355.139752 -249.385074)
		(stroke
			(width 0.0635)
			(type default)
		)
		(layer "F.Cu")
	)
	(gr_arc
		(start 355.139752 -248.477024)
		(mid 355.176955 -248.566828)
		(end 355.266752 -248.604024)
		(stroke
			(width 0.0635)
			(type default)
		)
		(layer "F.Cu")
	)
	(gr_line
		(start 355.139752 -248.115074)
		(end 355.139752 -248.477024)
		(stroke
			(width 0.0635)
			(type default)
		)
		(layer "F.Cu")
	)
	(gr_arc
		(start 355.187504 -17.4371)
		(mid 355.063916 -17.488279)
		(end 355.012752 -17.611852)
		(stroke
			(width 0.0635)
			(type default)
		)
		(layer "F.Cu")
	)
	(gr_line
		(start 355.187504 -17.4371)
		(end 355.501702 -17.4371)
		(stroke
			(width 0.0635)
			(type default)
		)
		(layer "F.Cu")
	)
	(gr_arc
		(start 355.19868 -132.437124)
		(mid 355.067205 -132.491585)
		(end 355.012752 -132.623052)
		(stroke
			(width 0.0635)
			(type default)
		)
		(layer "F.Cu")
	)
	(gr_line
		(start 355.19868 -132.437124)
		(end 355.501702 -132.437124)
		(stroke
			(width 0.0635)
			(type default)
		)
		(layer "F.Cu")
	)
	(gr_arc
		(start 355.266752 -248.896124)
		(mid 355.176949 -248.933321)
		(end 355.139752 -249.023124)
		(stroke
			(width 0.0635)
			(type default)
		)
		(layer "F.Cu")
	)
	(gr_line
		(start 357.382318 -248.975118)
		(end 357.463598 -249.056398)
		(stroke
			(width 0.0635)
			(type default)
		)
		(layer "F.Cu")
	)
	(gr_line
		(start 357.382318 -248.558304)
		(end 357.463598 -248.477024)
		(stroke
			(width 0.0635)
			(type default)
		)
		(layer "F.Cu")
	)
	(gr_line
		(start 357.398828 -245.148354)
		(end 357.463598 -245.213124)
		(stroke
			(width 0.0635)
			(type default)
		)
		(layer "F.Cu")
	)
	(gr_line
		(start 357.398828 -244.731794)
		(end 357.463598 -244.667024)
		(stroke
			(width 0.0635)
			(type default)
		)
		(layer "F.Cu")
	)
	(gr_line
		(start 357.398828 -130.14833)
		(end 357.463598 -130.2131)
		(stroke
			(width 0.0635)
			(type default)
		)
		(layer "F.Cu")
	)
	(gr_line
		(start 357.398828 -129.73177)
		(end 357.463598 -129.667)
		(stroke
			(width 0.0635)
			(type default)
		)
		(layer "F.Cu")
	)
	(gr_line
		(start 357.398828 -18.958306)
		(end 357.463598 -19.023076)
		(stroke
			(width 0.0635)
			(type default)
		)
		(layer "F.Cu")
	)
	(gr_line
		(start 357.398828 -18.541746)
		(end 357.463598 -18.476976)
		(stroke
			(width 0.0635)
			(type default)
		)
		(layer "F.Cu")
	)
	(gr_line
		(start 357.398828 -15.148306)
		(end 357.463598 -15.213076)
		(stroke
			(width 0.0635)
			(type default)
		)
		(layer "F.Cu")
	)
	(gr_line
		(start 357.398828 -14.731746)
		(end 357.463598 -14.666976)
		(stroke
			(width 0.0635)
			(type default)
		)
		(layer "F.Cu")
	)
	(gr_line
		(start 357.413306 -133.944106)
		(end 357.463598 -133.994398)
		(stroke
			(width 0.0635)
			(type default)
		)
		(layer "F.Cu")
	)
	(gr_line
		(start 357.413306 -133.527292)
		(end 357.463598 -133.477)
		(stroke
			(width 0.0635)
			(type default)
		)
		(layer "F.Cu")
	)
	(gr_line
		(start 357.463598 -249.258074)
		(end 357.590598 -249.385074)
		(stroke
			(width 0.0635)
			(type default)
		)
		(layer "F.Cu")
	)
	(gr_line
		(start 357.463598 -249.056398)
		(end 357.463598 -249.258074)
		(stroke
			(width 0.0635)
			(type default)
		)
		(layer "F.Cu")
	)
	(gr_line
		(start 357.463598 -248.242074)
		(end 357.463598 -248.477024)
		(stroke
			(width 0.0635)
			(type default)
		)
		(layer "F.Cu")
	)
	(gr_line
		(start 357.463598 -248.242074)
		(end 357.590598 -248.115074)
		(stroke
			(width 0.0635)
			(type default)
		)
		(layer "F.Cu")
	)
	(gr_line
		(start 357.463598 -245.448074)
		(end 357.590598 -245.575074)
		(stroke
			(width 0.0635)
			(type default)
		)
		(layer "F.Cu")
	)
	(gr_line
		(start 357.463598 -245.213124)
		(end 357.463598 -245.448074)
		(stroke
			(width 0.0635)
			(type default)
		)
		(layer "F.Cu")
	)
	(gr_line
		(start 357.463598 -244.432074)
		(end 357.463598 -244.667024)
		(stroke
			(width 0.0635)
			(type default)
		)
		(layer "F.Cu")
	)
	(gr_line
		(start 357.463598 -244.432074)
		(end 357.590598 -244.305074)
		(stroke
			(width 0.0635)
			(type default)
		)
		(layer "F.Cu")
	)
	(gr_line
		(start 357.463598 -134.25805)
		(end 357.590598 -134.38505)
		(stroke
			(width 0.0635)
			(type default)
		)
		(layer "F.Cu")
	)
	(gr_line
		(start 357.463598 -133.994398)
		(end 357.463598 -134.25805)
		(stroke
			(width 0.0635)
			(type default)
		)
		(layer "F.Cu")
	)
	(gr_line
		(start 357.463598 -133.24205)
		(end 357.463598 -133.477)
		(stroke
			(width 0.0635)
			(type default)
		)
		(layer "F.Cu")
	)
	(gr_line
		(start 357.463598 -133.24205)
		(end 357.590598 -133.11505)
		(stroke
			(width 0.0635)
			(type default)
		)
		(layer "F.Cu")
	)
	(gr_line
		(start 357.463598 -130.44805)
		(end 357.590598 -130.57505)
		(stroke
			(width 0.0635)
			(type default)
		)
		(layer "F.Cu")
	)
	(gr_line
		(start 357.463598 -130.2131)
		(end 357.463598 -130.44805)
		(stroke
			(width 0.0635)
			(type default)
		)
		(layer "F.Cu")
	)
	(gr_line
		(start 357.463598 -129.43205)
		(end 357.463598 -129.667)
		(stroke
			(width 0.0635)
			(type default)
		)
		(layer "F.Cu")
	)
	(gr_line
		(start 357.463598 -129.43205)
		(end 357.590598 -129.30505)
		(stroke
			(width 0.0635)
			(type default)
		)
		(layer "F.Cu")
	)
	(gr_line
		(start 357.463598 -19.258026)
		(end 357.590598 -19.385026)
		(stroke
			(width 0.0635)
			(type default)
		)
		(layer "F.Cu")
	)
	(gr_line
		(start 357.463598 -19.023076)
		(end 357.463598 -19.258026)
		(stroke
			(width 0.0635)
			(type default)
		)
		(layer "F.Cu")
	)
	(gr_line
		(start 357.463598 -18.242026)
		(end 357.463598 -18.476976)
		(stroke
			(width 0.0635)
			(type default)
		)
		(layer "F.Cu")
	)
	(gr_line
		(start 357.463598 -18.242026)
		(end 357.590598 -18.115026)
		(stroke
			(width 0.0635)
			(type default)
		)
		(layer "F.Cu")
	)
	(gr_line
		(start 357.463598 -15.448026)
		(end 357.590598 -15.575026)
		(stroke
			(width 0.0635)
			(type default)
		)
		(layer "F.Cu")
	)
	(gr_line
		(start 357.463598 -15.213076)
		(end 357.463598 -15.448026)
		(stroke
			(width 0.0635)
			(type default)
		)
		(layer "F.Cu")
	)
	(gr_line
		(start 357.463598 -14.432026)
		(end 357.463598 -14.666976)
		(stroke
			(width 0.0635)
			(type default)
		)
		(layer "F.Cu")
	)
	(gr_line
		(start 357.463598 -14.432026)
		(end 357.590598 -14.305026)
		(stroke
			(width 0.0635)
			(type default)
		)
		(layer "F.Cu")
	)
	(gr_line
		(start 357.590598 -249.385074)
		(end 358.925114 -249.385074)
		(stroke
			(width 0.0635)
			(type default)
		)
		(layer "F.Cu")
	)
	(gr_line
		(start 357.590598 -248.115074)
		(end 358.925114 -248.115074)
		(stroke
			(width 0.0635)
			(type default)
		)
		(layer "F.Cu")
	)
	(gr_line
		(start 357.590598 -245.575074)
		(end 358.925114 -245.575074)
		(stroke
			(width 0.0635)
			(type default)
		)
		(layer "F.Cu")
	)
	(gr_line
		(start 357.590598 -244.305074)
		(end 358.925114 -244.305074)
		(stroke
			(width 0.0635)
			(type default)
		)
		(layer "F.Cu")
	)
	(gr_line
		(start 357.590598 -134.38505)
		(end 358.925114 -134.38505)
		(stroke
			(width 0.0635)
			(type default)
		)
		(layer "F.Cu")
	)
	(gr_line
		(start 357.590598 -133.11505)
		(end 358.925114 -133.11505)
		(stroke
			(width 0.0635)
			(type default)
		)
		(layer "F.Cu")
	)
	(gr_line
		(start 357.590598 -130.57505)
		(end 358.925114 -130.57505)
		(stroke
			(width 0.0635)
			(type default)
		)
		(layer "F.Cu")
	)
	(gr_line
		(start 357.590598 -129.30505)
		(end 358.925114 -129.30505)
		(stroke
			(width 0.0635)
			(type default)
		)
		(layer "F.Cu")
	)
	(gr_line
		(start 357.590598 -19.385026)
		(end 358.925114 -19.385026)
		(stroke
			(width 0.0635)
			(type default)
		)
		(layer "F.Cu")
	)
	(gr_line
		(start 357.590598 -18.115026)
		(end 358.925114 -18.115026)
		(stroke
			(width 0.0635)
			(type default)
		)
		(layer "F.Cu")
	)
	(gr_line
		(start 357.590598 -15.575026)
		(end 358.925114 -15.575026)
		(stroke
			(width 0.0635)
			(type default)
		)
		(layer "F.Cu")
	)
	(gr_line
		(start 357.590598 -14.305026)
		(end 358.925114 -14.305026)
		(stroke
			(width 0.0635)
			(type default)
		)
		(layer "F.Cu")
	)
	(gr_line
		(start 382.31445 -128.627124)
		(end 382.576324 -128.627124)
		(stroke
			(width 0.0635)
			(type default)
		)
		(layer "F.Cu")
	)
	(gr_line
		(start 382.31445 -13.6271)
		(end 382.5875 -13.6271)
		(stroke
			(width 0.0635)
			(type default)
		)
		(layer "F.Cu")
	)
	(gr_line
		(start 382.49225 -245.216934)
		(end 382.49225 -245.445534)
		(stroke
			(width 0.0635)
			(type default)
		)
		(layer "F.Cu")
	)
	(gr_arc
		(start 382.49225 -244.531134)
		(mid 382.549918 -244.670306)
		(end 382.6891 -244.727984)
		(stroke
			(width 0.0635)
			(type default)
		)
		(layer "F.Cu")
	)
	(gr_line
		(start 382.49225 -244.302534)
		(end 382.49225 -244.531134)
		(stroke
			(width 0.0635)
			(type default)
		)
		(layer "F.Cu")
	)
	(gr_arc
		(start 382.6891 -245.020084)
		(mid 382.549906 -245.07774)
		(end 382.49225 -245.216934)
		(stroke
			(width 0.0635)
			(type default)
		)
		(layer "F.Cu")
	)
	(gr_arc
		(start 382.7399 -128.7907)
		(mid 382.69199 -128.675034)
		(end 382.576324 -128.627124)
		(stroke
			(width 0.0635)
			(type default)
		)
		(layer "F.Cu")
	)
	(gr_arc
		(start 382.7399 -13.7795)
		(mid 382.695263 -13.671737)
		(end 382.5875 -13.6271)
		(stroke
			(width 0.0635)
			(type default)
		)
		(layer "F.Cu")
	)
	(gr_arc
		(start 383.1844 -13.6271)
		(mid 383.076637 -13.671737)
		(end 383.032 -13.7795)
		(stroke
			(width 0.0635)
			(type default)
		)
		(layer "F.Cu")
	)
	(gr_line
		(start 383.1844 -13.6271)
		(end 383.45745 -13.6271)
		(stroke
			(width 0.0635)
			(type default)
		)
		(layer "F.Cu")
	)
	(gr_arc
		(start 383.195576 -128.627124)
		(mid 383.079926 -128.675043)
		(end 383.032 -128.7907)
		(stroke
			(width 0.0635)
			(type default)
		)
		(layer "F.Cu")
	)
	(gr_line
		(start 383.195576 -128.627124)
		(end 383.45745 -128.627124)
		(stroke
			(width 0.0635)
			(type default)
		)
		(layer "F.Cu")
	)
	(gr_line
		(start 383.904236 -14.999716)
		(end 384.123946 -15.219426)
		(stroke
			(width 0.0635)
			(type default)
		)
		(layer "F.Cu")
	)
	(gr_line
		(start 383.927096 -245.022624)
		(end 384.123946 -245.219474)
		(stroke
			(width 0.0635)
			(type default)
		)
		(layer "F.Cu")
	)
	(gr_line
		(start 384.052826 -130.14833)
		(end 384.123946 -130.21945)
		(stroke
			(width 0.0635)
			(type default)
		)
		(layer "F.Cu")
	)
	(gr_line
		(start 384.052826 -129.73177)
		(end 384.123946 -129.66065)
		(stroke
			(width 0.0635)
			(type default)
		)
		(layer "F.Cu")
	)
	(gr_line
		(start 384.056636 -244.727984)
		(end 384.123946 -244.660674)
		(stroke
			(width 0.0635)
			(type default)
		)
		(layer "F.Cu")
	)
	(gr_line
		(start 384.079496 -14.705076)
		(end 384.123946 -14.660626)
		(stroke
			(width 0.0635)
			(type default)
		)
		(layer "F.Cu")
	)
	(gr_line
		(start 384.123946 -245.219474)
		(end 384.455162 -245.219474)
		(stroke
			(width 0.0635)
			(type default)
		)
		(layer "F.Cu")
	)
	(gr_line
		(start 384.123946 -244.660674)
		(end 384.455162 -244.660674)
		(stroke
			(width 0.0635)
			(type default)
		)
		(layer "F.Cu")
	)
	(gr_line
		(start 384.123946 -130.21945)
		(end 384.455162 -130.21945)
		(stroke
			(width 0.0635)
			(type default)
		)
		(layer "F.Cu")
	)
	(gr_line
		(start 384.123946 -129.66065)
		(end 384.455162 -129.66065)
		(stroke
			(width 0.0635)
			(type default)
		)
		(layer "F.Cu")
	)
	(gr_line
		(start 384.123946 -15.219426)
		(end 384.455162 -15.219426)
		(stroke
			(width 0.0635)
			(type default)
		)
		(layer "F.Cu")
	)
	(gr_line
		(start 384.123946 -14.660626)
		(end 384.455162 -14.660626)
		(stroke
			(width 0.0635)
			(type default)
		)
		(layer "F.Cu")
	)
	(gr_line
		(start 385.013962 -245.219474)
		(end 385.386326 -245.219474)
		(stroke
			(width 0.0635)
			(type default)
		)
		(layer "F.Cu")
	)
	(gr_line
		(start 385.013962 -244.660674)
		(end 385.402074 -244.660674)
		(stroke
			(width 0.0635)
			(type default)
		)
		(layer "F.Cu")
	)
	(gr_line
		(start 385.013962 -130.21945)
		(end 385.377944 -130.21945)
		(stroke
			(width 0.0635)
			(type default)
		)
		(layer "F.Cu")
	)
	(gr_line
		(start 385.013962 -129.66065)
		(end 385.38531 -129.66065)
		(stroke
			(width 0.0635)
			(type default)
		)
		(layer "F.Cu")
	)
	(gr_line
		(start 385.013962 -15.219426)
		(end 385.4069 -15.219426)
		(stroke
			(width 0.0635)
			(type default)
		)
		(layer "F.Cu")
	)
	(gr_line
		(start 385.013962 -14.660626)
		(end 385.382008 -14.660626)
		(stroke
			(width 0.0635)
			(type default)
		)
		(layer "F.Cu")
	)
	(gr_line
		(start 385.377944 -130.21945)
		(end 385.45262 -130.144774)
		(stroke
			(width 0.0635)
			(type default)
		)
		(layer "F.Cu")
	)
	(gr_line
		(start 385.382008 -14.660626)
		(end 385.465574 -14.744192)
		(stroke
			(width 0.0635)
			(type default)
		)
		(layer "F.Cu")
	)
	(gr_line
		(start 385.38531 -129.66065)
		(end 385.45262 -129.72796)
		(stroke
			(width 0.0635)
			(type default)
		)
		(layer "F.Cu")
	)
	(gr_line
		(start 385.386326 -245.219474)
		(end 385.46532 -245.14048)
		(stroke
			(width 0.0635)
			(type default)
		)
		(layer "F.Cu")
	)
	(gr_line
		(start 385.402074 -244.660674)
		(end 385.46532 -244.72392)
		(stroke
			(width 0.0635)
			(type default)
		)
		(layer "F.Cu")
	)
	(gr_line
		(start 385.4069 -15.219426)
		(end 385.465574 -15.160752)
		(stroke
			(width 0.0635)
			(type default)
		)
		(layer "F.Cu")
	)
	(gr_line
		(start 385.78155 -132.437124)
		(end 386.106924 -132.437124)
		(stroke
			(width 0.0635)
			(type default)
		)
		(layer "F.Cu")
	)
	(gr_line
		(start 385.78155 -17.4371)
		(end 386.108448 -17.4371)
		(stroke
			(width 0.0635)
			(type default)
		)
		(layer "F.Cu")
	)
	(gr_arc
		(start 386.2705 -132.6007)
		(mid 386.22259 -132.485034)
		(end 386.106924 -132.437124)
		(stroke
			(width 0.0635)
			(type default)
		)
		(layer "F.Cu")
	)
	(gr_arc
		(start 386.2705 -17.599152)
		(mid 386.223036 -17.484564)
		(end 386.108448 -17.4371)
		(stroke
			(width 0.0635)
			(type default)
		)
		(layer "F.Cu")
	)
	(gr_line
		(start 386.6896 -249.023124)
		(end 386.6896 -249.385074)
		(stroke
			(width 0.0635)
			(type default)
		)
		(layer "F.Cu")
	)
	(gr_arc
		(start 386.6896 -248.477024)
		(mid 386.726806 -248.566811)
		(end 386.8166 -248.604024)
		(stroke
			(width 0.0635)
			(type default)
		)
		(layer "F.Cu")
	)
	(gr_line
		(start 386.6896 -248.115074)
		(end 386.6896 -248.477024)
		(stroke
			(width 0.0635)
			(type default)
		)
		(layer "F.Cu")
	)
	(gr_arc
		(start 386.724652 -17.4371)
		(mid 386.610078 -17.484578)
		(end 386.5626 -17.599152)
		(stroke
			(width 0.0635)
			(type default)
		)
		(layer "F.Cu")
	)
	(gr_line
		(start 386.724652 -17.4371)
		(end 387.05155 -17.4371)
		(stroke
			(width 0.0635)
			(type default)
		)
		(layer "F.Cu")
	)
	(gr_arc
		(start 386.726176 -132.437124)
		(mid 386.610526 -132.485043)
		(end 386.5626 -132.6007)
		(stroke
			(width 0.0635)
			(type default)
		)
		(layer "F.Cu")
	)
	(gr_line
		(start 386.726176 -132.437124)
		(end 387.05155 -132.437124)
		(stroke
			(width 0.0635)
			(type default)
		)
		(layer "F.Cu")
	)
	(gr_arc
		(start 386.8166 -248.896124)
		(mid 386.726797 -248.933321)
		(end 386.6896 -249.023124)
		(stroke
			(width 0.0635)
			(type default)
		)
		(layer "F.Cu")
	)
	(gr_line
		(start 388.943342 -248.963942)
		(end 389.013446 -249.034046)
		(stroke
			(width 0.0635)
			(type default)
		)
		(layer "F.Cu")
	)
	(gr_line
		(start 388.943342 -248.547128)
		(end 389.013446 -248.477024)
		(stroke
			(width 0.0635)
			(type default)
		)
		(layer "F.Cu")
	)
	(gr_line
		(start 388.948676 -245.148354)
		(end 389.013446 -245.213124)
		(stroke
			(width 0.0635)
			(type default)
		)
		(layer "F.Cu")
	)
	(gr_line
		(start 388.948676 -244.731794)
		(end 389.013446 -244.667024)
		(stroke
			(width 0.0635)
			(type default)
		)
		(layer "F.Cu")
	)
	(gr_line
		(start 388.948676 -133.95833)
		(end 389.013446 -134.0231)
		(stroke
			(width 0.0635)
			(type default)
		)
		(layer "F.Cu")
	)
	(gr_line
		(start 388.948676 -133.54177)
		(end 389.013446 -133.477)
		(stroke
			(width 0.0635)
			(type default)
		)
		(layer "F.Cu")
	)
	(gr_line
		(start 388.948676 -130.14833)
		(end 389.013446 -130.2131)
		(stroke
			(width 0.0635)
			(type default)
		)
		(layer "F.Cu")
	)
	(gr_line
		(start 388.948676 -129.73177)
		(end 389.013446 -129.667)
		(stroke
			(width 0.0635)
			(type default)
		)
		(layer "F.Cu")
	)
	(gr_line
		(start 388.948676 -15.148306)
		(end 389.013446 -15.213076)
		(stroke
			(width 0.0635)
			(type default)
		)
		(layer "F.Cu")
	)
	(gr_line
		(start 388.948676 -14.731746)
		(end 389.013446 -14.666976)
		(stroke
			(width 0.0635)
			(type default)
		)
		(layer "F.Cu")
	)
	(gr_line
		(start 388.954518 -18.952718)
		(end 389.013446 -19.011646)
		(stroke
			(width 0.0635)
			(type default)
		)
		(layer "F.Cu")
	)
	(gr_line
		(start 388.954518 -18.535904)
		(end 389.013446 -18.476976)
		(stroke
			(width 0.0635)
			(type default)
		)
		(layer "F.Cu")
	)
	(gr_line
		(start 389.013446 -249.258074)
		(end 389.140446 -249.385074)
		(stroke
			(width 0.0635)
			(type default)
		)
		(layer "F.Cu")
	)
	(gr_line
		(start 389.013446 -249.034046)
		(end 389.013446 -249.258074)
		(stroke
			(width 0.0635)
			(type default)
		)
		(layer "F.Cu")
	)
	(gr_line
		(start 389.013446 -248.221754)
		(end 389.013446 -248.477024)
		(stroke
			(width 0.0635)
			(type default)
		)
		(layer "F.Cu")
	)
	(gr_line
		(start 389.013446 -248.221754)
		(end 389.120126 -248.115074)
		(stroke
			(width 0.0635)
			(type default)
		)
		(layer "F.Cu")
	)
	(gr_line
		(start 389.013446 -245.448074)
		(end 389.140446 -245.575074)
		(stroke
			(width 0.0635)
			(type default)
		)
		(layer "F.Cu")
	)
	(gr_line
		(start 389.013446 -245.213124)
		(end 389.013446 -245.448074)
		(stroke
			(width 0.0635)
			(type default)
		)
		(layer "F.Cu")
	)
	(gr_line
		(start 389.013446 -244.432074)
		(end 389.013446 -244.667024)
		(stroke
			(width 0.0635)
			(type default)
		)
		(layer "F.Cu")
	)
	(gr_line
		(start 389.013446 -244.432074)
		(end 389.140446 -244.305074)
		(stroke
			(width 0.0635)
			(type default)
		)
		(layer "F.Cu")
	)
	(gr_line
		(start 389.013446 -134.25805)
		(end 389.140446 -134.38505)
		(stroke
			(width 0.0635)
			(type default)
		)
		(layer "F.Cu")
	)
	(gr_line
		(start 389.013446 -134.0231)
		(end 389.013446 -134.25805)
		(stroke
			(width 0.0635)
			(type default)
		)
		(layer "F.Cu")
	)
	(gr_line
		(start 389.013446 -133.24205)
		(end 389.013446 -133.477)
		(stroke
			(width 0.0635)
			(type default)
		)
		(layer "F.Cu")
	)
	(gr_line
		(start 389.013446 -133.24205)
		(end 389.140446 -133.11505)
		(stroke
			(width 0.0635)
			(type default)
		)
		(layer "F.Cu")
	)
	(gr_line
		(start 389.013446 -130.44805)
		(end 389.140446 -130.57505)
		(stroke
			(width 0.0635)
			(type default)
		)
		(layer "F.Cu")
	)
	(gr_line
		(start 389.013446 -130.2131)
		(end 389.013446 -130.44805)
		(stroke
			(width 0.0635)
			(type default)
		)
		(layer "F.Cu")
	)
	(gr_line
		(start 389.013446 -129.43205)
		(end 389.013446 -129.667)
		(stroke
			(width 0.0635)
			(type default)
		)
		(layer "F.Cu")
	)
	(gr_line
		(start 389.013446 -129.43205)
		(end 389.140446 -129.30505)
		(stroke
			(width 0.0635)
			(type default)
		)
		(layer "F.Cu")
	)
	(gr_line
		(start 389.013446 -19.291046)
		(end 389.107426 -19.385026)
		(stroke
			(width 0.0635)
			(type default)
		)
		(layer "F.Cu")
	)
	(gr_line
		(start 389.013446 -19.011646)
		(end 389.013446 -19.291046)
		(stroke
			(width 0.0635)
			(type default)
		)
		(layer "F.Cu")
	)
	(gr_line
		(start 389.013446 -18.242026)
		(end 389.013446 -18.476976)
		(stroke
			(width 0.0635)
			(type default)
		)
		(layer "F.Cu")
	)
	(gr_line
		(start 389.013446 -18.242026)
		(end 389.140446 -18.115026)
		(stroke
			(width 0.0635)
			(type default)
		)
		(layer "F.Cu")
	)
	(gr_line
		(start 389.013446 -15.448026)
		(end 389.140446 -15.575026)
		(stroke
			(width 0.0635)
			(type default)
		)
		(layer "F.Cu")
	)
	(gr_line
		(start 389.013446 -15.213076)
		(end 389.013446 -15.448026)
		(stroke
			(width 0.0635)
			(type default)
		)
		(layer "F.Cu")
	)
	(gr_line
		(start 389.013446 -14.432026)
		(end 389.013446 -14.666976)
		(stroke
			(width 0.0635)
			(type default)
		)
		(layer "F.Cu")
	)
	(gr_line
		(start 389.013446 -14.432026)
		(end 389.140446 -14.305026)
		(stroke
			(width 0.0635)
			(type default)
		)
		(layer "F.Cu")
	)
	(gr_line
		(start 389.107426 -19.385026)
		(end 390.474962 -19.385026)
		(stroke
			(width 0.0635)
			(type default)
		)
		(layer "F.Cu")
	)
	(gr_line
		(start 389.120126 -248.115074)
		(end 390.474962 -248.115074)
		(stroke
			(width 0.0635)
			(type default)
		)
		(layer "F.Cu")
	)
	(gr_line
		(start 389.140446 -249.385074)
		(end 390.474962 -249.385074)
		(stroke
			(width 0.0635)
			(type default)
		)
		(layer "F.Cu")
	)
	(gr_line
		(start 389.140446 -245.575074)
		(end 390.474962 -245.575074)
		(stroke
			(width 0.0635)
			(type default)
		)
		(layer "F.Cu")
	)
	(gr_line
		(start 389.140446 -244.305074)
		(end 390.474962 -244.305074)
		(stroke
			(width 0.0635)
			(type default)
		)
		(layer "F.Cu")
	)
	(gr_line
		(start 389.140446 -134.38505)
		(end 390.474962 -134.38505)
		(stroke
			(width 0.0635)
			(type default)
		)
		(layer "F.Cu")
	)
	(gr_line
		(start 389.140446 -133.11505)
		(end 390.474962 -133.11505)
		(stroke
			(width 0.0635)
			(type default)
		)
		(layer "F.Cu")
	)
	(gr_line
		(start 389.140446 -130.57505)
		(end 390.474962 -130.57505)
		(stroke
			(width 0.0635)
			(type default)
		)
		(layer "F.Cu")
	)
	(gr_line
		(start 389.140446 -129.30505)
		(end 390.474962 -129.30505)
		(stroke
			(width 0.0635)
			(type default)
		)
		(layer "F.Cu")
	)
	(gr_line
		(start 389.140446 -18.115026)
		(end 390.474962 -18.115026)
		(stroke
			(width 0.0635)
			(type default)
		)
		(layer "F.Cu")
	)
	(gr_line
		(start 389.140446 -15.575026)
		(end 390.474962 -15.575026)
		(stroke
			(width 0.0635)
			(type default)
		)
		(layer "F.Cu")
	)
	(gr_line
		(start 389.140446 -14.305026)
		(end 390.474962 -14.305026)
		(stroke
			(width 0.0635)
			(type default)
		)
		(layer "F.Cu")
	)
	(gr_line
		(start 413.864552 -128.627124)
		(end 414.148524 -128.627124)
		(stroke
			(width 0.0635)
			(type default)
		)
		(layer "F.Cu")
	)
	(gr_line
		(start 413.864552 -13.6271)
		(end 414.1343 -13.6271)
		(stroke
			(width 0.0635)
			(type default)
		)
		(layer "F.Cu")
	)
	(gr_line
		(start 414.042352 -245.328948)
		(end 414.042352 -245.587774)
		(stroke
			(width 0.0635)
			(type default)
		)
		(layer "F.Cu")
	)
	(gr_arc
		(start 414.042352 -244.7036)
		(mid 414.091154 -244.821429)
		(end 414.208976 -244.870224)
		(stroke
			(width 0.0635)
			(type default)
		)
		(layer "F.Cu")
	)
	(gr_line
		(start 414.042352 -244.444774)
		(end 414.042352 -244.7036)
		(stroke
			(width 0.0635)
			(type default)
		)
		(layer "F.Cu")
	)
	(gr_arc
		(start 414.208976 -245.162324)
		(mid 414.091155 -245.211127)
		(end 414.042352 -245.328948)
		(stroke
			(width 0.0635)
			(type default)
		)
		(layer "F.Cu")
	)
	(gr_arc
		(start 414.290002 -128.768602)
		(mid 414.248564 -128.668562)
		(end 414.148524 -128.627124)
		(stroke
			(width 0.0635)
			(type default)
		)
		(layer "F.Cu")
	)
	(gr_arc
		(start 414.290002 -13.782802)
		(mid 414.244398 -13.672704)
		(end 414.1343 -13.6271)
		(stroke
			(width 0.0635)
			(type default)
		)
		(layer "F.Cu")
	)
	(gr_arc
		(start 414.72358 -128.627124)
		(mid 414.623554 -128.668569)
		(end 414.582102 -128.768602)
		(stroke
			(width 0.0635)
			(type default)
		)
		(layer "F.Cu")
	)
	(gr_line
		(start 414.72358 -128.627124)
		(end 415.007552 -128.627124)
		(stroke
			(width 0.0635)
			(type default)
		)
		(layer "F.Cu")
	)
	(gr_arc
		(start 414.737804 -13.6271)
		(mid 414.627704 -13.672703)
		(end 414.582102 -13.782802)
		(stroke
			(width 0.0635)
			(type default)
		)
		(layer "F.Cu")
	)
	(gr_line
		(start 414.737804 -13.6271)
		(end 415.007552 -13.6271)
		(stroke
			(width 0.0635)
			(type default)
		)
		(layer "F.Cu")
	)
	(gr_line
		(start 415.413444 -244.867684)
		(end 415.620454 -244.660674)
		(stroke
			(width 0.0635)
			(type default)
		)
		(layer "F.Cu")
	)
	(gr_line
		(start 415.579052 -245.162324)
		(end 415.636202 -245.219474)
		(stroke
			(width 0.0635)
			(type default)
		)
		(layer "F.Cu")
	)
	(gr_line
		(start 415.602928 -130.14833)
		(end 415.674048 -130.21945)
		(stroke
			(width 0.0635)
			(type default)
		)
		(layer "F.Cu")
	)
	(gr_line
		(start 415.602928 -129.73177)
		(end 415.674048 -129.66065)
		(stroke
			(width 0.0635)
			(type default)
		)
		(layer "F.Cu")
	)
	(gr_line
		(start 415.602928 -15.148306)
		(end 415.674048 -15.219426)
		(stroke
			(width 0.0635)
			(type default)
		)
		(layer "F.Cu")
	)
	(gr_line
		(start 415.602928 -14.731746)
		(end 415.674048 -14.660626)
		(stroke
			(width 0.0635)
			(type default)
		)
		(layer "F.Cu")
	)
	(gr_line
		(start 415.620454 -244.660674)
		(end 416.005264 -244.660674)
		(stroke
			(width 0.0635)
			(type default)
		)
		(layer "F.Cu")
	)
	(gr_line
		(start 415.636202 -245.219474)
		(end 416.005264 -245.219474)
		(stroke
			(width 0.0635)
			(type default)
		)
		(layer "F.Cu")
	)
	(gr_line
		(start 415.674048 -130.21945)
		(end 416.005264 -130.21945)
		(stroke
			(width 0.0635)
			(type default)
		)
		(layer "F.Cu")
	)
	(gr_line
		(start 415.674048 -129.66065)
		(end 416.005264 -129.66065)
		(stroke
			(width 0.0635)
			(type default)
		)
		(layer "F.Cu")
	)
	(gr_line
		(start 415.674048 -15.219426)
		(end 416.005264 -15.219426)
		(stroke
			(width 0.0635)
			(type default)
		)
		(layer "F.Cu")
	)
	(gr_line
		(start 415.674048 -14.660626)
		(end 416.005264 -14.660626)
		(stroke
			(width 0.0635)
			(type default)
		)
		(layer "F.Cu")
	)
	(gr_line
		(start 416.564064 -245.219474)
		(end 416.933126 -245.219474)
		(stroke
			(width 0.0635)
			(type default)
		)
		(layer "F.Cu")
	)
	(gr_line
		(start 416.564064 -244.660674)
		(end 416.948874 -244.660674)
		(stroke
			(width 0.0635)
			(type default)
		)
		(layer "F.Cu")
	)
	(gr_line
		(start 416.564064 -130.21945)
		(end 416.929316 -130.21945)
		(stroke
			(width 0.0635)
			(type default)
		)
		(layer "F.Cu")
	)
	(gr_line
		(start 416.564064 -129.66065)
		(end 416.927538 -129.66065)
		(stroke
			(width 0.0635)
			(type default)
		)
		(layer "F.Cu")
	)
	(gr_line
		(start 416.564064 -15.219426)
		(end 416.936174 -15.219426)
		(stroke
			(width 0.0635)
			(type default)
		)
		(layer "F.Cu")
	)
	(gr_line
		(start 416.564064 -14.660626)
		(end 416.920426 -14.660626)
		(stroke
			(width 0.0635)
			(type default)
		)
		(layer "F.Cu")
	)
	(gr_line
		(start 416.920426 -14.660626)
		(end 416.99942 -14.73962)
		(stroke
			(width 0.0635)
			(type default)
		)
		(layer "F.Cu")
	)
	(gr_line
		(start 416.927538 -129.66065)
		(end 416.99942 -129.732532)
		(stroke
			(width 0.0635)
			(type default)
		)
		(layer "F.Cu")
	)
	(gr_line
		(start 416.929316 -130.21945)
		(end 416.99942 -130.149346)
		(stroke
			(width 0.0635)
			(type default)
		)
		(layer "F.Cu")
	)
	(gr_line
		(start 416.933126 -245.219474)
		(end 417.01212 -245.14048)
		(stroke
			(width 0.0635)
			(type default)
		)
		(layer "F.Cu")
	)
	(gr_line
		(start 416.936174 -15.219426)
		(end 416.99942 -15.15618)
		(stroke
			(width 0.0635)
			(type default)
		)
		(layer "F.Cu")
	)
	(gr_line
		(start 416.948874 -244.660674)
		(end 417.01212 -244.72392)
		(stroke
			(width 0.0635)
			(type default)
		)
		(layer "F.Cu")
	)
	(gr_line
		(start 417.331652 -132.437124)
		(end 417.669726 -132.437124)
		(stroke
			(width 0.0635)
			(type default)
		)
		(layer "F.Cu")
	)
	(gr_line
		(start 417.331652 -17.4371)
		(end 417.65855 -17.4371)
		(stroke
			(width 0.0635)
			(type default)
		)
		(layer "F.Cu")
	)
	(gr_arc
		(start 417.820602 -132.588)
		(mid 417.776411 -132.481315)
		(end 417.669726 -132.437124)
		(stroke
			(width 0.0635)
			(type default)
		)
		(layer "F.Cu")
	)
	(gr_arc
		(start 417.820602 -17.599152)
		(mid 417.773138 -17.484564)
		(end 417.65855 -17.4371)
		(stroke
			(width 0.0635)
			(type default)
		)
		(layer "F.Cu")
	)
	(gr_line
		(start 418.239702 -249.023124)
		(end 418.239702 -249.385074)
		(stroke
			(width 0.0635)
			(type default)
		)
		(layer "F.Cu")
	)
	(gr_arc
		(start 418.239702 -248.477024)
		(mid 418.276908 -248.56681)
		(end 418.366702 -248.604024)
		(stroke
			(width 0.0635)
			(type default)
		)
		(layer "F.Cu")
	)
	(gr_line
		(start 418.239702 -248.115074)
		(end 418.239702 -248.477024)
		(stroke
			(width 0.0635)
			(type default)
		)
		(layer "F.Cu")
	)
	(gr_arc
		(start 418.263578 -132.437124)
		(mid 418.156907 -132.481322)
		(end 418.112702 -132.588)
		(stroke
			(width 0.0635)
			(type default)
		)
		(layer "F.Cu")
	)
	(gr_line
		(start 418.263578 -132.437124)
		(end 418.601652 -132.437124)
		(stroke
			(width 0.0635)
			(type default)
		)
		(layer "F.Cu")
	)
	(gr_arc
		(start 418.274754 -17.4371)
		(mid 418.160179 -17.484577)
		(end 418.112702 -17.599152)
		(stroke
			(width 0.0635)
			(type default)
		)
		(layer "F.Cu")
	)
	(gr_line
		(start 418.274754 -17.4371)
		(end 418.601652 -17.4371)
		(stroke
			(width 0.0635)
			(type default)
		)
		(layer "F.Cu")
	)
	(gr_arc
		(start 418.366702 -248.896124)
		(mid 418.276899 -248.933321)
		(end 418.239702 -249.023124)
		(stroke
			(width 0.0635)
			(type default)
		)
		(layer "F.Cu")
	)
	(gr_line
		(start 420.498778 -245.148354)
		(end 420.563548 -245.213124)
		(stroke
			(width 0.0635)
			(type default)
		)
		(layer "F.Cu")
	)
	(gr_line
		(start 420.498778 -244.731794)
		(end 420.563548 -244.667024)
		(stroke
			(width 0.0635)
			(type default)
		)
		(layer "F.Cu")
	)
	(gr_line
		(start 420.498778 -130.14833)
		(end 420.563548 -130.2131)
		(stroke
			(width 0.0635)
			(type default)
		)
		(layer "F.Cu")
	)
	(gr_line
		(start 420.498778 -129.73177)
		(end 420.563548 -129.667)
		(stroke
			(width 0.0635)
			(type default)
		)
		(layer "F.Cu")
	)
	(gr_line
		(start 420.498778 -18.958306)
		(end 420.563548 -19.023076)
		(stroke
			(width 0.0635)
			(type default)
		)
		(layer "F.Cu")
	)
	(gr_line
		(start 420.498778 -18.541746)
		(end 420.563548 -18.476976)
		(stroke
			(width 0.0635)
			(type default)
		)
		(layer "F.Cu")
	)
	(gr_line
		(start 420.498778 -15.148306)
		(end 420.563548 -15.213076)
		(stroke
			(width 0.0635)
			(type default)
		)
		(layer "F.Cu")
	)
	(gr_line
		(start 420.498778 -14.731746)
		(end 420.563548 -14.666976)
		(stroke
			(width 0.0635)
			(type default)
		)
		(layer "F.Cu")
	)
	(gr_line
		(start 420.50208 -248.97588)
		(end 420.563548 -249.037348)
		(stroke
			(width 0.0635)
			(type default)
		)
		(layer "F.Cu")
	)
	(gr_line
		(start 420.50208 -248.55932)
		(end 420.563548 -248.497852)
		(stroke
			(width 0.0635)
			(type default)
		)
		(layer "F.Cu")
	)
	(gr_line
		(start 420.509954 -133.947154)
		(end 420.563548 -134.000748)
		(stroke
			(width 0.0635)
			(type default)
		)
		(layer "F.Cu")
	)
	(gr_line
		(start 420.509954 -133.530594)
		(end 420.563548 -133.477)
		(stroke
			(width 0.0635)
			(type default)
		)
		(layer "F.Cu")
	)
	(gr_line
		(start 420.563548 -249.258074)
		(end 420.690548 -249.385074)
		(stroke
			(width 0.0635)
			(type default)
		)
		(layer "F.Cu")
	)
	(gr_line
		(start 420.563548 -249.037348)
		(end 420.563548 -249.258074)
		(stroke
			(width 0.0635)
			(type default)
		)
		(layer "F.Cu")
	)
	(gr_line
		(start 420.563548 -248.242074)
		(end 420.563548 -248.497852)
		(stroke
			(width 0.0635)
			(type default)
		)
		(layer "F.Cu")
	)
	(gr_line
		(start 420.563548 -248.242074)
		(end 420.690548 -248.115074)
		(stroke
			(width 0.0635)
			(type default)
		)
		(layer "F.Cu")
	)
	(gr_line
		(start 420.563548 -245.448074)
		(end 420.690548 -245.575074)
		(stroke
			(width 0.0635)
			(type default)
		)
		(layer "F.Cu")
	)
	(gr_line
		(start 420.563548 -245.213124)
		(end 420.563548 -245.448074)
		(stroke
			(width 0.0635)
			(type default)
		)
		(layer "F.Cu")
	)
	(gr_line
		(start 420.563548 -244.432074)
		(end 420.563548 -244.667024)
		(stroke
			(width 0.0635)
			(type default)
		)
		(layer "F.Cu")
	)
	(gr_line
		(start 420.563548 -244.432074)
		(end 420.690548 -244.305074)
		(stroke
			(width 0.0635)
			(type default)
		)
		(layer "F.Cu")
	)
	(gr_line
		(start 420.563548 -134.25805)
		(end 420.690548 -134.38505)
		(stroke
			(width 0.0635)
			(type default)
		)
		(layer "F.Cu")
	)
	(gr_line
		(start 420.563548 -134.000748)
		(end 420.563548 -134.25805)
		(stroke
			(width 0.0635)
			(type default)
		)
		(layer "F.Cu")
	)
	(gr_line
		(start 420.563548 -133.24205)
		(end 420.563548 -133.477)
		(stroke
			(width 0.0635)
			(type default)
		)
		(layer "F.Cu")
	)
	(gr_line
		(start 420.563548 -133.24205)
		(end 420.690548 -133.11505)
		(stroke
			(width 0.0635)
			(type default)
		)
		(layer "F.Cu")
	)
	(gr_line
		(start 420.563548 -130.44805)
		(end 420.690548 -130.57505)
		(stroke
			(width 0.0635)
			(type default)
		)
		(layer "F.Cu")
	)
	(gr_line
		(start 420.563548 -130.2131)
		(end 420.563548 -130.44805)
		(stroke
			(width 0.0635)
			(type default)
		)
		(layer "F.Cu")
	)
	(gr_line
		(start 420.563548 -129.43205)
		(end 420.563548 -129.667)
		(stroke
			(width 0.0635)
			(type default)
		)
		(layer "F.Cu")
	)
	(gr_line
		(start 420.563548 -129.43205)
		(end 420.690548 -129.30505)
		(stroke
			(width 0.0635)
			(type default)
		)
		(layer "F.Cu")
	)
	(gr_line
		(start 420.563548 -19.258026)
		(end 420.690548 -19.385026)
		(stroke
			(width 0.0635)
			(type default)
		)
		(layer "F.Cu")
	)
	(gr_line
		(start 420.563548 -19.023076)
		(end 420.563548 -19.258026)
		(stroke
			(width 0.0635)
			(type default)
		)
		(layer "F.Cu")
	)
	(gr_line
		(start 420.563548 -18.242026)
		(end 420.563548 -18.476976)
		(stroke
			(width 0.0635)
			(type default)
		)
		(layer "F.Cu")
	)
	(gr_line
		(start 420.563548 -18.242026)
		(end 420.690548 -18.115026)
		(stroke
			(width 0.0635)
			(type default)
		)
		(layer "F.Cu")
	)
	(gr_line
		(start 420.563548 -15.448026)
		(end 420.690548 -15.575026)
		(stroke
			(width 0.0635)
			(type default)
		)
		(layer "F.Cu")
	)
	(gr_line
		(start 420.563548 -15.213076)
		(end 420.563548 -15.448026)
		(stroke
			(width 0.0635)
			(type default)
		)
		(layer "F.Cu")
	)
	(gr_line
		(start 420.563548 -14.432026)
		(end 420.563548 -14.666976)
		(stroke
			(width 0.0635)
			(type default)
		)
		(layer "F.Cu")
	)
	(gr_line
		(start 420.563548 -14.432026)
		(end 420.690548 -14.305026)
		(stroke
			(width 0.0635)
			(type default)
		)
		(layer "F.Cu")
	)
	(gr_line
		(start 420.690548 -249.385074)
		(end 422.025064 -249.385074)
		(stroke
			(width 0.0635)
			(type default)
		)
		(layer "F.Cu")
	)
	(gr_line
		(start 420.690548 -248.115074)
		(end 422.025064 -248.115074)
		(stroke
			(width 0.0635)
			(type default)
		)
		(layer "F.Cu")
	)
	(gr_line
		(start 420.690548 -245.575074)
		(end 422.025064 -245.575074)
		(stroke
			(width 0.0635)
			(type default)
		)
		(layer "F.Cu")
	)
	(gr_line
		(start 420.690548 -244.305074)
		(end 422.025064 -244.305074)
		(stroke
			(width 0.0635)
			(type default)
		)
		(layer "F.Cu")
	)
	(gr_line
		(start 420.690548 -134.38505)
		(end 422.025064 -134.38505)
		(stroke
			(width 0.0635)
			(type default)
		)
		(layer "F.Cu")
	)
	(gr_line
		(start 420.690548 -133.11505)
		(end 422.025064 -133.11505)
		(stroke
			(width 0.0635)
			(type default)
		)
		(layer "F.Cu")
	)
	(gr_line
		(start 420.690548 -130.57505)
		(end 422.025064 -130.57505)
		(stroke
			(width 0.0635)
			(type default)
		)
		(layer "F.Cu")
	)
	(gr_line
		(start 420.690548 -129.30505)
		(end 422.025064 -129.30505)
		(stroke
			(width 0.0635)
			(type default)
		)
		(layer "F.Cu")
	)
	(gr_line
		(start 420.690548 -19.385026)
		(end 422.025064 -19.385026)
		(stroke
			(width 0.0635)
			(type default)
		)
		(layer "F.Cu")
	)
	(gr_line
		(start 420.690548 -18.115026)
		(end 422.025064 -18.115026)
		(stroke
			(width 0.0635)
			(type default)
		)
		(layer "F.Cu")
	)
	(gr_line
		(start 420.690548 -15.575026)
		(end 422.025064 -15.575026)
		(stroke
			(width 0.0635)
			(type default)
		)
		(layer "F.Cu")
	)
	(gr_line
		(start 420.690548 -14.305026)
		(end 422.025064 -14.305026)
		(stroke
			(width 0.0635)
			(type default)
		)
		(layer "F.Cu")
	)
	(gr_line
		(start 445.4144 -128.627124)
		(end 445.669924 -128.627124)
		(stroke
			(width 0.0635)
			(type default)
		)
		(layer "F.Cu")
	)
	(gr_line
		(start 445.4144 -13.6271)
		(end 445.6811 -13.6271)
		(stroke
			(width 0.0635)
			(type default)
		)
		(layer "F.Cu")
	)
	(gr_line
		(start 445.60236 -245.220744)
		(end 445.60236 -245.455694)
		(stroke
			(width 0.0635)
			(type default)
		)
		(layer "F.Cu")
	)
	(gr_arc
		(start 445.60236 -244.547644)
		(mid 445.658169 -244.682334)
		(end 445.79286 -244.738144)
		(stroke
			(width 0.0635)
			(type default)
		)
		(layer "F.Cu")
	)
	(gr_line
		(start 445.60236 -244.312694)
		(end 445.60236 -244.547644)
		(stroke
			(width 0.0635)
			(type default)
		)
		(layer "F.Cu")
	)
	(gr_arc
		(start 445.79286 -245.030244)
		(mid 445.658156 -245.08604)
		(end 445.60236 -245.220744)
		(stroke
			(width 0.0635)
			(type default)
		)
		(layer "F.Cu")
	)
	(gr_arc
		(start 445.83985 -128.79705)
		(mid 445.79008 -128.676894)
		(end 445.669924 -128.627124)
		(stroke
			(width 0.0635)
			(type default)
		)
		(layer "F.Cu")
	)
	(gr_arc
		(start 445.83985 -13.78585)
		(mid 445.793353 -13.673597)
		(end 445.6811 -13.6271)
		(stroke
			(width 0.0635)
			(type default)
		)
		(layer "F.Cu")
	)
	(gr_arc
		(start 446.2907 -13.6271)
		(mid 446.178429 -13.673594)
		(end 446.13195 -13.78585)
		(stroke
			(width 0.0635)
			(type default)
		)
		(layer "F.Cu")
	)
	(gr_line
		(start 446.2907 -13.6271)
		(end 446.5574 -13.6271)
		(stroke
			(width 0.0635)
			(type default)
		)
		(layer "F.Cu")
	)
	(gr_arc
		(start 446.301876 -128.627124)
		(mid 446.181753 -128.676906)
		(end 446.13195 -128.79705)
		(stroke
			(width 0.0635)
			(type default)
		)
		(layer "F.Cu")
	)
	(gr_line
		(start 446.301876 -128.627124)
		(end 446.5574 -128.627124)
		(stroke
			(width 0.0635)
			(type default)
		)
		(layer "F.Cu")
	)
	(gr_line
		(start 447.016886 -15.012416)
		(end 447.223896 -15.219426)
		(stroke
			(width 0.0635)
			(type default)
		)
		(layer "F.Cu")
	)
	(gr_line
		(start 447.120264 -245.15064)
		(end 447.189098 -245.219474)
		(stroke
			(width 0.0635)
			(type default)
		)
		(layer "F.Cu")
	)
	(gr_line
		(start 447.120264 -244.73408)
		(end 447.19367 -244.660674)
		(stroke
			(width 0.0635)
			(type default)
		)
		(layer "F.Cu")
	)
	(gr_line
		(start 447.152776 -130.14833)
		(end 447.223896 -130.21945)
		(stroke
			(width 0.0635)
			(type default)
		)
		(layer "F.Cu")
	)
	(gr_line
		(start 447.152776 -129.73177)
		(end 447.223896 -129.66065)
		(stroke
			(width 0.0635)
			(type default)
		)
		(layer "F.Cu")
	)
	(gr_line
		(start 447.166746 -14.717776)
		(end 447.223896 -14.660626)
		(stroke
			(width 0.0635)
			(type default)
		)
		(layer "F.Cu")
	)
	(gr_line
		(start 447.189098 -245.219474)
		(end 447.555112 -245.219474)
		(stroke
			(width 0.0635)
			(type default)
		)
		(layer "F.Cu")
	)
	(gr_line
		(start 447.19367 -244.660674)
		(end 447.555112 -244.660674)
		(stroke
			(width 0.0635)
			(type default)
		)
		(layer "F.Cu")
	)
	(gr_line
		(start 447.223896 -130.21945)
		(end 447.555112 -130.21945)
		(stroke
			(width 0.0635)
			(type default)
		)
		(layer "F.Cu")
	)
	(gr_line
		(start 447.223896 -129.66065)
		(end 447.555112 -129.66065)
		(stroke
			(width 0.0635)
			(type default)
		)
		(layer "F.Cu")
	)
	(gr_line
		(start 447.223896 -15.219426)
		(end 447.555112 -15.219426)
		(stroke
			(width 0.0635)
			(type default)
		)
		(layer "F.Cu")
	)
	(gr_line
		(start 447.223896 -14.660626)
		(end 447.555112 -14.660626)
		(stroke
			(width 0.0635)
			(type default)
		)
		(layer "F.Cu")
	)
	(gr_line
		(start 448.113912 -245.219474)
		(end 448.479926 -245.219474)
		(stroke
			(width 0.0635)
			(type default)
		)
		(layer "F.Cu")
	)
	(gr_line
		(start 448.113912 -244.660674)
		(end 448.470274 -244.660674)
		(stroke
			(width 0.0635)
			(type default)
		)
		(layer "F.Cu")
	)
	(gr_line
		(start 448.113912 -130.21945)
		(end 448.492118 -130.21945)
		(stroke
			(width 0.0635)
			(type default)
		)
		(layer "F.Cu")
	)
	(gr_line
		(start 448.113912 -129.66065)
		(end 448.470274 -129.66065)
		(stroke
			(width 0.0635)
			(type default)
		)
		(layer "F.Cu")
	)
	(gr_line
		(start 448.113912 -15.219426)
		(end 448.545966 -15.219426)
		(stroke
			(width 0.0635)
			(type default)
		)
		(layer "F.Cu")
	)
	(gr_line
		(start 448.113912 -14.660626)
		(end 448.525138 -14.660626)
		(stroke
			(width 0.0635)
			(type default)
		)
		(layer "F.Cu")
	)
	(gr_line
		(start 448.470274 -244.660674)
		(end 448.54622 -244.73662)
		(stroke
			(width 0.0635)
			(type default)
		)
		(layer "F.Cu")
	)
	(gr_line
		(start 448.470274 -129.66065)
		(end 448.552316 -129.742692)
		(stroke
			(width 0.0635)
			(type default)
		)
		(layer "F.Cu")
	)
	(gr_line
		(start 448.479926 -245.219474)
		(end 448.54622 -245.15318)
		(stroke
			(width 0.0635)
			(type default)
		)
		(layer "F.Cu")
	)
	(gr_line
		(start 448.492118 -130.21945)
		(end 448.552316 -130.159252)
		(stroke
			(width 0.0635)
			(type default)
		)
		(layer "F.Cu")
	)
	(gr_line
		(start 448.525138 -14.660626)
		(end 448.606672 -14.74216)
		(stroke
			(width 0.0635)
			(type default)
		)
		(layer "F.Cu")
	)
	(gr_line
		(start 448.545966 -15.219426)
		(end 448.606672 -15.15872)
		(stroke
			(width 0.0635)
			(type default)
		)
		(layer "F.Cu")
	)
	(gr_line
		(start 448.8815 -132.437124)
		(end 449.200524 -132.437124)
		(stroke
			(width 0.0635)
			(type default)
		)
		(layer "F.Cu")
	)
	(gr_line
		(start 448.8815 -17.4371)
		(end 449.208398 -17.4371)
		(stroke
			(width 0.0635)
			(type default)
		)
		(layer "F.Cu")
	)
	(gr_arc
		(start 449.37045 -132.60705)
		(mid 449.32068 -132.486894)
		(end 449.200524 -132.437124)
		(stroke
			(width 0.0635)
			(type default)
		)
		(layer "F.Cu")
	)
	(gr_arc
		(start 449.37045 -17.599152)
		(mid 449.322986 -17.484564)
		(end 449.208398 -17.4371)
		(stroke
			(width 0.0635)
			(type default)
		)
		(layer "F.Cu")
	)
	(gr_line
		(start 449.78955 -249.023124)
		(end 449.78955 -249.385074)
		(stroke
			(width 0.0635)
			(type default)
		)
		(layer "F.Cu")
	)
	(gr_arc
		(start 449.78955 -248.477024)
		(mid 449.826759 -248.566793)
		(end 449.91655 -248.604024)
		(stroke
			(width 0.0635)
			(type default)
		)
		(layer "F.Cu")
	)
	(gr_line
		(start 449.78955 -248.115074)
		(end 449.78955 -248.477024)
		(stroke
			(width 0.0635)
			(type default)
		)
		(layer "F.Cu")
	)
	(gr_arc
		(start 449.824602 -17.4371)
		(mid 449.709996 -17.48456)
		(end 449.66255 -17.599152)
		(stroke
			(width 0.0635)
			(type default)
		)
		(layer "F.Cu")
	)
	(gr_line
		(start 449.824602 -17.4371)
		(end 450.1515 -17.4371)
		(stroke
			(width 0.0635)
			(type default)
		)
		(layer "F.Cu")
	)
	(gr_arc
		(start 449.832476 -132.437124)
		(mid 449.712353 -132.486906)
		(end 449.66255 -132.60705)
		(stroke
			(width 0.0635)
			(type default)
		)
		(layer "F.Cu")
	)
	(gr_line
		(start 449.832476 -132.437124)
		(end 450.1515 -132.437124)
		(stroke
			(width 0.0635)
			(type default)
		)
		(layer "F.Cu")
	)
	(gr_arc
		(start 449.91655 -248.896124)
		(mid 449.826747 -248.933321)
		(end 449.78955 -249.023124)
		(stroke
			(width 0.0635)
			(type default)
		)
		(layer "F.Cu")
	)
	(gr_line
		(start 452.048626 -245.148354)
		(end 452.113396 -245.213124)
		(stroke
			(width 0.0635)
			(type default)
		)
		(layer "F.Cu")
	)
	(gr_line
		(start 452.048626 -244.731794)
		(end 452.113396 -244.667024)
		(stroke
			(width 0.0635)
			(type default)
		)
		(layer "F.Cu")
	)
	(gr_line
		(start 452.048626 -133.95833)
		(end 452.113396 -134.0231)
		(stroke
			(width 0.0635)
			(type default)
		)
		(layer "F.Cu")
	)
	(gr_line
		(start 452.048626 -133.54177)
		(end 452.113396 -133.477)
		(stroke
			(width 0.0635)
			(type default)
		)
		(layer "F.Cu")
	)
	(gr_line
		(start 452.048626 -130.14833)
		(end 452.113396 -130.2131)
		(stroke
			(width 0.0635)
			(type default)
		)
		(layer "F.Cu")
	)
	(gr_line
		(start 452.048626 -129.73177)
		(end 452.113396 -129.667)
		(stroke
			(width 0.0635)
			(type default)
		)
		(layer "F.Cu")
	)
	(gr_line
		(start 452.048626 -15.148306)
		(end 452.113396 -15.213076)
		(stroke
			(width 0.0635)
			(type default)
		)
		(layer "F.Cu")
	)
	(gr_line
		(start 452.048626 -14.731746)
		(end 452.113396 -14.666976)
		(stroke
			(width 0.0635)
			(type default)
		)
		(layer "F.Cu")
	)
	(gr_line
		(start 452.063866 -18.943066)
		(end 452.113396 -18.992596)
		(stroke
			(width 0.0635)
			(type default)
		)
		(layer "F.Cu")
	)
	(gr_line
		(start 452.063866 -18.526506)
		(end 452.113396 -18.476976)
		(stroke
			(width 0.0635)
			(type default)
		)
		(layer "F.Cu")
	)
	(gr_line
		(start 452.070216 -248.979944)
		(end 452.113396 -249.023124)
		(stroke
			(width 0.0635)
			(type default)
		)
		(layer "F.Cu")
	)
	(gr_line
		(start 452.070216 -248.563384)
		(end 452.113396 -248.520204)
		(stroke
			(width 0.0635)
			(type default)
		)
		(layer "F.Cu")
	)
	(gr_line
		(start 452.113396 -249.243596)
		(end 452.254874 -249.385074)
		(stroke
			(width 0.0635)
			(type default)
		)
		(layer "F.Cu")
	)
	(gr_line
		(start 452.113396 -249.023124)
		(end 452.113396 -249.243596)
		(stroke
			(width 0.0635)
			(type default)
		)
		(layer "F.Cu")
	)
	(gr_line
		(start 452.113396 -248.242074)
		(end 452.113396 -248.520204)
		(stroke
			(width 0.0635)
			(type default)
		)
		(layer "F.Cu")
	)
	(gr_line
		(start 452.113396 -248.242074)
		(end 452.240396 -248.115074)
		(stroke
			(width 0.0635)
			(type default)
		)
		(layer "F.Cu")
	)
	(gr_line
		(start 452.113396 -245.448074)
		(end 452.240396 -245.575074)
		(stroke
			(width 0.0635)
			(type default)
		)
		(layer "F.Cu")
	)
	(gr_line
		(start 452.113396 -245.213124)
		(end 452.113396 -245.448074)
		(stroke
			(width 0.0635)
			(type default)
		)
		(layer "F.Cu")
	)
	(gr_line
		(start 452.113396 -244.432074)
		(end 452.113396 -244.667024)
		(stroke
			(width 0.0635)
			(type default)
		)
		(layer "F.Cu")
	)
	(gr_line
		(start 452.113396 -244.432074)
		(end 452.240396 -244.305074)
		(stroke
			(width 0.0635)
			(type default)
		)
		(layer "F.Cu")
	)
	(gr_line
		(start 452.113396 -134.25805)
		(end 452.240396 -134.38505)
		(stroke
			(width 0.0635)
			(type default)
		)
		(layer "F.Cu")
	)
	(gr_line
		(start 452.113396 -134.0231)
		(end 452.113396 -134.25805)
		(stroke
			(width 0.0635)
			(type default)
		)
		(layer "F.Cu")
	)
	(gr_line
		(start 452.113396 -133.24205)
		(end 452.113396 -133.477)
		(stroke
			(width 0.0635)
			(type default)
		)
		(layer "F.Cu")
	)
	(gr_line
		(start 452.113396 -133.24205)
		(end 452.240396 -133.11505)
		(stroke
			(width 0.0635)
			(type default)
		)
		(layer "F.Cu")
	)
	(gr_line
		(start 452.113396 -130.44805)
		(end 452.240396 -130.57505)
		(stroke
			(width 0.0635)
			(type default)
		)
		(layer "F.Cu")
	)
	(gr_line
		(start 452.113396 -130.2131)
		(end 452.113396 -130.44805)
		(stroke
			(width 0.0635)
			(type default)
		)
		(layer "F.Cu")
	)
	(gr_line
		(start 452.113396 -129.43205)
		(end 452.113396 -129.667)
		(stroke
			(width 0.0635)
			(type default)
		)
		(layer "F.Cu")
	)
	(gr_line
		(start 452.113396 -129.43205)
		(end 452.240396 -129.30505)
		(stroke
			(width 0.0635)
			(type default)
		)
		(layer "F.Cu")
	)
	(gr_line
		(start 452.113396 -19.258026)
		(end 452.240396 -19.385026)
		(stroke
			(width 0.0635)
			(type default)
		)
		(layer "F.Cu")
	)
	(gr_line
		(start 452.113396 -18.992596)
		(end 452.113396 -19.258026)
		(stroke
			(width 0.0635)
			(type default)
		)
		(layer "F.Cu")
	)
	(gr_line
		(start 452.113396 -18.242026)
		(end 452.113396 -18.476976)
		(stroke
			(width 0.0635)
			(type default)
		)
		(layer "F.Cu")
	)
	(gr_line
		(start 452.113396 -18.242026)
		(end 452.240396 -18.115026)
		(stroke
			(width 0.0635)
			(type default)
		)
		(layer "F.Cu")
	)
	(gr_line
		(start 452.113396 -15.448026)
		(end 452.240396 -15.575026)
		(stroke
			(width 0.0635)
			(type default)
		)
		(layer "F.Cu")
	)
	(gr_line
		(start 452.113396 -15.213076)
		(end 452.113396 -15.448026)
		(stroke
			(width 0.0635)
			(type default)
		)
		(layer "F.Cu")
	)
	(gr_line
		(start 452.113396 -14.432026)
		(end 452.113396 -14.666976)
		(stroke
			(width 0.0635)
			(type default)
		)
		(layer "F.Cu")
	)
	(gr_line
		(start 452.113396 -14.432026)
		(end 452.240396 -14.305026)
		(stroke
			(width 0.0635)
			(type default)
		)
		(layer "F.Cu")
	)
	(gr_line
		(start 452.240396 -248.115074)
		(end 453.574912 -248.115074)
		(stroke
			(width 0.0635)
			(type default)
		)
		(layer "F.Cu")
	)
	(gr_line
		(start 452.240396 -245.575074)
		(end 453.574912 -245.575074)
		(stroke
			(width 0.0635)
			(type default)
		)
		(layer "F.Cu")
	)
	(gr_line
		(start 452.240396 -244.305074)
		(end 453.574912 -244.305074)
		(stroke
			(width 0.0635)
			(type default)
		)
		(layer "F.Cu")
	)
	(gr_line
		(start 452.240396 -134.38505)
		(end 453.574912 -134.38505)
		(stroke
			(width 0.0635)
			(type default)
		)
		(layer "F.Cu")
	)
	(gr_line
		(start 452.240396 -133.11505)
		(end 453.574912 -133.11505)
		(stroke
			(width 0.0635)
			(type default)
		)
		(layer "F.Cu")
	)
	(gr_line
		(start 452.240396 -130.57505)
		(end 453.574912 -130.57505)
		(stroke
			(width 0.0635)
			(type default)
		)
		(layer "F.Cu")
	)
	(gr_line
		(start 452.240396 -129.30505)
		(end 453.574912 -129.30505)
		(stroke
			(width 0.0635)
			(type default)
		)
		(layer "F.Cu")
	)
	(gr_line
		(start 452.240396 -19.385026)
		(end 453.574912 -19.385026)
		(stroke
			(width 0.0635)
			(type default)
		)
		(layer "F.Cu")
	)
	(gr_line
		(start 452.240396 -18.115026)
		(end 453.574912 -18.115026)
		(stroke
			(width 0.0635)
			(type default)
		)
		(layer "F.Cu")
	)
	(gr_line
		(start 452.240396 -15.575026)
		(end 453.574912 -15.575026)
		(stroke
			(width 0.0635)
			(type default)
		)
		(layer "F.Cu")
	)
	(gr_line
		(start 452.240396 -14.305026)
		(end 453.574912 -14.305026)
		(stroke
			(width 0.0635)
			(type default)
		)
		(layer "F.Cu")
	)
	(gr_line
		(start 452.254874 -249.385074)
		(end 453.574912 -249.385074)
		(stroke
			(width 0.0635)
			(type default)
		)
		(layer "F.Cu")
	)
	(gr_line
		(start 476.964502 -128.627124)
		(end 477.224852 -128.627124)
		(stroke
			(width 0.0635)
			(type default)
		)
		(layer "F.Cu")
	)
	(gr_line
		(start 476.964502 -13.6271)
		(end 477.224852 -13.6271)
		(stroke
			(width 0.0635)
			(type default)
		)
		(layer "F.Cu")
	)
	(gr_line
		(start 477.152462 -245.215918)
		(end 477.152462 -245.455694)
		(stroke
			(width 0.0635)
			(type default)
		)
		(layer "F.Cu")
	)
	(gr_arc
		(start 477.152462 -244.55247)
		(mid 477.206836 -244.683768)
		(end 477.338136 -244.738144)
		(stroke
			(width 0.0635)
			(type default)
		)
		(layer "F.Cu")
	)
	(gr_line
		(start 477.152462 -244.312694)
		(end 477.152462 -244.55247)
		(stroke
			(width 0.0635)
			(type default)
		)
		(layer "F.Cu")
	)
	(gr_arc
		(start 477.338136 -245.030244)
		(mid 477.206845 -245.084627)
		(end 477.152462 -245.215918)
		(stroke
			(width 0.0635)
			(type default)
		)
		(layer "F.Cu")
	)
	(gr_arc
		(start 477.389952 -128.792224)
		(mid 477.341595 -128.675481)
		(end 477.224852 -128.627124)
		(stroke
			(width 0.0635)
			(type default)
		)
		(layer "F.Cu")
	)
	(gr_arc
		(start 477.389952 -13.7922)
		(mid 477.341595 -13.675457)
		(end 477.224852 -13.6271)
		(stroke
			(width 0.0635)
			(type default)
		)
		(layer "F.Cu")
	)
	(gr_arc
		(start 477.847152 -128.627124)
		(mid 477.730448 -128.675499)
		(end 477.682052 -128.792224)
		(stroke
			(width 0.0635)
			(type default)
		)
		(layer "F.Cu")
	)
	(gr_line
		(start 477.847152 -128.627124)
		(end 478.107502 -128.627124)
		(stroke
			(width 0.0635)
			(type default)
		)
		(layer "F.Cu")
	)
	(gr_arc
		(start 477.847152 -13.6271)
		(mid 477.73044 -13.675474)
		(end 477.682052 -13.7922)
		(stroke
			(width 0.0635)
			(type default)
		)
		(layer "F.Cu")
	)
	(gr_line
		(start 477.847152 -13.6271)
		(end 478.107502 -13.6271)
		(stroke
			(width 0.0635)
			(type default)
		)
		(layer "F.Cu")
	)
	(gr_line
		(start 478.702878 -245.148354)
		(end 478.773998 -245.219474)
		(stroke
			(width 0.0635)
			(type default)
		)
		(layer "F.Cu")
	)
	(gr_line
		(start 478.702878 -244.731794)
		(end 478.773998 -244.660674)
		(stroke
			(width 0.0635)
			(type default)
		)
		(layer "F.Cu")
	)
	(gr_line
		(start 478.702878 -130.14833)
		(end 478.773998 -130.21945)
		(stroke
			(width 0.0635)
			(type default)
		)
		(layer "F.Cu")
	)
	(gr_line
		(start 478.702878 -129.73177)
		(end 478.773998 -129.66065)
		(stroke
			(width 0.0635)
			(type default)
		)
		(layer "F.Cu")
	)
	(gr_line
		(start 478.702878 -15.148306)
		(end 478.773998 -15.219426)
		(stroke
			(width 0.0635)
			(type default)
		)
		(layer "F.Cu")
	)
	(gr_line
		(start 478.702878 -14.731746)
		(end 478.773998 -14.660626)
		(stroke
			(width 0.0635)
			(type default)
		)
		(layer "F.Cu")
	)
	(gr_line
		(start 478.773998 -245.219474)
		(end 479.105214 -245.219474)
		(stroke
			(width 0.0635)
			(type default)
		)
		(layer "F.Cu")
	)
	(gr_line
		(start 478.773998 -244.660674)
		(end 479.105214 -244.660674)
		(stroke
			(width 0.0635)
			(type default)
		)
		(layer "F.Cu")
	)
	(gr_line
		(start 478.773998 -130.21945)
		(end 479.105214 -130.21945)
		(stroke
			(width 0.0635)
			(type default)
		)
		(layer "F.Cu")
	)
	(gr_line
		(start 478.773998 -129.66065)
		(end 479.105214 -129.66065)
		(stroke
			(width 0.0635)
			(type default)
		)
		(layer "F.Cu")
	)
	(gr_line
		(start 478.773998 -15.219426)
		(end 479.105214 -15.219426)
		(stroke
			(width 0.0635)
			(type default)
		)
		(layer "F.Cu")
	)
	(gr_line
		(start 478.773998 -14.660626)
		(end 479.105214 -14.660626)
		(stroke
			(width 0.0635)
			(type default)
		)
		(layer "F.Cu")
	)
	(gr_line
		(start 479.664014 -245.219474)
		(end 480.102926 -245.219474)
		(stroke
			(width 0.0635)
			(type default)
		)
		(layer "F.Cu")
	)
	(gr_line
		(start 479.664014 -244.660674)
		(end 480.067874 -244.660674)
		(stroke
			(width 0.0635)
			(type default)
		)
		(layer "F.Cu")
	)
	(gr_line
		(start 479.664014 -130.21945)
		(end 480.076764 -130.21945)
		(stroke
			(width 0.0635)
			(type default)
		)
		(layer "F.Cu")
	)
	(gr_line
		(start 479.664014 -129.66065)
		(end 480.026218 -129.66065)
		(stroke
			(width 0.0635)
			(type default)
		)
		(layer "F.Cu")
	)
	(gr_line
		(start 479.664014 -15.219426)
		(end 480.072446 -15.219426)
		(stroke
			(width 0.0635)
			(type default)
		)
		(layer "F.Cu")
	)
	(gr_line
		(start 479.664014 -14.660626)
		(end 480.071938 -14.660626)
		(stroke
			(width 0.0635)
			(type default)
		)
		(layer "F.Cu")
	)
	(gr_line
		(start 480.026218 -129.66065)
		(end 480.122484 -129.756916)
		(stroke
			(width 0.0635)
			(type default)
		)
		(layer "F.Cu")
	)
	(gr_line
		(start 480.067874 -244.660674)
		(end 480.15652 -244.74932)
		(stroke
			(width 0.0635)
			(type default)
		)
		(layer "F.Cu")
	)
	(gr_line
		(start 480.071938 -14.660626)
		(end 480.143312 -14.732)
		(stroke
			(width 0.0635)
			(type default)
		)
		(layer "F.Cu")
	)
	(gr_line
		(start 480.072446 -15.219426)
		(end 480.143312 -15.14856)
		(stroke
			(width 0.0635)
			(type default)
		)
		(layer "F.Cu")
	)
	(gr_line
		(start 480.076764 -130.21945)
		(end 480.122484 -130.17373)
		(stroke
			(width 0.0635)
			(type default)
		)
		(layer "F.Cu")
	)
	(gr_line
		(start 480.102926 -245.219474)
		(end 480.15652 -245.16588)
		(stroke
			(width 0.0635)
			(type default)
		)
		(layer "F.Cu")
	)
	(gr_line
		(start 480.431602 -132.437124)
		(end 480.7585 -132.437124)
		(stroke
			(width 0.0635)
			(type default)
		)
		(layer "F.Cu")
	)
	(gr_line
		(start 480.431602 -17.4371)
		(end 480.7585 -17.4371)
		(stroke
			(width 0.0635)
			(type default)
		)
		(layer "F.Cu")
	)
	(gr_arc
		(start 480.920552 -132.599176)
		(mid 480.873088 -132.484588)
		(end 480.7585 -132.437124)
		(stroke
			(width 0.0635)
			(type default)
		)
		(layer "F.Cu")
	)
	(gr_arc
		(start 480.920552 -17.599152)
		(mid 480.873088 -17.484564)
		(end 480.7585 -17.4371)
		(stroke
			(width 0.0635)
			(type default)
		)
		(layer "F.Cu")
	)
	(gr_line
		(start 481.339652 -249.064272)
		(end 481.339652 -249.385074)
		(stroke
			(width 0.0635)
			(type default)
		)
		(layer "F.Cu")
	)
	(gr_arc
		(start 481.339652 -248.435876)
		(mid 481.388893 -248.55479)
		(end 481.5078 -248.604024)
		(stroke
			(width 0.0635)
			(type default)
		)
		(layer "F.Cu")
	)
	(gr_line
		(start 481.339652 -248.115074)
		(end 481.339652 -248.435876)
		(stroke
			(width 0.0635)
			(type default)
		)
		(layer "F.Cu")
	)
	(gr_arc
		(start 481.374704 -132.437124)
		(mid 481.260105 -132.484585)
		(end 481.212652 -132.599176)
		(stroke
			(width 0.0635)
			(type default)
		)
		(layer "F.Cu")
	)
	(gr_line
		(start 481.374704 -132.437124)
		(end 481.701602 -132.437124)
		(stroke
			(width 0.0635)
			(type default)
		)
		(layer "F.Cu")
	)
	(gr_arc
		(start 481.3935 -17.4371)
		(mid 481.265638 -17.490072)
		(end 481.212652 -17.617948)
		(stroke
			(width 0.0635)
			(type default)
		)
		(layer "F.Cu")
	)
	(gr_line
		(start 481.3935 -17.4371)
		(end 481.701602 -17.4371)
		(stroke
			(width 0.0635)
			(type default)
		)
		(layer "F.Cu")
	)
	(gr_arc
		(start 481.5078 -248.896124)
		(mid 481.388901 -248.945373)
		(end 481.339652 -249.064272)
		(stroke
			(width 0.0635)
			(type default)
		)
		(layer "F.Cu")
	)
	(gr_line
		(start 483.598728 -248.958354)
		(end 483.663498 -249.023124)
		(stroke
			(width 0.0635)
			(type default)
		)
		(layer "F.Cu")
	)
	(gr_line
		(start 483.598728 -248.541794)
		(end 483.663498 -248.477024)
		(stroke
			(width 0.0635)
			(type default)
		)
		(layer "F.Cu")
	)
	(gr_line
		(start 483.598728 -245.148354)
		(end 483.663498 -245.213124)
		(stroke
			(width 0.0635)
			(type default)
		)
		(layer "F.Cu")
	)
	(gr_line
		(start 483.598728 -244.731794)
		(end 483.663498 -244.667024)
		(stroke
			(width 0.0635)
			(type default)
		)
		(layer "F.Cu")
	)
	(gr_line
		(start 483.598728 -130.14833)
		(end 483.663498 -130.2131)
		(stroke
			(width 0.0635)
			(type default)
		)
		(layer "F.Cu")
	)
	(gr_line
		(start 483.598728 -129.73177)
		(end 483.663498 -129.667)
		(stroke
			(width 0.0635)
			(type default)
		)
		(layer "F.Cu")
	)
	(gr_line
		(start 483.598728 -18.958306)
		(end 483.663498 -19.023076)
		(stroke
			(width 0.0635)
			(type default)
		)
		(layer "F.Cu")
	)
	(gr_line
		(start 483.598728 -18.541746)
		(end 483.663498 -18.476976)
		(stroke
			(width 0.0635)
			(type default)
		)
		(layer "F.Cu")
	)
	(gr_line
		(start 483.598728 -15.148306)
		(end 483.663498 -15.213076)
		(stroke
			(width 0.0635)
			(type default)
		)
		(layer "F.Cu")
	)
	(gr_line
		(start 483.598728 -14.731746)
		(end 483.663498 -14.666976)
		(stroke
			(width 0.0635)
			(type default)
		)
		(layer "F.Cu")
	)
	(gr_line
		(start 483.606856 -133.950456)
		(end 483.663498 -134.007098)
		(stroke
			(width 0.0635)
			(type default)
		)
		(layer "F.Cu")
	)
	(gr_line
		(start 483.606856 -133.533642)
		(end 483.663498 -133.477)
		(stroke
			(width 0.0635)
			(type default)
		)
		(layer "F.Cu")
	)
	(gr_line
		(start 483.663498 -249.221498)
		(end 483.827074 -249.385074)
		(stroke
			(width 0.0635)
			(type default)
		)
		(layer "F.Cu")
	)
	(gr_line
		(start 483.663498 -249.023124)
		(end 483.663498 -249.221498)
		(stroke
			(width 0.0635)
			(type default)
		)
		(layer "F.Cu")
	)
	(gr_line
		(start 483.663498 -248.242074)
		(end 483.663498 -248.477024)
		(stroke
			(width 0.0635)
			(type default)
		)
		(layer "F.Cu")
	)
	(gr_line
		(start 483.663498 -248.242074)
		(end 483.790498 -248.115074)
		(stroke
			(width 0.0635)
			(type default)
		)
		(layer "F.Cu")
	)
	(gr_line
		(start 483.663498 -245.448074)
		(end 483.790498 -245.575074)
		(stroke
			(width 0.0635)
			(type default)
		)
		(layer "F.Cu")
	)
	(gr_line
		(start 483.663498 -245.213124)
		(end 483.663498 -245.448074)
		(stroke
			(width 0.0635)
			(type default)
		)
		(layer "F.Cu")
	)
	(gr_line
		(start 483.663498 -244.432074)
		(end 483.663498 -244.667024)
		(stroke
			(width 0.0635)
			(type default)
		)
		(layer "F.Cu")
	)
	(gr_line
		(start 483.663498 -244.432074)
		(end 483.790498 -244.305074)
		(stroke
			(width 0.0635)
			(type default)
		)
		(layer "F.Cu")
	)
	(gr_line
		(start 483.663498 -134.25805)
		(end 483.790498 -134.38505)
		(stroke
			(width 0.0635)
			(type default)
		)
		(layer "F.Cu")
	)
	(gr_line
		(start 483.663498 -134.007098)
		(end 483.663498 -134.25805)
		(stroke
			(width 0.0635)
			(type default)
		)
		(layer "F.Cu")
	)
	(gr_line
		(start 483.663498 -133.24205)
		(end 483.663498 -133.477)
		(stroke
			(width 0.0635)
			(type default)
		)
		(layer "F.Cu")
	)
	(gr_line
		(start 483.663498 -133.24205)
		(end 483.790498 -133.11505)
		(stroke
			(width 0.0635)
			(type default)
		)
		(layer "F.Cu")
	)
	(gr_line
		(start 483.663498 -130.44805)
		(end 483.790498 -130.57505)
		(stroke
			(width 0.0635)
			(type default)
		)
		(layer "F.Cu")
	)
	(gr_line
		(start 483.663498 -130.2131)
		(end 483.663498 -130.44805)
		(stroke
			(width 0.0635)
			(type default)
		)
		(layer "F.Cu")
	)
	(gr_line
		(start 483.663498 -129.43205)
		(end 483.663498 -129.667)
		(stroke
			(width 0.0635)
			(type default)
		)
		(layer "F.Cu")
	)
	(gr_line
		(start 483.663498 -129.43205)
		(end 483.790498 -129.30505)
		(stroke
			(width 0.0635)
			(type default)
		)
		(layer "F.Cu")
	)
	(gr_line
		(start 483.663498 -19.258026)
		(end 483.790498 -19.385026)
		(stroke
			(width 0.0635)
			(type default)
		)
		(layer "F.Cu")
	)
	(gr_line
		(start 483.663498 -19.023076)
		(end 483.663498 -19.258026)
		(stroke
			(width 0.0635)
			(type default)
		)
		(layer "F.Cu")
	)
	(gr_line
		(start 483.663498 -18.242026)
		(end 483.663498 -18.476976)
		(stroke
			(width 0.0635)
			(type default)
		)
		(layer "F.Cu")
	)
	(gr_line
		(start 483.663498 -18.242026)
		(end 483.790498 -18.115026)
		(stroke
			(width 0.0635)
			(type default)
		)
		(layer "F.Cu")
	)
	(gr_line
		(start 483.663498 -15.448026)
		(end 483.790498 -15.575026)
		(stroke
			(width 0.0635)
			(type default)
		)
		(layer "F.Cu")
	)
	(gr_line
		(start 483.663498 -15.213076)
		(end 483.663498 -15.448026)
		(stroke
			(width 0.0635)
			(type default)
		)
		(layer "F.Cu")
	)
	(gr_line
		(start 483.663498 -14.432026)
		(end 483.663498 -14.666976)
		(stroke
			(width 0.0635)
			(type default)
		)
		(layer "F.Cu")
	)
	(gr_line
		(start 483.663498 -14.432026)
		(end 483.790498 -14.305026)
		(stroke
			(width 0.0635)
			(type default)
		)
		(layer "F.Cu")
	)
	(gr_line
		(start 483.790498 -248.115074)
		(end 485.125014 -248.115074)
		(stroke
			(width 0.0635)
			(type default)
		)
		(layer "F.Cu")
	)
	(gr_line
		(start 483.790498 -245.575074)
		(end 485.125014 -245.575074)
		(stroke
			(width 0.0635)
			(type default)
		)
		(layer "F.Cu")
	)
	(gr_line
		(start 483.790498 -244.305074)
		(end 485.125014 -244.305074)
		(stroke
			(width 0.0635)
			(type default)
		)
		(layer "F.Cu")
	)
	(gr_line
		(start 483.790498 -134.38505)
		(end 485.125014 -134.38505)
		(stroke
			(width 0.0635)
			(type default)
		)
		(layer "F.Cu")
	)
	(gr_line
		(start 483.790498 -133.11505)
		(end 485.125014 -133.11505)
		(stroke
			(width 0.0635)
			(type default)
		)
		(layer "F.Cu")
	)
	(gr_line
		(start 483.790498 -130.57505)
		(end 485.125014 -130.57505)
		(stroke
			(width 0.0635)
			(type default)
		)
		(layer "F.Cu")
	)
	(gr_line
		(start 483.790498 -129.30505)
		(end 485.125014 -129.30505)
		(stroke
			(width 0.0635)
			(type default)
		)
		(layer "F.Cu")
	)
	(gr_line
		(start 483.790498 -19.385026)
		(end 485.125014 -19.385026)
		(stroke
			(width 0.0635)
			(type default)
		)
		(layer "F.Cu")
	)
	(gr_line
		(start 483.790498 -18.115026)
		(end 485.125014 -18.115026)
		(stroke
			(width 0.0635)
			(type default)
		)
		(layer "F.Cu")
	)
	(gr_line
		(start 483.790498 -15.575026)
		(end 485.125014 -15.575026)
		(stroke
			(width 0.0635)
			(type default)
		)
		(layer "F.Cu")
	)
	(gr_line
		(start 483.790498 -14.305026)
		(end 485.125014 -14.305026)
		(stroke
			(width 0.0635)
			(type default)
		)
		(layer "F.Cu")
	)
	(gr_line
		(start 483.827074 -249.385074)
		(end 485.125014 -249.385074)
		(stroke
			(width 0.0635)
			(type default)
		)
		(layer "F.Cu")
	)
	(gr_line
		(start 34.285682 -245.281196)
		(end 34.285682 -245.562374)
		(stroke
			(width 0.0635)
			(type default)
		)
		(layer "B.Cu")
	)
	(gr_arc
		(start 34.285682 -244.710204)
		(mid 34.325113 -244.805391)
		(end 34.420302 -244.844824)
		(stroke
			(width 0.0635)
			(type default)
		)
		(layer "B.Cu")
	)
	(gr_line
		(start 34.285682 -244.419374)
		(end 34.285682 -244.710204)
		(stroke
			(width 0.0635)
			(type default)
		)
		(layer "B.Cu")
	)
	(gr_line
		(start 34.285682 -130.281172)
		(end 34.285682 -130.56235)
		(stroke
			(width 0.0635)
			(type default)
		)
		(layer "B.Cu")
	)
	(gr_arc
		(start 34.285682 -129.71018)
		(mid 34.325104 -129.805383)
		(end 34.420302 -129.8448)
		(stroke
			(width 0.0635)
			(type default)
		)
		(layer "B.Cu")
	)
	(gr_line
		(start 34.285682 -129.41935)
		(end 34.285682 -129.71018)
		(stroke
			(width 0.0635)
			(type default)
		)
		(layer "B.Cu")
	)
	(gr_line
		(start 34.285682 -15.281148)
		(end 34.285682 -15.562326)
		(stroke
			(width 0.0635)
			(type default)
		)
		(layer "B.Cu")
	)
	(gr_arc
		(start 34.285682 -14.710156)
		(mid 34.325096 -14.805374)
		(end 34.420302 -14.844776)
		(stroke
			(width 0.0635)
			(type default)
		)
		(layer "B.Cu")
	)
	(gr_line
		(start 34.285682 -14.419326)
		(end 34.285682 -14.710156)
		(stroke
			(width 0.0635)
			(type default)
		)
		(layer "B.Cu")
	)
	(gr_arc
		(start 34.429954 -245.136924)
		(mid 34.327938 -245.17918)
		(end 34.285682 -245.281196)
		(stroke
			(width 0.0635)
			(type default)
		)
		(layer "B.Cu")
	)
	(gr_arc
		(start 34.429954 -130.1369)
		(mid 34.327938 -130.179156)
		(end 34.285682 -130.281172)
		(stroke
			(width 0.0635)
			(type default)
		)
		(layer "B.Cu")
	)
	(gr_arc
		(start 34.429954 -15.136876)
		(mid 34.327938 -15.179132)
		(end 34.285682 -15.281148)
		(stroke
			(width 0.0635)
			(type default)
		)
		(layer "B.Cu")
	)
	(gr_line
		(start 35.545522 -14.920722)
		(end 35.561778 -14.924278)
		(stroke
			(width 0.0635)
			(type default)
		)
		(layer "B.Cu")
	)
	(gr_line
		(start 35.561778 -14.924278)
		(end 35.57524 -14.933168)
		(stroke
			(width 0.0635)
			(type default)
		)
		(layer "B.Cu")
	)
	(gr_line
		(start 36.894008 -15.789656)
		(end 36.914582 -15.802864)
		(stroke
			(width 0.0635)
			(type default)
		)
		(layer "B.Cu")
	)
	(gr_line
		(start 36.914582 -15.802864)
		(end 36.92779 -15.823438)
		(stroke
			(width 0.0635)
			(type default)
		)
		(layer "B.Cu")
	)
	(gr_line
		(start 37.48151 -17.21231)
		(end 37.494718 -17.232884)
		(stroke
			(width 0.0635)
			(type default)
		)
		(layer "B.Cu")
	)
	(gr_line
		(start 37.494718 -17.232884)
		(end 37.515292 -17.246092)
		(stroke
			(width 0.0635)
			(type default)
		)
		(layer "B.Cu")
	)
	(gr_line
		(start 38.325552 -17.775174)
		(end 38.369494 -17.982946)
		(stroke
			(width 0.0635)
			(type default)
		)
		(layer "B.Cu")
	)
	(gr_line
		(start 38.369494 -17.982946)
		(end 38.689026 -18.190464)
		(stroke
			(width 0.0635)
			(type default)
		)
		(layer "B.Cu")
	)
	(gr_line
		(start 38.514782 -17.546828)
		(end 39.027862 -17.880076)
		(stroke
			(width 0.0635)
			(type default)
		)
		(layer "B.Cu")
	)
	(gr_line
		(start 38.689026 -18.190464)
		(end 38.896544 -18.146268)
		(stroke
			(width 0.0635)
			(type default)
		)
		(layer "B.Cu")
	)
	(gr_line
		(start 39.22014 -18.356326)
		(end 39.264336 -18.563844)
		(stroke
			(width 0.0635)
			(type default)
		)
		(layer "B.Cu")
	)
	(gr_line
		(start 39.264336 -18.563844)
		(end 39.583614 -18.771362)
		(stroke
			(width 0.0635)
			(type default)
		)
		(layer "B.Cu")
	)
	(gr_line
		(start 39.410132 -18.128488)
		(end 39.923466 -18.461736)
		(stroke
			(width 0.0635)
			(type default)
		)
		(layer "B.Cu")
	)
	(gr_line
		(start 39.583614 -18.771362)
		(end 39.791386 -18.72742)
		(stroke
			(width 0.0635)
			(type default)
		)
		(layer "B.Cu")
	)
	(gr_line
		(start 40.114728 -18.937224)
		(end 40.158924 -19.144996)
		(stroke
			(width 0.0635)
			(type default)
		)
		(layer "B.Cu")
	)
	(gr_line
		(start 40.158924 -19.144996)
		(end 40.478456 -19.352514)
		(stroke
			(width 0.0635)
			(type default)
		)
		(layer "B.Cu")
	)
	(gr_line
		(start 40.303958 -18.708878)
		(end 40.817292 -19.04238)
		(stroke
			(width 0.0635)
			(type default)
		)
		(layer "B.Cu")
	)
	(gr_line
		(start 40.478456 -19.352514)
		(end 40.685974 -19.308572)
		(stroke
			(width 0.0635)
			(type default)
		)
		(layer "B.Cu")
	)
	(gr_line
		(start 41.00957 -19.51863)
		(end 41.053512 -19.726148)
		(stroke
			(width 0.0635)
			(type default)
		)
		(layer "B.Cu")
	)
	(gr_line
		(start 41.053512 -19.726148)
		(end 41.373044 -19.933666)
		(stroke
			(width 0.0635)
			(type default)
		)
		(layer "B.Cu")
	)
	(gr_line
		(start 41.199054 -19.290284)
		(end 41.710864 -19.62277)
		(stroke
			(width 0.0635)
			(type default)
		)
		(layer "B.Cu")
	)
	(gr_line
		(start 41.373044 -19.933666)
		(end 41.580562 -19.88947)
		(stroke
			(width 0.0635)
			(type default)
		)
		(layer "B.Cu")
	)
	(gr_line
		(start 49.838102 -25.249886)
		(end 49.851564 -25.258776)
		(stroke
			(width 0.0635)
			(type default)
		)
		(layer "B.Cu")
	)
	(gr_line
		(start 49.851564 -25.258776)
		(end 49.86782 -25.262332)
		(stroke
			(width 0.0635)
			(type default)
		)
		(layer "B.Cu")
	)
	(gr_line
		(start 51.73091 -132.322824)
		(end 51.755802 -132.326634)
		(stroke
			(width 0.0635)
			(type default)
		)
		(layer "B.Cu")
	)
	(gr_line
		(start 51.755802 -132.326634)
		(end 51.777392 -132.340604)
		(stroke
			(width 0.0635)
			(type default)
		)
		(layer "B.Cu")
	)
	(gr_line
		(start 64.600074 -141.019022)
		(end 64.613536 -141.027912)
		(stroke
			(width 0.0635)
			(type default)
		)
		(layer "B.Cu")
	)
	(gr_line
		(start 64.613536 -141.027912)
		(end 64.629792 -141.031468)
		(stroke
			(width 0.0635)
			(type default)
		)
		(layer "B.Cu")
	)
	(gr_line
		(start 65.83553 -245.281196)
		(end 65.83553 -245.562374)
		(stroke
			(width 0.0635)
			(type default)
		)
		(layer "B.Cu")
	)
	(gr_arc
		(start 65.83553 -244.710204)
		(mid 65.874964 -244.805374)
		(end 65.97015 -244.844824)
		(stroke
			(width 0.0635)
			(type default)
		)
		(layer "B.Cu")
	)
	(gr_line
		(start 65.83553 -244.419374)
		(end 65.83553 -244.710204)
		(stroke
			(width 0.0635)
			(type default)
		)
		(layer "B.Cu")
	)
	(gr_line
		(start 65.83553 -130.281172)
		(end 65.83553 -130.56235)
		(stroke
			(width 0.0635)
			(type default)
		)
		(layer "B.Cu")
	)
	(gr_arc
		(start 65.83553 -129.71018)
		(mid 65.874955 -129.805366)
		(end 65.97015 -129.8448)
		(stroke
			(width 0.0635)
			(type default)
		)
		(layer "B.Cu")
	)
	(gr_line
		(start 65.83553 -129.41935)
		(end 65.83553 -129.71018)
		(stroke
			(width 0.0635)
			(type default)
		)
		(layer "B.Cu")
	)
	(gr_line
		(start 65.83553 -15.281148)
		(end 65.83553 -15.562326)
		(stroke
			(width 0.0635)
			(type default)
		)
		(layer "B.Cu")
	)
	(gr_arc
		(start 65.83553 -14.710156)
		(mid 65.874947 -14.805357)
		(end 65.97015 -14.844776)
		(stroke
			(width 0.0635)
			(type default)
		)
		(layer "B.Cu")
	)
	(gr_line
		(start 65.83553 -14.419326)
		(end 65.83553 -14.710156)
		(stroke
			(width 0.0635)
			(type default)
		)
		(layer "B.Cu")
	)
	(gr_arc
		(start 65.979802 -245.136924)
		(mid 65.877786 -245.17918)
		(end 65.83553 -245.281196)
		(stroke
			(width 0.0635)
			(type default)
		)
		(layer "B.Cu")
	)
	(gr_arc
		(start 65.979802 -130.1369)
		(mid 65.877786 -130.179156)
		(end 65.83553 -130.281172)
		(stroke
			(width 0.0635)
			(type default)
		)
		(layer "B.Cu")
	)
	(gr_arc
		(start 65.979802 -15.136876)
		(mid 65.877786 -15.179132)
		(end 65.83553 -15.281148)
		(stroke
			(width 0.0635)
			(type default)
		)
		(layer "B.Cu")
	)
	(gr_line
		(start 66.722244 -129.8448)
		(end 66.763392 -129.87147)
		(stroke
			(width 0.0635)
			(type default)
		)
		(layer "B.Cu")
	)
	(gr_line
		(start 68.185284 -15.187168)
		(end 68.200778 -15.19047)
		(stroke
			(width 0.0635)
			(type default)
		)
		(layer "B.Cu")
	)
	(gr_line
		(start 68.200778 -15.19047)
		(end 68.213732 -15.198852)
		(stroke
			(width 0.0635)
			(type default)
		)
		(layer "B.Cu")
	)
	(gr_line
		(start 68.98259 -29.02585)
		(end 68.998846 -29.029406)
		(stroke
			(width 0.0635)
			(type default)
		)
		(layer "B.Cu")
	)
	(gr_line
		(start 68.998846 -29.029406)
		(end 69.012308 -29.038296)
		(stroke
			(width 0.0635)
			(type default)
		)
		(layer "B.Cu")
	)
	(gr_line
		(start 83.161632 -140.869162)
		(end 83.175094 -140.878052)
		(stroke
			(width 0.0635)
			(type default)
		)
		(layer "B.Cu")
	)
	(gr_line
		(start 83.175094 -140.878052)
		(end 83.19135 -140.881608)
		(stroke
			(width 0.0635)
			(type default)
		)
		(layer "B.Cu")
	)
	(gr_line
		(start 97.385632 -245.281196)
		(end 97.385632 -245.562374)
		(stroke
			(width 0.0635)
			(type default)
		)
		(layer "B.Cu")
	)
	(gr_arc
		(start 97.385632 -244.710204)
		(mid 97.42506 -244.805409)
		(end 97.520252 -244.844824)
		(stroke
			(width 0.0635)
			(type default)
		)
		(layer "B.Cu")
	)
	(gr_line
		(start 97.385632 -244.419374)
		(end 97.385632 -244.710204)
		(stroke
			(width 0.0635)
			(type default)
		)
		(layer "B.Cu")
	)
	(gr_line
		(start 97.385632 -130.281172)
		(end 97.385632 -130.56235)
		(stroke
			(width 0.0635)
			(type default)
		)
		(layer "B.Cu")
	)
	(gr_arc
		(start 97.385632 -129.71018)
		(mid 97.425051 -129.805401)
		(end 97.520252 -129.8448)
		(stroke
			(width 0.0635)
			(type default)
		)
		(layer "B.Cu")
	)
	(gr_line
		(start 97.385632 -129.41935)
		(end 97.385632 -129.71018)
		(stroke
			(width 0.0635)
			(type default)
		)
		(layer "B.Cu")
	)
	(gr_line
		(start 97.385632 -15.281148)
		(end 97.385632 -15.562326)
		(stroke
			(width 0.0635)
			(type default)
		)
		(layer "B.Cu")
	)
	(gr_arc
		(start 97.385632 -14.710156)
		(mid 97.425043 -14.805392)
		(end 97.520252 -14.844776)
		(stroke
			(width 0.0635)
			(type default)
		)
		(layer "B.Cu")
	)
	(gr_line
		(start 97.385632 -14.419326)
		(end 97.385632 -14.710156)
		(stroke
			(width 0.0635)
			(type default)
		)
		(layer "B.Cu")
	)
	(gr_arc
		(start 97.529904 -245.136924)
		(mid 97.427888 -245.17918)
		(end 97.385632 -245.281196)
		(stroke
			(width 0.0635)
			(type default)
		)
		(layer "B.Cu")
	)
	(gr_arc
		(start 97.529904 -130.1369)
		(mid 97.427888 -130.179156)
		(end 97.385632 -130.281172)
		(stroke
			(width 0.0635)
			(type default)
		)
		(layer "B.Cu")
	)
	(gr_arc
		(start 97.529904 -15.136876)
		(mid 97.427888 -15.179132)
		(end 97.385632 -15.281148)
		(stroke
			(width 0.0635)
			(type default)
		)
		(layer "B.Cu")
	)
	(gr_line
		(start 98.636582 -14.929358)
		(end 98.652838 -14.932914)
		(stroke
			(width 0.0635)
			(type default)
		)
		(layer "B.Cu")
	)
	(gr_line
		(start 98.652838 -14.932914)
		(end 98.6663 -14.941804)
		(stroke
			(width 0.0635)
			(type default)
		)
		(layer "B.Cu")
	)
	(gr_line
		(start 99.306888 -15.357856)
		(end 99.326446 -15.370556)
		(stroke
			(width 0.0635)
			(type default)
		)
		(layer "B.Cu")
	)
	(gr_line
		(start 99.326446 -15.370556)
		(end 99.339146 -15.390368)
		(stroke
			(width 0.0635)
			(type default)
		)
		(layer "B.Cu")
	)
	(gr_line
		(start 99.563936 -15.73657)
		(end 99.572318 -15.749524)
		(stroke
			(width 0.0635)
			(type default)
		)
		(layer "B.Cu")
	)
	(gr_line
		(start 99.572318 -15.749524)
		(end 99.57562 -15.764764)
		(stroke
			(width 0.0635)
			(type default)
		)
		(layer "B.Cu")
	)
	(gr_line
		(start 99.859084 -19.236944)
		(end 99.938332 -19.609562)
		(stroke
			(width 0.0635)
			(type default)
		)
		(layer "B.Cu")
	)
	(gr_line
		(start 99.859084 -19.236944)
		(end 99.974654 -19.05889)
		(stroke
			(width 0.0635)
			(type default)
		)
		(layer "B.Cu")
	)
	(gr_line
		(start 99.938332 -19.609562)
		(end 100.116132 -19.724878)
		(stroke
			(width 0.0635)
			(type default)
		)
		(layer "B.Cu")
	)
	(gr_line
		(start 100.080826 -20.280376)
		(end 100.160074 -20.652994)
		(stroke
			(width 0.0635)
			(type default)
		)
		(layer "B.Cu")
	)
	(gr_line
		(start 100.080826 -20.280376)
		(end 100.196396 -20.102576)
		(stroke
			(width 0.0635)
			(type default)
		)
		(layer "B.Cu")
	)
	(gr_line
		(start 100.160074 -20.652994)
		(end 100.338128 -20.768564)
		(stroke
			(width 0.0635)
			(type default)
		)
		(layer "B.Cu")
	)
	(gr_line
		(start 100.270056 -19.031712)
		(end 100.396802 -19.62785)
		(stroke
			(width 0.0635)
			(type default)
		)
		(layer "B.Cu")
	)
	(gr_line
		(start 100.302822 -21.323808)
		(end 100.38207 -21.696426)
		(stroke
			(width 0.0635)
			(type default)
		)
		(layer "B.Cu")
	)
	(gr_line
		(start 100.302822 -21.323808)
		(end 100.418392 -21.146008)
		(stroke
			(width 0.0635)
			(type default)
		)
		(layer "B.Cu")
	)
	(gr_line
		(start 100.38207 -21.696426)
		(end 100.55987 -21.811996)
		(stroke
			(width 0.0635)
			(type default)
		)
		(layer "B.Cu")
	)
	(gr_line
		(start 100.492306 -20.077176)
		(end 100.619052 -20.673314)
		(stroke
			(width 0.0635)
			(type default)
		)
		(layer "B.Cu")
	)
	(gr_line
		(start 100.524564 -22.36724)
		(end 100.603812 -22.739858)
		(stroke
			(width 0.0635)
			(type default)
		)
		(layer "B.Cu")
	)
	(gr_line
		(start 100.524564 -22.36724)
		(end 100.640134 -22.18944)
		(stroke
			(width 0.0635)
			(type default)
		)
		(layer "B.Cu")
	)
	(gr_line
		(start 100.603812 -22.739858)
		(end 100.781612 -22.855428)
		(stroke
			(width 0.0635)
			(type default)
		)
		(layer "B.Cu")
	)
	(gr_line
		(start 100.713794 -21.117814)
		(end 100.841302 -21.717762)
		(stroke
			(width 0.0635)
			(type default)
		)
		(layer "B.Cu")
	)
	(gr_line
		(start 100.935536 -22.160738)
		(end 101.06279 -22.759924)
		(stroke
			(width 0.0635)
			(type default)
		)
		(layer "B.Cu")
	)
	(gr_line
		(start 102.201726 -29.524198)
		(end 102.205282 -29.540454)
		(stroke
			(width 0.0635)
			(type default)
		)
		(layer "B.Cu")
	)
	(gr_line
		(start 102.205282 -29.540454)
		(end 102.214172 -29.553916)
		(stroke
			(width 0.0635)
			(type default)
		)
		(layer "B.Cu")
	)
	(gr_line
		(start 103.336598 -37.998654)
		(end 103.357172 -38.011862)
		(stroke
			(width 0.0635)
			(type default)
		)
		(layer "B.Cu")
	)
	(gr_line
		(start 103.357172 -38.011862)
		(end 103.37038 -38.032436)
		(stroke
			(width 0.0635)
			(type default)
		)
		(layer "B.Cu")
	)
	(gr_line
		(start 111.107728 -56.375046)
		(end 111.128302 -56.388254)
		(stroke
			(width 0.0635)
			(type default)
		)
		(layer "B.Cu")
	)
	(gr_line
		(start 111.128302 -56.388254)
		(end 111.14151 -56.408828)
		(stroke
			(width 0.0635)
			(type default)
		)
		(layer "B.Cu")
	)
	(gr_line
		(start 128.93548 -245.281196)
		(end 128.93548 -245.562374)
		(stroke
			(width 0.0635)
			(type default)
		)
		(layer "B.Cu")
	)
	(gr_arc
		(start 128.93548 -244.710204)
		(mid 128.974911 -244.805392)
		(end 129.0701 -244.844824)
		(stroke
			(width 0.0635)
			(type default)
		)
		(layer "B.Cu")
	)
	(gr_line
		(start 128.93548 -244.419374)
		(end 128.93548 -244.710204)
		(stroke
			(width 0.0635)
			(type default)
		)
		(layer "B.Cu")
	)
	(gr_line
		(start 128.93548 -130.281172)
		(end 128.93548 -130.56235)
		(stroke
			(width 0.0635)
			(type default)
		)
		(layer "B.Cu")
	)
	(gr_arc
		(start 128.93548 -129.71018)
		(mid 128.974902 -129.805384)
		(end 129.0701 -129.8448)
		(stroke
			(width 0.0635)
			(type default)
		)
		(layer "B.Cu")
	)
	(gr_line
		(start 128.93548 -129.41935)
		(end 128.93548 -129.71018)
		(stroke
			(width 0.0635)
			(type default)
		)
		(layer "B.Cu")
	)
	(gr_line
		(start 128.93548 -15.281148)
		(end 128.93548 -15.562326)
		(stroke
			(width 0.0635)
			(type default)
		)
		(layer "B.Cu")
	)
	(gr_arc
		(start 128.93548 -14.710156)
		(mid 128.974894 -14.805375)
		(end 129.0701 -14.844776)
		(stroke
			(width 0.0635)
			(type default)
		)
		(layer "B.Cu")
	)
	(gr_line
		(start 128.93548 -14.419326)
		(end 128.93548 -14.710156)
		(stroke
			(width 0.0635)
			(type default)
		)
		(layer "B.Cu")
	)
	(gr_arc
		(start 129.079752 -245.136924)
		(mid 128.977736 -245.17918)
		(end 128.93548 -245.281196)
		(stroke
			(width 0.0635)
			(type default)
		)
		(layer "B.Cu")
	)
	(gr_arc
		(start 129.079752 -130.1369)
		(mid 128.977736 -130.179156)
		(end 128.93548 -130.281172)
		(stroke
			(width 0.0635)
			(type default)
		)
		(layer "B.Cu")
	)
	(gr_arc
		(start 129.079752 -15.136876)
		(mid 128.977736 -15.179132)
		(end 128.93548 -15.281148)
		(stroke
			(width 0.0635)
			(type default)
		)
		(layer "B.Cu")
	)
	(gr_line
		(start 129.916174 -129.8448)
		(end 129.970276 -129.892806)
		(stroke
			(width 0.0635)
			(type default)
		)
		(layer "B.Cu")
	)
	(gr_line
		(start 129.995422 -14.900148)
		(end 130.011678 -14.903704)
		(stroke
			(width 0.0635)
			(type default)
		)
		(layer "B.Cu")
	)
	(gr_line
		(start 130.011678 -14.903704)
		(end 130.02514 -14.912594)
		(stroke
			(width 0.0635)
			(type default)
		)
		(layer "B.Cu")
	)
	(gr_line
		(start 130.503422 -80.629506)
		(end 130.547364 -80.421734)
		(stroke
			(width 0.0635)
			(type default)
		)
		(layer "B.Cu")
	)
	(gr_line
		(start 130.503422 -80.629506)
		(end 130.71094 -80.949038)
		(stroke
			(width 0.0635)
			(type default)
		)
		(layer "B.Cu")
	)
	(gr_line
		(start 130.556254 -15.257272)
		(end 130.576066 -15.269972)
		(stroke
			(width 0.0635)
			(type default)
		)
		(layer "B.Cu")
	)
	(gr_line
		(start 130.576066 -15.269972)
		(end 130.588766 -15.28953)
		(stroke
			(width 0.0635)
			(type default)
		)
		(layer "B.Cu")
	)
	(gr_line
		(start 130.71094 -80.949038)
		(end 130.918458 -80.99298)
		(stroke
			(width 0.0635)
			(type default)
		)
		(layer "B.Cu")
	)
	(gr_line
		(start 130.81254 -80.288638)
		(end 131.148328 -80.805528)
		(stroke
			(width 0.0635)
			(type default)
		)
		(layer "B.Cu")
	)
	(gr_line
		(start 131.084574 -81.524094)
		(end 131.128516 -81.316576)
		(stroke
			(width 0.0635)
			(type default)
		)
		(layer "B.Cu")
	)
	(gr_line
		(start 131.084574 -81.524094)
		(end 131.292092 -81.843626)
		(stroke
			(width 0.0635)
			(type default)
		)
		(layer "B.Cu")
	)
	(gr_line
		(start 131.155694 -87.763858)
		(end 131.168902 -87.784432)
		(stroke
			(width 0.0635)
			(type default)
		)
		(layer "B.Cu")
	)
	(gr_line
		(start 131.168902 -87.784432)
		(end 131.189476 -87.79764)
		(stroke
			(width 0.0635)
			(type default)
		)
		(layer "B.Cu")
	)
	(gr_line
		(start 131.292092 -81.843626)
		(end 131.49961 -81.887822)
		(stroke
			(width 0.0635)
			(type default)
		)
		(layer "B.Cu")
	)
	(gr_line
		(start 131.392676 -81.18094)
		(end 131.731004 -81.702148)
		(stroke
			(width 0.0635)
			(type default)
		)
		(layer "B.Cu")
	)
	(gr_line
		(start 131.52628 -136.912858)
		(end 131.541774 -136.91616)
		(stroke
			(width 0.0635)
			(type default)
		)
		(layer "B.Cu")
	)
	(gr_line
		(start 131.541774 -136.91616)
		(end 131.554728 -136.924542)
		(stroke
			(width 0.0635)
			(type default)
		)
		(layer "B.Cu")
	)
	(gr_line
		(start 131.665472 -82.418936)
		(end 131.709414 -82.211164)
		(stroke
			(width 0.0635)
			(type default)
		)
		(layer "B.Cu")
	)
	(gr_line
		(start 131.665472 -82.418936)
		(end 131.87299 -82.738468)
		(stroke
			(width 0.0635)
			(type default)
		)
		(layer "B.Cu")
	)
	(gr_line
		(start 131.87299 -82.738468)
		(end 132.080508 -82.78241)
		(stroke
			(width 0.0635)
			(type default)
		)
		(layer "B.Cu")
	)
	(gr_line
		(start 131.973574 -82.076036)
		(end 132.310378 -82.594704)
		(stroke
			(width 0.0635)
			(type default)
		)
		(layer "B.Cu")
	)
	(gr_line
		(start 132.089652 -17.59966)
		(end 132.098542 -17.613122)
		(stroke
			(width 0.0635)
			(type default)
		)
		(layer "B.Cu")
	)
	(gr_line
		(start 132.098542 -17.613122)
		(end 132.102098 -17.629378)
		(stroke
			(width 0.0635)
			(type default)
		)
		(layer "B.Cu")
	)
	(gr_line
		(start 132.246624 -83.313524)
		(end 132.290566 -83.106006)
		(stroke
			(width 0.0635)
			(type default)
		)
		(layer "B.Cu")
	)
	(gr_line
		(start 132.246624 -83.313524)
		(end 132.453888 -83.633056)
		(stroke
			(width 0.0635)
			(type default)
		)
		(layer "B.Cu")
	)
	(gr_line
		(start 132.453888 -83.633056)
		(end 132.661406 -83.676998)
		(stroke
			(width 0.0635)
			(type default)
		)
		(layer "B.Cu")
	)
	(gr_line
		(start 132.55625 -82.973672)
		(end 132.89026 -83.488022)
		(stroke
			(width 0.0635)
			(type default)
		)
		(layer "B.Cu")
	)
	(gr_line
		(start 132.7531 -238.980218)
		(end 133.348476 -238.858552)
		(stroke
			(width 0.0635)
			(type default)
		)
		(layer "B.Cu")
	)
	(gr_line
		(start 132.775706 -239.275874)
		(end 132.952744 -239.392714)
		(stroke
			(width 0.0635)
			(type default)
		)
		(layer "B.Cu")
	)
	(gr_line
		(start 132.952744 -239.392714)
		(end 133.326124 -239.316514)
		(stroke
			(width 0.0635)
			(type default)
		)
		(layer "B.Cu")
	)
	(gr_line
		(start 133.209538 -244.347238)
		(end 133.818884 -244.256306)
		(stroke
			(width 0.0635)
			(type default)
		)
		(layer "B.Cu")
	)
	(gr_line
		(start 133.220206 -244.643656)
		(end 133.390894 -244.770148)
		(stroke
			(width 0.0635)
			(type default)
		)
		(layer "B.Cu")
	)
	(gr_line
		(start 133.326124 -239.316514)
		(end 133.442964 -239.13973)
		(stroke
			(width 0.0635)
			(type default)
		)
		(layer "B.Cu")
	)
	(gr_line
		(start 133.390894 -244.770148)
		(end 133.767576 -244.714014)
		(stroke
			(width 0.0635)
			(type default)
		)
		(layer "B.Cu")
	)
	(gr_line
		(start 133.62051 -225.810318)
		(end 134.2263 -225.725482)
		(stroke
			(width 0.0635)
			(type default)
		)
		(layer "B.Cu")
	)
	(gr_line
		(start 133.62686 -226.10699)
		(end 133.796024 -226.234752)
		(stroke
			(width 0.0635)
			(type default)
		)
		(layer "B.Cu")
	)
	(gr_line
		(start 133.767576 -244.714014)
		(end 133.894068 -244.543072)
		(stroke
			(width 0.0635)
			(type default)
		)
		(layer "B.Cu")
	)
	(gr_line
		(start 133.796024 -226.234752)
		(end 134.173214 -226.18192)
		(stroke
			(width 0.0635)
			(type default)
		)
		(layer "B.Cu")
	)
	(gr_line
		(start 133.797548 -238.766858)
		(end 134.394448 -238.644938)
		(stroke
			(width 0.0635)
			(type default)
		)
		(layer "B.Cu")
	)
	(gr_line
		(start 133.820916 -239.062514)
		(end 133.997954 -239.179354)
		(stroke
			(width 0.0635)
			(type default)
		)
		(layer "B.Cu")
	)
	(gr_line
		(start 133.997954 -239.179354)
		(end 134.371334 -239.103154)
		(stroke
			(width 0.0635)
			(type default)
		)
		(layer "B.Cu")
	)
	(gr_line
		(start 134.173214 -226.18192)
		(end 134.300976 -226.012502)
		(stroke
			(width 0.0635)
			(type default)
		)
		(layer "B.Cu")
	)
	(gr_line
		(start 134.264654 -244.189758)
		(end 134.874 -244.098826)
		(stroke
			(width 0.0635)
			(type default)
		)
		(layer "B.Cu")
	)
	(gr_line
		(start 134.275322 -244.486176)
		(end 134.44601 -244.612668)
		(stroke
			(width 0.0635)
			(type default)
		)
		(layer "B.Cu")
	)
	(gr_line
		(start 134.371334 -239.103154)
		(end 134.488428 -238.92637)
		(stroke
			(width 0.0635)
			(type default)
		)
		(layer "B.Cu")
	)
	(gr_line
		(start 134.44601 -244.612668)
		(end 134.822692 -244.556534)
		(stroke
			(width 0.0635)
			(type default)
		)
		(layer "B.Cu")
	)
	(gr_line
		(start 134.675626 -225.66249)
		(end 135.282686 -225.5774)
		(stroke
			(width 0.0635)
			(type default)
		)
		(layer "B.Cu")
	)
	(gr_line
		(start 134.682992 -225.959162)
		(end 134.85241 -226.086924)
		(stroke
			(width 0.0635)
			(type default)
		)
		(layer "B.Cu")
	)
	(gr_line
		(start 134.822692 -244.556534)
		(end 134.949184 -244.385846)
		(stroke
			(width 0.0635)
			(type default)
		)
		(layer "B.Cu")
	)
	(gr_line
		(start 134.841996 -238.553498)
		(end 135.440674 -238.431324)
		(stroke
			(width 0.0635)
			(type default)
		)
		(layer "B.Cu")
	)
	(gr_line
		(start 134.85241 -226.086924)
		(end 135.229854 -226.034092)
		(stroke
			(width 0.0635)
			(type default)
		)
		(layer "B.Cu")
	)
	(gr_line
		(start 134.866126 -238.849154)
		(end 135.043164 -238.965994)
		(stroke
			(width 0.0635)
			(type default)
		)
		(layer "B.Cu")
	)
	(gr_line
		(start 135.043164 -238.965994)
		(end 135.416544 -238.889794)
		(stroke
			(width 0.0635)
			(type default)
		)
		(layer "B.Cu")
	)
	(gr_line
		(start 135.229854 -226.034092)
		(end 135.357616 -225.864674)
		(stroke
			(width 0.0635)
			(type default)
		)
		(layer "B.Cu")
	)
	(gr_line
		(start 135.317992 -244.032786)
		(end 135.9281 -243.9416)
		(stroke
			(width 0.0635)
			(type default)
		)
		(layer "B.Cu")
	)
	(gr_line
		(start 135.330184 -244.32895)
		(end 135.501126 -244.455442)
		(stroke
			(width 0.0635)
			(type default)
		)
		(layer "B.Cu")
	)
	(gr_line
		(start 135.416544 -238.889794)
		(end 135.533638 -238.71301)
		(stroke
			(width 0.0635)
			(type default)
		)
		(layer "B.Cu")
	)
	(gr_line
		(start 135.501126 -244.455442)
		(end 135.878062 -244.399054)
		(stroke
			(width 0.0635)
			(type default)
		)
		(layer "B.Cu")
	)
	(gr_line
		(start 135.73252 -225.514408)
		(end 136.340088 -225.429318)
		(stroke
			(width 0.0635)
			(type default)
		)
		(layer "B.Cu")
	)
	(gr_line
		(start 135.739632 -225.81108)
		(end 135.90905 -225.938842)
		(stroke
			(width 0.0635)
			(type default)
		)
		(layer "B.Cu")
	)
	(gr_line
		(start 135.878062 -244.399054)
		(end 136.004046 -244.228366)
		(stroke
			(width 0.0635)
			(type default)
		)
		(layer "B.Cu")
	)
	(gr_line
		(start 135.885682 -238.340138)
		(end 136.486138 -238.21771)
		(stroke
			(width 0.0635)
			(type default)
		)
		(layer "B.Cu")
	)
	(gr_line
		(start 135.90905 -225.938842)
		(end 136.28624 -225.88601)
		(stroke
			(width 0.0635)
			(type default)
		)
		(layer "B.Cu")
	)
	(gr_line
		(start 135.911336 -238.635794)
		(end 136.088374 -238.752634)
		(stroke
			(width 0.0635)
			(type default)
		)
		(layer "B.Cu")
	)
	(gr_line
		(start 136.088374 -238.752634)
		(end 136.461754 -238.676434)
		(stroke
			(width 0.0635)
			(type default)
		)
		(layer "B.Cu")
	)
	(gr_line
		(start 136.192514 -89.109804)
		(end 136.205722 -89.130378)
		(stroke
			(width 0.0635)
			(type default)
		)
		(layer "B.Cu")
	)
	(gr_line
		(start 136.205722 -89.130378)
		(end 136.226296 -89.143586)
		(stroke
			(width 0.0635)
			(type default)
		)
		(layer "B.Cu")
	)
	(gr_line
		(start 136.28624 -225.88601)
		(end 136.414002 -225.716592)
		(stroke
			(width 0.0635)
			(type default)
		)
		(layer "B.Cu")
	)
	(gr_line
		(start 136.374632 -243.875052)
		(end 136.983216 -243.784374)
		(stroke
			(width 0.0635)
			(type default)
		)
		(layer "B.Cu")
	)
	(gr_line
		(start 136.385554 -244.17147)
		(end 136.556242 -244.297962)
		(stroke
			(width 0.0635)
			(type default)
		)
		(layer "B.Cu")
	)
	(gr_line
		(start 136.461754 -238.676434)
		(end 136.578848 -238.49965)
		(stroke
			(width 0.0635)
			(type default)
		)
		(layer "B.Cu")
	)
	(gr_line
		(start 136.556242 -244.297962)
		(end 136.933178 -244.241828)
		(stroke
			(width 0.0635)
			(type default)
		)
		(layer "B.Cu")
	)
	(gr_line
		(start 136.787128 -225.36658)
		(end 137.396474 -225.281236)
		(stroke
			(width 0.0635)
			(type default)
		)
		(layer "B.Cu")
	)
	(gr_line
		(start 136.796018 -225.663252)
		(end 136.965436 -225.791014)
		(stroke
			(width 0.0635)
			(type default)
		)
		(layer "B.Cu")
	)
	(gr_line
		(start 136.933178 -244.241828)
		(end 137.059416 -244.070886)
		(stroke
			(width 0.0635)
			(type default)
		)
		(layer "B.Cu")
	)
	(gr_line
		(start 136.965436 -225.791014)
		(end 137.34288 -225.738182)
		(stroke
			(width 0.0635)
			(type default)
		)
		(layer "B.Cu")
	)
	(gr_line
		(start 137.34288 -225.738182)
		(end 137.470642 -225.568764)
		(stroke
			(width 0.0635)
			(type default)
		)
		(layer "B.Cu")
	)
	(gr_line
		(start 142.183104 -91.101418)
		(end 142.196312 -91.121992)
		(stroke
			(width 0.0635)
			(type default)
		)
		(layer "B.Cu")
	)
	(gr_line
		(start 142.196312 -91.121992)
		(end 142.216886 -91.1352)
		(stroke
			(width 0.0635)
			(type default)
		)
		(layer "B.Cu")
	)
	(gr_line
		(start 142.724124 -69.0118)
		(end 142.72768 -69.028056)
		(stroke
			(width 0.0635)
			(type default)
		)
		(layer "B.Cu")
	)
	(gr_line
		(start 142.72768 -69.028056)
		(end 142.73657 -69.041518)
		(stroke
			(width 0.0635)
			(type default)
		)
		(layer "B.Cu")
	)
	(gr_line
		(start 145.3007 -73.270364)
		(end 145.344896 -73.062846)
		(stroke
			(width 0.0635)
			(type default)
		)
		(layer "B.Cu")
	)
	(gr_line
		(start 145.3007 -73.270364)
		(end 145.508218 -73.589896)
		(stroke
			(width 0.0635)
			(type default)
		)
		(layer "B.Cu")
	)
	(gr_line
		(start 145.508218 -73.589896)
		(end 145.715736 -73.633838)
		(stroke
			(width 0.0635)
			(type default)
		)
		(layer "B.Cu")
	)
	(gr_line
		(start 145.612104 -72.933814)
		(end 145.942304 -73.442322)
		(stroke
			(width 0.0635)
			(type default)
		)
		(layer "B.Cu")
	)
	(gr_line
		(start 145.881852 -74.164952)
		(end 145.925794 -73.957434)
		(stroke
			(width 0.0635)
			(type default)
		)
		(layer "B.Cu")
	)
	(gr_line
		(start 145.881852 -74.164952)
		(end 146.08937 -74.484484)
		(stroke
			(width 0.0635)
			(type default)
		)
		(layer "B.Cu")
	)
	(gr_line
		(start 146.08937 -74.484484)
		(end 146.296888 -74.52868)
		(stroke
			(width 0.0635)
			(type default)
		)
		(layer "B.Cu")
	)
	(gr_line
		(start 146.193002 -73.828148)
		(end 146.523456 -74.337164)
		(stroke
			(width 0.0635)
			(type default)
		)
		(layer "B.Cu")
	)
	(gr_line
		(start 146.46275 -75.059794)
		(end 146.506946 -74.852276)
		(stroke
			(width 0.0635)
			(type default)
		)
		(layer "B.Cu")
	)
	(gr_line
		(start 146.46275 -75.059794)
		(end 146.670268 -75.379326)
		(stroke
			(width 0.0635)
			(type default)
		)
		(layer "B.Cu")
	)
	(gr_line
		(start 146.670268 -75.379326)
		(end 146.877786 -75.423268)
		(stroke
			(width 0.0635)
			(type default)
		)
		(layer "B.Cu")
	)
	(gr_line
		(start 146.774154 -74.72299)
		(end 147.105116 -75.232768)
		(stroke
			(width 0.0635)
			(type default)
		)
		(layer "B.Cu")
	)
	(gr_line
		(start 147.043902 -75.954382)
		(end 147.087844 -75.746864)
		(stroke
			(width 0.0635)
			(type default)
		)
		(layer "B.Cu")
	)
	(gr_line
		(start 147.043902 -75.954382)
		(end 147.25142 -76.273914)
		(stroke
			(width 0.0635)
			(type default)
		)
		(layer "B.Cu")
	)
	(gr_line
		(start 147.25142 -76.273914)
		(end 147.458684 -76.317856)
		(stroke
			(width 0.0635)
			(type default)
		)
		(layer "B.Cu")
	)
	(gr_line
		(start 147.354036 -75.615546)
		(end 147.686014 -76.126848)
		(stroke
			(width 0.0635)
			(type default)
		)
		(layer "B.Cu")
	)
	(gr_line
		(start 153.130504 -155.448254)
		(end 153.14676 -155.45181)
		(stroke
			(width 0.0635)
			(type default)
		)
		(layer "B.Cu")
	)
	(gr_line
		(start 153.14676 -155.45181)
		(end 153.160222 -155.4607)
		(stroke
			(width 0.0635)
			(type default)
		)
		(layer "B.Cu")
	)
	(gr_line
		(start 154.12212 -159.75457)
		(end 154.13736 -159.757872)
		(stroke
			(width 0.0635)
			(type default)
		)
		(layer "B.Cu")
	)
	(gr_line
		(start 154.13736 -159.757872)
		(end 154.150314 -159.766254)
		(stroke
			(width 0.0635)
			(type default)
		)
		(layer "B.Cu")
	)
	(gr_line
		(start 155.474416 -157.314646)
		(end 155.518358 -157.522164)
		(stroke
			(width 0.0635)
			(type default)
		)
		(layer "B.Cu")
	)
	(gr_line
		(start 155.518358 -157.522164)
		(end 155.83789 -157.729682)
		(stroke
			(width 0.0635)
			(type default)
		)
		(layer "B.Cu")
	)
	(gr_line
		(start 155.665424 -157.08757)
		(end 156.17698 -157.419802)
		(stroke
			(width 0.0635)
			(type default)
		)
		(layer "B.Cu")
	)
	(gr_line
		(start 155.83789 -157.729682)
		(end 156.045408 -157.68574)
		(stroke
			(width 0.0635)
			(type default)
		)
		(layer "B.Cu")
	)
	(gr_line
		(start 156.369004 -157.895544)
		(end 156.4132 -158.103316)
		(stroke
			(width 0.0635)
			(type default)
		)
		(layer "B.Cu")
	)
	(gr_line
		(start 156.4132 -158.103316)
		(end 156.732732 -158.310834)
		(stroke
			(width 0.0635)
			(type default)
		)
		(layer "B.Cu")
	)
	(gr_line
		(start 156.558996 -157.66796)
		(end 157.070044 -157.999684)
		(stroke
			(width 0.0635)
			(type default)
		)
		(layer "B.Cu")
	)
	(gr_line
		(start 156.732732 -158.310834)
		(end 156.939996 -158.266638)
		(stroke
			(width 0.0635)
			(type default)
		)
		(layer "B.Cu")
	)
	(gr_line
		(start 157.263846 -158.47695)
		(end 157.307788 -158.684214)
		(stroke
			(width 0.0635)
			(type default)
		)
		(layer "B.Cu")
	)
	(gr_line
		(start 157.307788 -158.684214)
		(end 157.62732 -158.891732)
		(stroke
			(width 0.0635)
			(type default)
		)
		(layer "B.Cu")
	)
	(gr_line
		(start 157.455108 -158.249874)
		(end 157.965394 -158.581344)
		(stroke
			(width 0.0635)
			(type default)
		)
		(layer "B.Cu")
	)
	(gr_line
		(start 157.62732 -158.891732)
		(end 157.834838 -158.84779)
		(stroke
			(width 0.0635)
			(type default)
		)
		(layer "B.Cu")
	)
	(gr_line
		(start 158.158434 -159.057848)
		(end 158.202376 -159.265366)
		(stroke
			(width 0.0635)
			(type default)
		)
		(layer "B.Cu")
	)
	(gr_line
		(start 158.202376 -159.265366)
		(end 158.521908 -159.472884)
		(stroke
			(width 0.0635)
			(type default)
		)
		(layer "B.Cu")
	)
	(gr_line
		(start 158.348426 -158.83001)
		(end 158.859982 -159.162242)
		(stroke
			(width 0.0635)
			(type default)
		)
		(layer "B.Cu")
	)
	(gr_line
		(start 158.521908 -159.472884)
		(end 158.729426 -159.428688)
		(stroke
			(width 0.0635)
			(type default)
		)
		(layer "B.Cu")
	)
	(gr_line
		(start 159.54375 -152.644602)
		(end 159.587946 -152.85212)
		(stroke
			(width 0.0635)
			(type default)
		)
		(layer "B.Cu")
	)
	(gr_line
		(start 159.587946 -152.85212)
		(end 159.907478 -153.059638)
		(stroke
			(width 0.0635)
			(type default)
		)
		(layer "B.Cu")
	)
	(gr_line
		(start 159.73425 -152.417272)
		(end 160.24606 -152.749504)
		(stroke
			(width 0.0635)
			(type default)
		)
		(layer "B.Cu")
	)
	(gr_line
		(start 159.907478 -153.059638)
		(end 160.114996 -153.015696)
		(stroke
			(width 0.0635)
			(type default)
		)
		(layer "B.Cu")
	)
	(gr_line
		(start 160.438592 -153.225754)
		(end 160.482534 -153.433272)
		(stroke
			(width 0.0635)
			(type default)
		)
		(layer "B.Cu")
	)
	(gr_line
		(start 160.482534 -153.433272)
		(end 160.802066 -153.64079)
		(stroke
			(width 0.0635)
			(type default)
		)
		(layer "B.Cu")
	)
	(gr_line
		(start 160.485582 -245.281196)
		(end 160.485582 -245.562374)
		(stroke
			(width 0.0635)
			(type default)
		)
		(layer "B.Cu")
	)
	(gr_arc
		(start 160.485582 -244.710204)
		(mid 160.525013 -244.805391)
		(end 160.620202 -244.844824)
		(stroke
			(width 0.0635)
			(type default)
		)
		(layer "B.Cu")
	)
	(gr_line
		(start 160.485582 -244.419374)
		(end 160.485582 -244.710204)
		(stroke
			(width 0.0635)
			(type default)
		)
		(layer "B.Cu")
	)
	(gr_line
		(start 160.485582 -130.281172)
		(end 160.485582 -130.56235)
		(stroke
			(width 0.0635)
			(type default)
		)
		(layer "B.Cu")
	)
	(gr_arc
		(start 160.485582 -129.71018)
		(mid 160.525004 -129.805383)
		(end 160.620202 -129.8448)
		(stroke
			(width 0.0635)
			(type default)
		)
		(layer "B.Cu")
	)
	(gr_line
		(start 160.485582 -129.41935)
		(end 160.485582 -129.71018)
		(stroke
			(width 0.0635)
			(type default)
		)
		(layer "B.Cu")
	)
	(gr_line
		(start 160.485582 -15.281148)
		(end 160.485582 -15.562326)
		(stroke
			(width 0.0635)
			(type default)
		)
		(layer "B.Cu")
	)
	(gr_arc
		(start 160.485582 -14.710156)
		(mid 160.524996 -14.805374)
		(end 160.620202 -14.844776)
		(stroke
			(width 0.0635)
			(type default)
		)
		(layer "B.Cu")
	)
	(gr_line
		(start 160.485582 -14.419326)
		(end 160.485582 -14.710156)
		(stroke
			(width 0.0635)
			(type default)
		)
		(layer "B.Cu")
	)
	(gr_line
		(start 160.628076 -152.997408)
		(end 161.141918 -153.331164)
		(stroke
			(width 0.0635)
			(type default)
		)
		(layer "B.Cu")
	)
	(gr_arc
		(start 160.629854 -245.136924)
		(mid 160.527838 -245.17918)
		(end 160.485582 -245.281196)
		(stroke
			(width 0.0635)
			(type default)
		)
		(layer "B.Cu")
	)
	(gr_arc
		(start 160.629854 -130.1369)
		(mid 160.527838 -130.179156)
		(end 160.485582 -130.281172)
		(stroke
			(width 0.0635)
			(type default)
		)
		(layer "B.Cu")
	)
	(gr_arc
		(start 160.629854 -15.136876)
		(mid 160.527838 -15.179132)
		(end 160.485582 -15.281148)
		(stroke
			(width 0.0635)
			(type default)
		)
		(layer "B.Cu")
	)
	(gr_line
		(start 160.802066 -153.64079)
		(end 161.009838 -153.596848)
		(stroke
			(width 0.0635)
			(type default)
		)
		(layer "B.Cu")
	)
	(gr_line
		(start 161.029142 -129.8448)
		(end 161.069528 -129.870962)
		(stroke
			(width 0.0635)
			(type default)
		)
		(layer "B.Cu")
	)
	(gr_line
		(start 161.294572 -130.017012)
		(end 161.315654 -130.030728)
		(stroke
			(width 0.0635)
			(type default)
		)
		(layer "B.Cu")
	)
	(gr_line
		(start 161.315654 -130.030728)
		(end 161.328862 -130.051302)
		(stroke
			(width 0.0635)
			(type default)
		)
		(layer "B.Cu")
	)
	(gr_line
		(start 161.454338 -14.876272)
		(end 161.470594 -14.879828)
		(stroke
			(width 0.0635)
			(type default)
		)
		(layer "B.Cu")
	)
	(gr_line
		(start 161.470594 -14.879828)
		(end 161.484056 -14.888718)
		(stroke
			(width 0.0635)
			(type default)
		)
		(layer "B.Cu")
	)
	(gr_line
		(start 162.060382 -15.262606)
		(end 162.081464 -15.276322)
		(stroke
			(width 0.0635)
			(type default)
		)
		(layer "B.Cu")
	)
	(gr_line
		(start 162.081464 -15.276322)
		(end 162.094672 -15.296896)
		(stroke
			(width 0.0635)
			(type default)
		)
		(layer "B.Cu")
	)
	(gr_line
		(start 162.728402 -16.273018)
		(end 162.737292 -16.28648)
		(stroke
			(width 0.0635)
			(type default)
		)
		(layer "B.Cu")
	)
	(gr_line
		(start 162.737292 -16.28648)
		(end 162.740848 -16.302736)
		(stroke
			(width 0.0635)
			(type default)
		)
		(layer "B.Cu")
	)
	(gr_line
		(start 162.749738 -18.483072)
		(end 162.828732 -18.85569)
		(stroke
			(width 0.0635)
			(type default)
		)
		(layer "B.Cu")
	)
	(gr_line
		(start 162.749738 -18.483072)
		(end 162.865054 -18.305272)
		(stroke
			(width 0.0635)
			(type default)
		)
		(layer "B.Cu")
	)
	(gr_line
		(start 162.828732 -18.85569)
		(end 163.006786 -18.97126)
		(stroke
			(width 0.0635)
			(type default)
		)
		(layer "B.Cu")
	)
	(gr_line
		(start 162.97148 -19.526504)
		(end 163.050728 -19.899376)
		(stroke
			(width 0.0635)
			(type default)
		)
		(layer "B.Cu")
	)
	(gr_line
		(start 162.97148 -19.526504)
		(end 163.08705 -19.348704)
		(stroke
			(width 0.0635)
			(type default)
		)
		(layer "B.Cu")
	)
	(gr_line
		(start 163.050728 -19.899376)
		(end 163.228528 -20.014946)
		(stroke
			(width 0.0635)
			(type default)
		)
		(layer "B.Cu")
	)
	(gr_line
		(start 163.160964 -18.279618)
		(end 163.287456 -18.87474)
		(stroke
			(width 0.0635)
			(type default)
		)
		(layer "B.Cu")
	)
	(gr_line
		(start 163.193222 -20.57019)
		(end 163.27247 -20.942808)
		(stroke
			(width 0.0635)
			(type default)
		)
		(layer "B.Cu")
	)
	(gr_line
		(start 163.193222 -20.57019)
		(end 163.308792 -20.392136)
		(stroke
			(width 0.0635)
			(type default)
		)
		(layer "B.Cu")
	)
	(gr_line
		(start 163.27247 -20.942808)
		(end 163.45027 -21.058124)
		(stroke
			(width 0.0635)
			(type default)
		)
		(layer "B.Cu")
	)
	(gr_line
		(start 163.382706 -19.323304)
		(end 163.509452 -19.919696)
		(stroke
			(width 0.0635)
			(type default)
		)
		(layer "B.Cu")
	)
	(gr_line
		(start 163.414964 -21.613622)
		(end 163.494212 -21.98624)
		(stroke
			(width 0.0635)
			(type default)
		)
		(layer "B.Cu")
	)
	(gr_line
		(start 163.414964 -21.613622)
		(end 163.530534 -21.435568)
		(stroke
			(width 0.0635)
			(type default)
		)
		(layer "B.Cu")
	)
	(gr_line
		(start 163.494212 -21.98624)
		(end 163.672012 -22.101556)
		(stroke
			(width 0.0635)
			(type default)
		)
		(layer "B.Cu")
	)
	(gr_line
		(start 163.604194 -20.364196)
		(end 163.731194 -20.961858)
		(stroke
			(width 0.0635)
			(type default)
		)
		(layer "B.Cu")
	)
	(gr_line
		(start 163.825936 -21.407882)
		(end 163.952936 -22.005544)
		(stroke
			(width 0.0635)
			(type default)
		)
		(layer "B.Cu")
	)
	(gr_line
		(start 164.966142 -372.724934)
		(end 165.1 -372.858792)
		(stroke
			(width 0.127)
			(type default)
		)
		(layer "B.Cu")
	)
	(gr_line
		(start 164.966142 -372.003066)
		(end 165.1 -371.869208)
		(stroke
			(width 0.127)
			(type default)
		)
		(layer "B.Cu")
	)
	(gr_line
		(start 165.773354 -104.516428)
		(end 165.786562 -104.537002)
		(stroke
			(width 0.0635)
			(type default)
		)
		(layer "B.Cu")
	)
	(gr_line
		(start 165.786562 -104.537002)
		(end 165.807136 -104.55021)
		(stroke
			(width 0.0635)
			(type default)
		)
		(layer "B.Cu")
	)
	(gr_line
		(start 167.069008 -139.706604)
		(end 167.11295 -139.498832)
		(stroke
			(width 0.0635)
			(type default)
		)
		(layer "B.Cu")
	)
	(gr_line
		(start 167.069008 -139.706604)
		(end 167.276526 -140.026136)
		(stroke
			(width 0.0635)
			(type default)
		)
		(layer "B.Cu")
	)
	(gr_line
		(start 167.124634 -370.057934)
		(end 167.2717 -370.205)
		(stroke
			(width 0.127)
			(type default)
		)
		(layer "B.Cu")
	)
	(gr_line
		(start 167.124634 -369.336066)
		(end 167.2717 -369.189)
		(stroke
			(width 0.127)
			(type default)
		)
		(layer "B.Cu")
	)
	(gr_line
		(start 167.276526 -140.026136)
		(end 167.484044 -140.070078)
		(stroke
			(width 0.0635)
			(type default)
		)
		(layer "B.Cu")
	)
	(gr_line
		(start 167.378888 -139.36726)
		(end 167.711882 -139.880086)
		(stroke
			(width 0.0635)
			(type default)
		)
		(layer "B.Cu")
	)
	(gr_line
		(start 167.649906 -140.601192)
		(end 167.694102 -140.393674)
		(stroke
			(width 0.0635)
			(type default)
		)
		(layer "B.Cu")
	)
	(gr_line
		(start 167.649906 -140.601192)
		(end 167.857424 -140.920724)
		(stroke
			(width 0.0635)
			(type default)
		)
		(layer "B.Cu")
	)
	(gr_line
		(start 167.857424 -140.920724)
		(end 168.065196 -140.96492)
		(stroke
			(width 0.0635)
			(type default)
		)
		(layer "B.Cu")
	)
	(gr_line
		(start 167.960548 -140.263118)
		(end 168.293542 -140.77569)
		(stroke
			(width 0.0635)
			(type default)
		)
		(layer "B.Cu")
	)
	(gr_line
		(start 168.1607 -370.205)
		(end 168.307766 -370.057934)
		(stroke
			(width 0.127)
			(type default)
		)
		(layer "B.Cu")
	)
	(gr_line
		(start 168.1607 -369.189)
		(end 168.307766 -369.336066)
		(stroke
			(width 0.127)
			(type default)
		)
		(layer "B.Cu")
	)
	(gr_line
		(start 168.231058 -141.496034)
		(end 168.275 -141.288262)
		(stroke
			(width 0.0635)
			(type default)
		)
		(layer "B.Cu")
	)
	(gr_line
		(start 168.231058 -141.496034)
		(end 168.438576 -141.815566)
		(stroke
			(width 0.0635)
			(type default)
		)
		(layer "B.Cu")
	)
	(gr_line
		(start 168.438576 -141.815566)
		(end 168.646094 -141.859508)
		(stroke
			(width 0.0635)
			(type default)
		)
		(layer "B.Cu")
	)
	(gr_line
		(start 168.540938 -141.15669)
		(end 168.873932 -141.669516)
		(stroke
			(width 0.0635)
			(type default)
		)
		(layer "B.Cu")
	)
	(gr_line
		(start 168.811956 -142.390622)
		(end 168.856152 -142.183104)
		(stroke
			(width 0.0635)
			(type default)
		)
		(layer "B.Cu")
	)
	(gr_line
		(start 168.811956 -142.390622)
		(end 169.019474 -142.710154)
		(stroke
			(width 0.0635)
			(type default)
		)
		(layer "B.Cu")
	)
	(gr_line
		(start 168.813734 -370.057934)
		(end 169.0878 -370.332)
		(stroke
			(width 0.127)
			(type default)
		)
		(layer "B.Cu")
	)
	(gr_line
		(start 168.813734 -369.336066)
		(end 169.0878 -369.062)
		(stroke
			(width 0.127)
			(type default)
		)
		(layer "B.Cu")
	)
	(gr_line
		(start 169.019474 -142.710154)
		(end 169.227246 -142.75435)
		(stroke
			(width 0.0635)
			(type default)
		)
		(layer "B.Cu")
	)
	(gr_line
		(start 169.0878 -372.999)
		(end 169.361866 -372.724934)
		(stroke
			(width 0.127)
			(type default)
		)
		(layer "B.Cu")
	)
	(gr_line
		(start 169.0878 -371.729)
		(end 169.361866 -372.003066)
		(stroke
			(width 0.127)
			(type default)
		)
		(layer "B.Cu")
	)
	(gr_line
		(start 169.122598 -142.052294)
		(end 169.455084 -142.564358)
		(stroke
			(width 0.0635)
			(type default)
		)
		(layer "B.Cu")
	)
	(gr_line
		(start 169.961814 -372.724934)
		(end 170.04538 -372.8085)
		(stroke
			(width 0.127)
			(type default)
		)
		(layer "B.Cu")
	)
	(gr_line
		(start 169.961814 -372.003066)
		(end 170.04538 -371.9195)
		(stroke
			(width 0.127)
			(type default)
		)
		(layer "B.Cu")
	)
	(gr_line
		(start 170.04538 -372.8085)
		(end 170.128946 -372.724934)
		(stroke
			(width 0.127)
			(type default)
		)
		(layer "B.Cu")
	)
	(gr_line
		(start 170.04538 -371.9195)
		(end 170.128946 -372.003066)
		(stroke
			(width 0.127)
			(type default)
		)
		(layer "B.Cu")
	)
	(gr_line
		(start 171.5897 -370.515134)
		(end 172.054774 -370.05006)
		(stroke
			(width 0.127)
			(type default)
		)
		(layer "B.Cu")
	)
	(gr_line
		(start 171.5897 -368.862864)
		(end 172.054774 -369.327938)
		(stroke
			(width 0.127)
			(type default)
		)
		(layer "B.Cu")
	)
	(gr_line
		(start 178.382676 -164.878512)
		(end 178.429666 -165.100508)
		(stroke
			(width 0.0635)
			(type default)
		)
		(layer "B.Cu")
	)
	(gr_line
		(start 178.429666 -165.100508)
		(end 178.749198 -165.308026)
		(stroke
			(width 0.0635)
			(type default)
		)
		(layer "B.Cu")
	)
	(gr_line
		(start 178.573176 -164.651436)
		(end 179.101242 -164.994082)
		(stroke
			(width 0.0635)
			(type default)
		)
		(layer "B.Cu")
	)
	(gr_line
		(start 178.749198 -165.308026)
		(end 178.97094 -165.260782)
		(stroke
			(width 0.0635)
			(type default)
		)
		(layer "B.Cu")
	)
	(gr_line
		(start 179.294536 -165.47084)
		(end 179.341526 -165.692582)
		(stroke
			(width 0.0635)
			(type default)
		)
		(layer "B.Cu")
	)
	(gr_line
		(start 179.341526 -165.692582)
		(end 179.661058 -165.9001)
		(stroke
			(width 0.0635)
			(type default)
		)
		(layer "B.Cu")
	)
	(gr_line
		(start 179.485036 -165.243256)
		(end 180.01361 -165.586664)
		(stroke
			(width 0.0635)
			(type default)
		)
		(layer "B.Cu")
	)
	(gr_line
		(start 179.661058 -165.9001)
		(end 179.882546 -165.852856)
		(stroke
			(width 0.0635)
			(type default)
		)
		(layer "B.Cu")
	)
	(gr_line
		(start 180.231288 -99.996244)
		(end 180.234844 -100.0125)
		(stroke
			(width 0.0635)
			(type default)
		)
		(layer "B.Cu")
	)
	(gr_line
		(start 180.234844 -100.0125)
		(end 180.243734 -100.025962)
		(stroke
			(width 0.0635)
			(type default)
		)
		(layer "B.Cu")
	)
	(gr_line
		(start 183.12511 -170.766232)
		(end 183.169306 -170.974004)
		(stroke
			(width 0.0635)
			(type default)
		)
		(layer "B.Cu")
	)
	(gr_line
		(start 183.169306 -170.974004)
		(end 183.488838 -171.181268)
		(stroke
			(width 0.0635)
			(type default)
		)
		(layer "B.Cu")
	)
	(gr_line
		(start 183.315102 -170.538648)
		(end 183.82615 -170.870372)
		(stroke
			(width 0.0635)
			(type default)
		)
		(layer "B.Cu")
	)
	(gr_line
		(start 183.488838 -171.181268)
		(end 183.696356 -171.137326)
		(stroke
			(width 0.0635)
			(type default)
		)
		(layer "B.Cu")
	)
	(gr_line
		(start 183.798718 -165.188138)
		(end 183.811926 -165.208712)
		(stroke
			(width 0.0635)
			(type default)
		)
		(layer "B.Cu")
	)
	(gr_line
		(start 183.811926 -165.208712)
		(end 183.8325 -165.22192)
		(stroke
			(width 0.0635)
			(type default)
		)
		(layer "B.Cu")
	)
	(gr_line
		(start 184.019952 -171.347384)
		(end 184.063894 -171.554902)
		(stroke
			(width 0.0635)
			(type default)
		)
		(layer "B.Cu")
	)
	(gr_line
		(start 184.063894 -171.554902)
		(end 184.383426 -171.76242)
		(stroke
			(width 0.0635)
			(type default)
		)
		(layer "B.Cu")
	)
	(gr_line
		(start 184.210706 -171.120054)
		(end 184.721754 -171.452032)
		(stroke
			(width 0.0635)
			(type default)
		)
		(layer "B.Cu")
	)
	(gr_line
		(start 184.383426 -171.76242)
		(end 184.591198 -171.718478)
		(stroke
			(width 0.0635)
			(type default)
		)
		(layer "B.Cu")
	)
	(gr_line
		(start 184.91454 -171.928282)
		(end 184.958482 -172.1358)
		(stroke
			(width 0.0635)
			(type default)
		)
		(layer "B.Cu")
	)
	(gr_line
		(start 184.958482 -172.1358)
		(end 185.278014 -172.343318)
		(stroke
			(width 0.0635)
			(type default)
		)
		(layer "B.Cu")
	)
	(gr_line
		(start 185.10631 -171.701968)
		(end 185.616596 -172.033184)
		(stroke
			(width 0.0635)
			(type default)
		)
		(layer "B.Cu")
	)
	(gr_line
		(start 185.278014 -172.343318)
		(end 185.485786 -172.299376)
		(stroke
			(width 0.0635)
			(type default)
		)
		(layer "B.Cu")
	)
	(gr_line
		(start 185.809128 -172.50918)
		(end 185.853324 -172.716952)
		(stroke
			(width 0.0635)
			(type default)
		)
		(layer "B.Cu")
	)
	(gr_line
		(start 185.853324 -172.716952)
		(end 186.172856 -172.92447)
		(stroke
			(width 0.0635)
			(type default)
		)
		(layer "B.Cu")
	)
	(gr_line
		(start 185.998104 -172.28058)
		(end 186.510676 -172.613574)
		(stroke
			(width 0.0635)
			(type default)
		)
		(layer "B.Cu")
	)
	(gr_line
		(start 186.172856 -172.92447)
		(end 186.380374 -172.880274)
		(stroke
			(width 0.0635)
			(type default)
		)
		(layer "B.Cu")
	)
	(gr_line
		(start 188.078618 -41.453816)
		(end 188.083698 -41.47693)
		(stroke
			(width 0.0635)
			(type default)
		)
		(layer "B.Cu")
	)
	(gr_line
		(start 188.078618 -41.453816)
		(end 188.083698 -41.430194)
		(stroke
			(width 0.0635)
			(type default)
		)
		(layer "B.Cu")
	)
	(gr_line
		(start 190.66129 -54.338728)
		(end 190.740538 -54.711346)
		(stroke
			(width 0.0635)
			(type default)
		)
		(layer "B.Cu")
	)
	(gr_line
		(start 190.66129 -54.338728)
		(end 190.77686 -54.16042)
		(stroke
			(width 0.0635)
			(type default)
		)
		(layer "B.Cu")
	)
	(gr_line
		(start 190.740538 -54.711346)
		(end 190.918592 -54.826916)
		(stroke
			(width 0.0635)
			(type default)
		)
		(layer "B.Cu")
	)
	(gr_line
		(start 190.883286 -55.38216)
		(end 190.96228 -55.754778)
		(stroke
			(width 0.0635)
			(type default)
		)
		(layer "B.Cu")
	)
	(gr_line
		(start 190.883286 -55.38216)
		(end 190.998856 -55.204106)
		(stroke
			(width 0.0635)
			(type default)
		)
		(layer "B.Cu")
	)
	(gr_line
		(start 190.96228 -55.754778)
		(end 191.140334 -55.870348)
		(stroke
			(width 0.0635)
			(type default)
		)
		(layer "B.Cu")
	)
	(gr_line
		(start 191.072262 -54.132226)
		(end 191.19977 -54.732174)
		(stroke
			(width 0.0635)
			(type default)
		)
		(layer "B.Cu")
	)
	(gr_line
		(start 191.105028 -56.425592)
		(end 191.184276 -56.79821)
		(stroke
			(width 0.0635)
			(type default)
		)
		(layer "B.Cu")
	)
	(gr_line
		(start 191.105028 -56.425592)
		(end 191.220598 -56.247538)
		(stroke
			(width 0.0635)
			(type default)
		)
		(layer "B.Cu")
	)
	(gr_line
		(start 191.184276 -56.79821)
		(end 191.362076 -56.91378)
		(stroke
			(width 0.0635)
			(type default)
		)
		(layer "B.Cu")
	)
	(gr_line
		(start 191.294258 -55.177436)
		(end 191.421258 -55.77459)
		(stroke
			(width 0.0635)
			(type default)
		)
		(layer "B.Cu")
	)
	(gr_line
		(start 191.32677 -57.469024)
		(end 191.406018 -57.841642)
		(stroke
			(width 0.0635)
			(type default)
		)
		(layer "B.Cu")
	)
	(gr_line
		(start 191.32677 -57.469024)
		(end 191.44234 -57.291224)
		(stroke
			(width 0.0635)
			(type default)
		)
		(layer "B.Cu")
	)
	(gr_line
		(start 191.406018 -57.841642)
		(end 191.584072 -57.957466)
		(stroke
			(width 0.0635)
			(type default)
		)
		(layer "B.Cu")
	)
	(gr_line
		(start 191.516254 -56.222138)
		(end 191.642746 -56.81726)
		(stroke
			(width 0.0635)
			(type default)
		)
		(layer "B.Cu")
	)
	(gr_line
		(start 191.59601 -184.42559)
		(end 191.640206 -184.633108)
		(stroke
			(width 0.0635)
			(type default)
		)
		(layer "B.Cu")
	)
	(gr_line
		(start 191.640206 -184.633108)
		(end 191.959738 -184.840626)
		(stroke
			(width 0.0635)
			(type default)
		)
		(layer "B.Cu")
	)
	(gr_line
		(start 191.737996 -57.265824)
		(end 191.864742 -57.862216)
		(stroke
			(width 0.0635)
			(type default)
		)
		(layer "B.Cu")
	)
	(gr_line
		(start 191.786002 -184.197752)
		(end 192.297812 -184.529984)
		(stroke
			(width 0.0635)
			(type default)
		)
		(layer "B.Cu")
	)
	(gr_line
		(start 191.959738 -184.840626)
		(end 192.167256 -184.79643)
		(stroke
			(width 0.0635)
			(type default)
		)
		(layer "B.Cu")
	)
	(gr_line
		(start 192.035684 -245.281196)
		(end 192.035684 -245.562374)
		(stroke
			(width 0.0635)
			(type default)
		)
		(layer "B.Cu")
	)
	(gr_arc
		(start 192.035684 -244.710204)
		(mid 192.075115 -244.805391)
		(end 192.170304 -244.844824)
		(stroke
			(width 0.0635)
			(type default)
		)
		(layer "B.Cu")
	)
	(gr_line
		(start 192.035684 -244.419374)
		(end 192.035684 -244.710204)
		(stroke
			(width 0.0635)
			(type default)
		)
		(layer "B.Cu")
	)
	(gr_line
		(start 192.035684 -130.281172)
		(end 192.035684 -130.56235)
		(stroke
			(width 0.0635)
			(type default)
		)
		(layer "B.Cu")
	)
	(gr_arc
		(start 192.035684 -129.71018)
		(mid 192.075106 -129.805382)
		(end 192.170304 -129.8448)
		(stroke
			(width 0.0635)
			(type default)
		)
		(layer "B.Cu")
	)
	(gr_line
		(start 192.035684 -129.41935)
		(end 192.035684 -129.71018)
		(stroke
			(width 0.0635)
			(type default)
		)
		(layer "B.Cu")
	)
	(gr_line
		(start 192.035684 -15.281148)
		(end 192.035684 -15.562326)
		(stroke
			(width 0.0635)
			(type default)
		)
		(layer "B.Cu")
	)
	(gr_arc
		(start 192.035684 -14.710156)
		(mid 192.075098 -14.805374)
		(end 192.170304 -14.844776)
		(stroke
			(width 0.0635)
			(type default)
		)
		(layer "B.Cu")
	)
	(gr_line
		(start 192.035684 -14.419326)
		(end 192.035684 -14.710156)
		(stroke
			(width 0.0635)
			(type default)
		)
		(layer "B.Cu")
	)
	(gr_arc
		(start 192.179956 -245.136924)
		(mid 192.07794 -245.17918)
		(end 192.035684 -245.281196)
		(stroke
			(width 0.0635)
			(type default)
		)
		(layer "B.Cu")
	)
	(gr_arc
		(start 192.179956 -130.1369)
		(mid 192.07794 -130.179156)
		(end 192.035684 -130.281172)
		(stroke
			(width 0.0635)
			(type default)
		)
		(layer "B.Cu")
	)
	(gr_arc
		(start 192.179956 -15.136876)
		(mid 192.07794 -15.179132)
		(end 192.035684 -15.281148)
		(stroke
			(width 0.0635)
			(type default)
		)
		(layer "B.Cu")
	)
	(gr_line
		(start 192.490852 -185.006488)
		(end 192.535048 -185.214006)
		(stroke
			(width 0.0635)
			(type default)
		)
		(layer "B.Cu")
	)
	(gr_line
		(start 192.535048 -185.214006)
		(end 192.85458 -185.421524)
		(stroke
			(width 0.0635)
			(type default)
		)
		(layer "B.Cu")
	)
	(gr_line
		(start 192.681352 -184.779158)
		(end 193.1924 -185.110628)
		(stroke
			(width 0.0635)
			(type default)
		)
		(layer "B.Cu")
	)
	(gr_line
		(start 192.748662 -14.844776)
		(end 192.789048 -14.871192)
		(stroke
			(width 0.0635)
			(type default)
		)
		(layer "B.Cu")
	)
	(gr_line
		(start 192.85458 -185.421524)
		(end 193.062098 -185.377328)
		(stroke
			(width 0.0635)
			(type default)
		)
		(layer "B.Cu")
	)
	(gr_line
		(start 193.050922 -15.041372)
		(end 193.072258 -15.055342)
		(stroke
			(width 0.0635)
			(type default)
		)
		(layer "B.Cu")
	)
	(gr_line
		(start 193.072258 -15.055342)
		(end 193.086228 -15.076678)
		(stroke
			(width 0.0635)
			(type default)
		)
		(layer "B.Cu")
	)
	(gr_line
		(start 193.08318 -129.893568)
		(end 193.099436 -129.897124)
		(stroke
			(width 0.0635)
			(type default)
		)
		(layer "B.Cu")
	)
	(gr_line
		(start 193.099436 -129.897124)
		(end 193.112898 -129.906014)
		(stroke
			(width 0.0635)
			(type default)
		)
		(layer "B.Cu")
	)
	(gr_line
		(start 193.25209 -15.332202)
		(end 193.26098 -15.345664)
		(stroke
			(width 0.0635)
			(type default)
		)
		(layer "B.Cu")
	)
	(gr_line
		(start 193.26098 -15.345664)
		(end 193.264536 -15.36192)
		(stroke
			(width 0.0635)
			(type default)
		)
		(layer "B.Cu")
	)
	(gr_line
		(start 193.385694 -185.587386)
		(end 193.429636 -185.794904)
		(stroke
			(width 0.0635)
			(type default)
		)
		(layer "B.Cu")
	)
	(gr_line
		(start 193.411856 -217.437208)
		(end 193.424556 -217.43543)
		(stroke
			(width 0.0635)
			(type default)
		)
		(layer "B.Cu")
	)
	(gr_line
		(start 193.424556 -217.43543)
		(end 193.436494 -217.43797)
		(stroke
			(width 0.0635)
			(type default)
		)
		(layer "B.Cu")
	)
	(gr_line
		(start 193.429636 -185.794904)
		(end 193.749168 -186.002422)
		(stroke
			(width 0.0635)
			(type default)
		)
		(layer "B.Cu")
	)
	(gr_line
		(start 193.432176 -130.113532)
		(end 193.451734 -130.126232)
		(stroke
			(width 0.0635)
			(type default)
		)
		(layer "B.Cu")
	)
	(gr_line
		(start 193.451734 -130.126232)
		(end 193.464434 -130.146044)
		(stroke
			(width 0.0635)
			(type default)
		)
		(layer "B.Cu")
	)
	(gr_line
		(start 193.576702 -185.36031)
		(end 194.08775 -185.692034)
		(stroke
			(width 0.0635)
			(type default)
		)
		(layer "B.Cu")
	)
	(gr_line
		(start 193.588894 -16.934688)
		(end 193.593974 -16.911574)
		(stroke
			(width 0.0635)
			(type default)
		)
		(layer "B.Cu")
	)
	(gr_line
		(start 193.588894 -16.887952)
		(end 193.593974 -16.911574)
		(stroke
			(width 0.0635)
			(type default)
		)
		(layer "B.Cu")
	)
	(gr_line
		(start 193.749168 -186.002422)
		(end 193.956686 -185.958226)
		(stroke
			(width 0.0635)
			(type default)
		)
		(layer "B.Cu")
	)
	(gr_line
		(start 193.776092 -120.866662)
		(end 193.7893 -120.887236)
		(stroke
			(width 0.0635)
			(type default)
		)
		(layer "B.Cu")
	)
	(gr_line
		(start 193.7893 -120.887236)
		(end 193.809874 -120.900444)
		(stroke
			(width 0.0635)
			(type default)
		)
		(layer "B.Cu")
	)
	(gr_line
		(start 193.838068 -130.721354)
		(end 193.84645 -130.734308)
		(stroke
			(width 0.0635)
			(type default)
		)
		(layer "B.Cu")
	)
	(gr_line
		(start 193.84645 -130.734308)
		(end 193.849752 -130.749802)
		(stroke
			(width 0.0635)
			(type default)
		)
		(layer "B.Cu")
	)
	(gr_line
		(start 194.280536 -186.168284)
		(end 194.324478 -186.375802)
		(stroke
			(width 0.0635)
			(type default)
		)
		(layer "B.Cu")
	)
	(gr_line
		(start 194.324478 -186.375802)
		(end 194.64401 -186.583066)
		(stroke
			(width 0.0635)
			(type default)
		)
		(layer "B.Cu")
	)
	(gr_line
		(start 194.470528 -185.940446)
		(end 194.983354 -186.273186)
		(stroke
			(width 0.0635)
			(type default)
		)
		(layer "B.Cu")
	)
	(gr_line
		(start 194.64401 -186.583066)
		(end 194.851528 -186.539124)
		(stroke
			(width 0.0635)
			(type default)
		)
		(layer "B.Cu")
	)
	(gr_line
		(start 195.936362 -107.070144)
		(end 195.941442 -107.093258)
		(stroke
			(width 0.0635)
			(type default)
		)
		(layer "B.Cu")
	)
	(gr_line
		(start 195.936362 -107.070144)
		(end 195.941442 -107.046522)
		(stroke
			(width 0.0635)
			(type default)
		)
		(layer "B.Cu")
	)
	(gr_line
		(start 196.021452 -142.427706)
		(end 196.024754 -142.4432)
		(stroke
			(width 0.0635)
			(type default)
		)
		(layer "B.Cu")
	)
	(gr_line
		(start 196.024754 -142.4432)
		(end 196.033136 -142.456154)
		(stroke
			(width 0.0635)
			(type default)
		)
		(layer "B.Cu")
	)
	(gr_line
		(start 198.44258 -118.861586)
		(end 198.446136 -118.877842)
		(stroke
			(width 0.0635)
			(type default)
		)
		(layer "B.Cu")
	)
	(gr_line
		(start 198.446136 -118.877842)
		(end 198.455026 -118.891304)
		(stroke
			(width 0.0635)
			(type default)
		)
		(layer "B.Cu")
	)
	(gr_line
		(start 199.27443 -92.769182)
		(end 199.27951 -92.746068)
		(stroke
			(width 0.0635)
			(type default)
		)
		(layer "B.Cu")
	)
	(gr_line
		(start 199.27443 -92.722446)
		(end 199.27951 -92.746068)
		(stroke
			(width 0.0635)
			(type default)
		)
		(layer "B.Cu")
	)
	(gr_line
		(start 201.661268 -220.816424)
		(end 201.683874 -220.811852)
		(stroke
			(width 0.0635)
			(type default)
		)
		(layer "B.Cu")
	)
	(gr_line
		(start 201.683874 -220.811852)
		(end 201.706226 -220.816678)
		(stroke
			(width 0.0635)
			(type default)
		)
		(layer "B.Cu")
	)
	(gr_line
		(start 202.027282 -124.39269)
		(end 202.04049 -124.413264)
		(stroke
			(width 0.0635)
			(type default)
		)
		(layer "B.Cu")
	)
	(gr_line
		(start 202.04049 -124.413264)
		(end 202.061064 -124.426472)
		(stroke
			(width 0.0635)
			(type default)
		)
		(layer "B.Cu")
	)
	(gr_line
		(start 202.306428 -221.24543)
		(end 202.421998 -221.42323)
		(stroke
			(width 0.0635)
			(type default)
		)
		(layer "B.Cu")
	)
	(gr_line
		(start 202.401932 -220.964506)
		(end 202.999086 -221.091506)
		(stroke
			(width 0.0635)
			(type default)
		)
		(layer "B.Cu")
	)
	(gr_line
		(start 202.421998 -221.42323)
		(end 202.79487 -221.502478)
		(stroke
			(width 0.0635)
			(type default)
		)
		(layer "B.Cu")
	)
	(gr_line
		(start 202.79487 -221.502478)
		(end 202.97267 -221.386908)
		(stroke
			(width 0.0635)
			(type default)
		)
		(layer "B.Cu")
	)
	(gr_line
		(start 203.34986 -221.467172)
		(end 203.465684 -221.645226)
		(stroke
			(width 0.0635)
			(type default)
		)
		(layer "B.Cu")
	)
	(gr_line
		(start 203.445618 -221.186248)
		(end 204.041756 -221.312994)
		(stroke
			(width 0.0635)
			(type default)
		)
		(layer "B.Cu")
	)
	(gr_line
		(start 203.465684 -221.645226)
		(end 203.838302 -221.724474)
		(stroke
			(width 0.0635)
			(type default)
		)
		(layer "B.Cu")
	)
	(gr_line
		(start 203.838302 -221.724474)
		(end 204.016102 -221.60865)
		(stroke
			(width 0.0635)
			(type default)
		)
		(layer "B.Cu")
	)
	(gr_line
		(start 204.393546 -221.689168)
		(end 204.509116 -221.866968)
		(stroke
			(width 0.0635)
			(type default)
		)
		(layer "B.Cu")
	)
	(gr_line
		(start 204.491336 -221.408752)
		(end 205.086204 -221.535244)
		(stroke
			(width 0.0635)
			(type default)
		)
		(layer "B.Cu")
	)
	(gr_line
		(start 204.509116 -221.866968)
		(end 204.881734 -221.946216)
		(stroke
			(width 0.0635)
			(type default)
		)
		(layer "B.Cu")
	)
	(gr_line
		(start 204.881734 -221.946216)
		(end 205.059788 -221.830646)
		(stroke
			(width 0.0635)
			(type default)
		)
		(layer "B.Cu")
	)
	(gr_line
		(start 205.437232 -221.91091)
		(end 205.552548 -222.08871)
		(stroke
			(width 0.0635)
			(type default)
		)
		(layer "B.Cu")
	)
	(gr_line
		(start 205.534514 -221.630494)
		(end 206.130398 -221.756986)
		(stroke
			(width 0.0635)
			(type default)
		)
		(layer "B.Cu")
	)
	(gr_line
		(start 205.552548 -222.08871)
		(end 205.925166 -222.167958)
		(stroke
			(width 0.0635)
			(type default)
		)
		(layer "B.Cu")
	)
	(gr_line
		(start 205.925166 -222.167958)
		(end 206.10322 -222.052388)
		(stroke
			(width 0.0635)
			(type default)
		)
		(layer "B.Cu")
	)
	(gr_line
		(start 207.369918 -223.748854)
		(end 207.39227 -223.744282)
		(stroke
			(width 0.0635)
			(type default)
		)
		(layer "B.Cu")
	)
	(gr_line
		(start 207.380078 -160.208976)
		(end 207.424274 -160.001458)
		(stroke
			(width 0.0635)
			(type default)
		)
		(layer "B.Cu")
	)
	(gr_line
		(start 207.380078 -160.208976)
		(end 207.587596 -160.528508)
		(stroke
			(width 0.0635)
			(type default)
		)
		(layer "B.Cu")
	)
	(gr_line
		(start 207.39227 -223.744282)
		(end 207.414114 -223.749108)
		(stroke
			(width 0.0635)
			(type default)
		)
		(layer "B.Cu")
	)
	(gr_line
		(start 207.587596 -160.528508)
		(end 207.795114 -160.57245)
		(stroke
			(width 0.0635)
			(type default)
		)
		(layer "B.Cu")
	)
	(gr_line
		(start 207.691228 -159.871664)
		(end 208.02219 -160.381442)
		(stroke
			(width 0.0635)
			(type default)
		)
		(layer "B.Cu")
	)
	(gr_line
		(start 207.96123 -161.103564)
		(end 208.005172 -160.896046)
		(stroke
			(width 0.0635)
			(type default)
		)
		(layer "B.Cu")
	)
	(gr_line
		(start 207.96123 -161.103564)
		(end 208.168748 -161.423096)
		(stroke
			(width 0.0635)
			(type default)
		)
		(layer "B.Cu")
	)
	(gr_line
		(start 208.168748 -161.423096)
		(end 208.376266 -161.467292)
		(stroke
			(width 0.0635)
			(type default)
		)
		(layer "B.Cu")
	)
	(gr_line
		(start 208.271872 -160.765744)
		(end 208.603342 -161.276284)
		(stroke
			(width 0.0635)
			(type default)
		)
		(layer "B.Cu")
	)
	(gr_line
		(start 208.539334 -162.012376)
		(end 208.586324 -161.790888)
		(stroke
			(width 0.0635)
			(type default)
		)
		(layer "B.Cu")
	)
	(gr_line
		(start 208.539334 -162.012376)
		(end 208.746852 -162.331908)
		(stroke
			(width 0.0635)
			(type default)
		)
		(layer "B.Cu")
	)
	(gr_line
		(start 208.746852 -162.331908)
		(end 208.96834 -162.379152)
		(stroke
			(width 0.0635)
			(type default)
		)
		(layer "B.Cu")
	)
	(gr_line
		(start 208.853278 -161.661094)
		(end 209.196178 -162.18916)
		(stroke
			(width 0.0635)
			(type default)
		)
		(layer "B.Cu")
	)
	(gr_line
		(start 209.131408 -162.924236)
		(end 209.178398 -162.702748)
		(stroke
			(width 0.0635)
			(type default)
		)
		(layer "B.Cu")
	)
	(gr_line
		(start 209.131408 -162.924236)
		(end 209.338926 -163.243768)
		(stroke
			(width 0.0635)
			(type default)
		)
		(layer "B.Cu")
	)
	(gr_line
		(start 209.338926 -163.243768)
		(end 209.560414 -163.290758)
		(stroke
			(width 0.0635)
			(type default)
		)
		(layer "B.Cu")
	)
	(gr_line
		(start 209.445352 -162.572954)
		(end 209.787744 -163.100258)
		(stroke
			(width 0.0635)
			(type default)
		)
		(layer "B.Cu")
	)
	(gr_arc
		(start 209.811874 -74.553826)
		(mid 209.944961 -74.498699)
		(end 210.000088 -74.365612)
		(stroke
			(width 0.08255)
			(type default)
		)
		(layer "B.Cu")
	)
	(gr_line
		(start 210.000088 -78.634082)
		(end 210.000088 -78.999842)
		(stroke
			(width 0.08255)
			(type default)
		)
		(layer "B.Cu")
	)
	(gr_arc
		(start 210.000088 -77.965554)
		(mid 210.055198 -78.09867)
		(end 210.188302 -78.153768)
		(stroke
			(width 0.08255)
			(type default)
		)
		(layer "B.Cu")
	)
	(gr_line
		(start 210.000088 -77.600048)
		(end 210.000088 -77.965554)
		(stroke
			(width 0.08255)
			(type default)
		)
		(layer "B.Cu")
	)
	(gr_arc
		(start 210.000088 -75.03414)
		(mid 209.944974 -74.901036)
		(end 209.811874 -74.845926)
		(stroke
			(width 0.08255)
			(type default)
		)
		(layer "B.Cu")
	)
	(gr_line
		(start 210.000088 -75.03414)
		(end 210.000088 -75.3999)
		(stroke
			(width 0.08255)
			(type default)
		)
		(layer "B.Cu")
	)
	(gr_line
		(start 210.000088 -73.999852)
		(end 210.000088 -74.365612)
		(stroke
			(width 0.08255)
			(type default)
		)
		(layer "B.Cu")
	)
	(gr_arc
		(start 210.188302 -78.445868)
		(mid 210.055215 -78.500995)
		(end 210.000088 -78.634082)
		(stroke
			(width 0.08255)
			(type default)
		)
		(layer "B.Cu")
	)
	(gr_line
		(start 210.256628 -90.76944)
		(end 210.260184 -90.785696)
		(stroke
			(width 0.08255)
			(type default)
		)
		(layer "B.Cu")
	)
	(gr_line
		(start 210.260184 -90.785696)
		(end 210.269074 -90.799158)
		(stroke
			(width 0.08255)
			(type default)
		)
		(layer "B.Cu")
	)
	(gr_line
		(start 211.745322 -89.977976)
		(end 211.748878 -89.994232)
		(stroke
			(width 0.08255)
			(type default)
		)
		(layer "B.Cu")
	)
	(gr_line
		(start 211.748878 -89.994232)
		(end 211.757768 -90.007694)
		(stroke
			(width 0.08255)
			(type default)
		)
		(layer "B.Cu")
	)
	(gr_line
		(start 211.800186 -77.434186)
		(end 211.800186 -77.799946)
		(stroke
			(width 0.08255)
			(type default)
		)
		(layer "B.Cu")
	)
	(gr_arc
		(start 211.800186 -76.765658)
		(mid 211.855298 -76.898773)
		(end 211.9884 -76.953872)
		(stroke
			(width 0.08255)
			(type default)
		)
		(layer "B.Cu")
	)
	(gr_line
		(start 211.800186 -76.399898)
		(end 211.800186 -76.765658)
		(stroke
			(width 0.08255)
			(type default)
		)
		(layer "B.Cu")
	)
	(gr_arc
		(start 211.9884 -77.245972)
		(mid 211.855313 -77.301099)
		(end 211.800186 -77.434186)
		(stroke
			(width 0.08255)
			(type default)
		)
		(layer "B.Cu")
	)
	(gr_line
		(start 212.899498 -94.850458)
		(end 213.263734 -95.411036)
		(stroke
			(width 0.08255)
			(type default)
		)
		(layer "B.Cu")
	)
	(gr_line
		(start 213.127336 -94.659958)
		(end 213.283546 -94.693232)
		(stroke
			(width 0.08255)
			(type default)
		)
		(layer "B.Cu")
	)
	(gr_line
		(start 213.283546 -94.693232)
		(end 213.5632 -95.123762)
		(stroke
			(width 0.08255)
			(type default)
		)
		(layer "B.Cu")
	)
	(gr_line
		(start 213.482682 -89.215722)
		(end 213.485476 -89.226644)
		(stroke
			(width 0.08255)
			(type default)
		)
		(layer "B.Cu")
	)
	(gr_line
		(start 213.485476 -89.226644)
		(end 213.491572 -89.235788)
		(stroke
			(width 0.08255)
			(type default)
		)
		(layer "B.Cu")
	)
	(gr_line
		(start 213.529926 -95.279972)
		(end 213.5632 -95.123762)
		(stroke
			(width 0.08255)
			(type default)
		)
		(layer "B.Cu")
	)
	(gr_line
		(start 213.574884 -95.89008)
		(end 213.938104 -96.449896)
		(stroke
			(width 0.08255)
			(type default)
		)
		(layer "B.Cu")
	)
	(gr_line
		(start 213.60003 -78.634082)
		(end 213.60003 -78.999842)
		(stroke
			(width 0.08255)
			(type default)
		)
		(layer "B.Cu")
	)
	(gr_arc
		(start 213.60003 -77.965554)
		(mid 213.655143 -78.098656)
		(end 213.788244 -78.153768)
		(stroke
			(width 0.08255)
			(type default)
		)
		(layer "B.Cu")
	)
	(gr_line
		(start 213.60003 -77.600048)
		(end 213.60003 -77.965554)
		(stroke
			(width 0.08255)
			(type default)
		)
		(layer "B.Cu")
	)
	(gr_arc
		(start 213.788244 -78.445868)
		(mid 213.655157 -78.500995)
		(end 213.60003 -78.634082)
		(stroke
			(width 0.08255)
			(type default)
		)
		(layer "B.Cu")
	)
	(gr_line
		(start 213.802214 -95.69958)
		(end 213.961218 -95.733362)
		(stroke
			(width 0.08255)
			(type default)
		)
		(layer "B.Cu")
	)
	(gr_line
		(start 213.955884 -96.477074)
		(end 213.959186 -96.482154)
		(stroke
			(width 0.08255)
			(type default)
		)
		(layer "B.Cu")
	)
	(gr_line
		(start 213.958932 -96.482154)
		(end 213.959186 -96.482154)
		(stroke
			(width 0.08255)
			(type default)
		)
		(layer "B.Cu")
	)
	(gr_line
		(start 213.961218 -95.733362)
		(end 214.23884 -96.16059)
		(stroke
			(width 0.08255)
			(type default)
		)
		(layer "B.Cu")
	)
	(gr_line
		(start 214.204296 -96.323404)
		(end 214.207598 -96.328484)
		(stroke
			(width 0.08255)
			(type default)
		)
		(layer "B.Cu")
	)
	(gr_line
		(start 214.204296 -96.322896)
		(end 214.204296 -96.323404)
		(stroke
			(width 0.08255)
			(type default)
		)
		(layer "B.Cu")
	)
	(gr_line
		(start 214.205058 -96.319594)
		(end 214.23884 -96.16059)
		(stroke
			(width 0.08255)
			(type default)
		)
		(layer "B.Cu")
	)
	(gr_line
		(start 214.368888 -83.824064)
		(end 214.454994 -83.691222)
		(stroke
			(width 0.08255)
			(type default)
		)
		(layer "B.Cu")
	)
	(gr_line
		(start 214.368888 -83.824064)
		(end 214.471758 -84.308442)
		(stroke
			(width 0.08255)
			(type default)
		)
		(layer "B.Cu")
	)
	(gr_line
		(start 214.471758 -84.308442)
		(end 214.604346 -84.394548)
		(stroke
			(width 0.08255)
			(type default)
		)
		(layer "B.Cu")
	)
	(gr_line
		(start 214.62238 -85.016594)
		(end 214.708486 -84.883752)
		(stroke
			(width 0.08255)
			(type default)
		)
		(layer "B.Cu")
	)
	(gr_line
		(start 214.62238 -85.016594)
		(end 214.72525 -85.500972)
		(stroke
			(width 0.08255)
			(type default)
		)
		(layer "B.Cu")
	)
	(gr_line
		(start 214.72525 -85.500972)
		(end 214.857838 -85.587078)
		(stroke
			(width 0.08255)
			(type default)
		)
		(layer "B.Cu")
	)
	(gr_line
		(start 214.750396 -83.664806)
		(end 214.885016 -84.297774)
		(stroke
			(width 0.08255)
			(type default)
		)
		(layer "B.Cu")
	)
	(gr_line
		(start 214.875872 -86.209124)
		(end 214.961978 -86.076282)
		(stroke
			(width 0.08255)
			(type default)
		)
		(layer "B.Cu")
	)
	(gr_line
		(start 214.875872 -86.209124)
		(end 214.978742 -86.693502)
		(stroke
			(width 0.08255)
			(type default)
		)
		(layer "B.Cu")
	)
	(gr_line
		(start 214.978742 -86.693502)
		(end 215.111584 -86.779862)
		(stroke
			(width 0.08255)
			(type default)
		)
		(layer "B.Cu")
	)
	(gr_line
		(start 215.003888 -84.857082)
		(end 215.138508 -85.490304)
		(stroke
			(width 0.08255)
			(type default)
		)
		(layer "B.Cu")
	)
	(gr_line
		(start 215.257634 -86.051136)
		(end 215.392 -86.682834)
		(stroke
			(width 0.08255)
			(type default)
		)
		(layer "B.Cu")
	)
	(gr_line
		(start 215.271604 -92.182442)
		(end 215.30437 -92.027502)
		(stroke
			(width 0.08255)
			(type default)
		)
		(layer "B.Cu")
	)
	(gr_line
		(start 215.271604 -92.182442)
		(end 215.541606 -92.597478)
		(stroke
			(width 0.08255)
			(type default)
		)
		(layer "B.Cu")
	)
	(gr_line
		(start 215.400128 -77.434186)
		(end 215.400128 -77.799946)
		(stroke
			(width 0.08255)
			(type default)
		)
		(layer "B.Cu")
	)
	(gr_arc
		(start 215.400128 -76.765658)
		(mid 215.455242 -76.898758)
		(end 215.588342 -76.953872)
		(stroke
			(width 0.08255)
			(type default)
		)
		(layer "B.Cu")
	)
	(gr_line
		(start 215.400128 -76.399898)
		(end 215.400128 -76.765658)
		(stroke
			(width 0.08255)
			(type default)
		)
		(layer "B.Cu")
	)
	(gr_line
		(start 215.541606 -92.597478)
		(end 215.696546 -92.630244)
		(stroke
			(width 0.08255)
			(type default)
		)
		(layer "B.Cu")
	)
	(gr_line
		(start 215.570562 -91.89593)
		(end 215.924638 -92.44076)
		(stroke
			(width 0.08255)
			(type default)
		)
		(layer "B.Cu")
	)
	(gr_arc
		(start 215.588342 -77.245972)
		(mid 215.455255 -77.301099)
		(end 215.400128 -77.434186)
		(stroke
			(width 0.08255)
			(type default)
		)
		(layer "B.Cu")
	)
	(gr_line
		(start 215.68537 -89.468198)
		(end 215.688926 -89.484454)
		(stroke
			(width 0.08255)
			(type default)
		)
		(layer "B.Cu")
	)
	(gr_line
		(start 215.688926 -89.484454)
		(end 215.697816 -89.497916)
		(stroke
			(width 0.08255)
			(type default)
		)
		(layer "B.Cu")
	)
	(gr_line
		(start 215.787478 -234.970828)
		(end 216.38641 -234.843574)
		(stroke
			(width 0.0635)
			(type default)
		)
		(layer "B.Cu")
	)
	(gr_line
		(start 215.815418 -235.266484)
		(end 215.992964 -235.382054)
		(stroke
			(width 0.0635)
			(type default)
		)
		(layer "B.Cu")
	)
	(gr_line
		(start 215.976708 -93.26626)
		(end 216.00922 -93.111066)
		(stroke
			(width 0.08255)
			(type default)
		)
		(layer "B.Cu")
	)
	(gr_line
		(start 215.976708 -93.26626)
		(end 216.24671 -93.681296)
		(stroke
			(width 0.08255)
			(type default)
		)
		(layer "B.Cu")
	)
	(gr_line
		(start 215.992964 -235.382054)
		(end 216.365582 -235.302806)
		(stroke
			(width 0.0635)
			(type default)
		)
		(layer "B.Cu")
	)
	(gr_line
		(start 216.24671 -93.681296)
		(end 216.401396 -93.714062)
		(stroke
			(width 0.08255)
			(type default)
		)
		(layer "B.Cu")
	)
	(gr_line
		(start 216.274396 -92.97797)
		(end 216.630758 -93.525848)
		(stroke
			(width 0.08255)
			(type default)
		)
		(layer "B.Cu")
	)
	(gr_line
		(start 216.365582 -235.302806)
		(end 216.481406 -235.124752)
		(stroke
			(width 0.0635)
			(type default)
		)
		(layer "B.Cu")
	)
	(gr_line
		(start 216.39657 -85.155786)
		(end 216.48293 -85.022944)
		(stroke
			(width 0.08255)
			(type default)
		)
		(layer "B.Cu")
	)
	(gr_line
		(start 216.39657 -85.155786)
		(end 216.49944 -85.640164)
		(stroke
			(width 0.08255)
			(type default)
		)
		(layer "B.Cu")
	)
	(gr_line
		(start 216.49944 -85.640164)
		(end 216.632282 -85.726524)
		(stroke
			(width 0.08255)
			(type default)
		)
		(layer "B.Cu")
	)
	(gr_line
		(start 216.641172 -94.288102)
		(end 216.673938 -94.133162)
		(stroke
			(width 0.08255)
			(type default)
		)
		(layer "B.Cu")
	)
	(gr_line
		(start 216.641172 -94.288102)
		(end 216.911428 -94.703392)
		(stroke
			(width 0.08255)
			(type default)
		)
		(layer "B.Cu")
	)
	(gr_line
		(start 216.649808 -86.348316)
		(end 216.736168 -86.215474)
		(stroke
			(width 0.08255)
			(type default)
		)
		(layer "B.Cu")
	)
	(gr_line
		(start 216.649808 -86.348316)
		(end 216.752678 -86.832694)
		(stroke
			(width 0.08255)
			(type default)
		)
		(layer "B.Cu")
	)
	(gr_line
		(start 216.752678 -86.832694)
		(end 216.88552 -86.919054)
		(stroke
			(width 0.08255)
			(type default)
		)
		(layer "B.Cu")
	)
	(gr_line
		(start 216.778332 -84.997036)
		(end 216.912698 -85.629496)
		(stroke
			(width 0.08255)
			(type default)
		)
		(layer "B.Cu")
	)
	(gr_line
		(start 216.831926 -234.749086)
		(end 217.42908 -234.622086)
		(stroke
			(width 0.0635)
			(type default)
		)
		(layer "B.Cu")
	)
	(gr_line
		(start 216.85885 -235.044742)
		(end 217.036396 -235.160058)
		(stroke
			(width 0.0635)
			(type default)
		)
		(layer "B.Cu")
	)
	(gr_line
		(start 216.903046 -87.540846)
		(end 216.989406 -87.408258)
		(stroke
			(width 0.08255)
			(type default)
		)
		(layer "B.Cu")
	)
	(gr_line
		(start 216.903046 -87.540846)
		(end 217.00617 -88.025478)
		(stroke
			(width 0.08255)
			(type default)
		)
		(layer "B.Cu")
	)
	(gr_line
		(start 216.911428 -94.703392)
		(end 217.066368 -94.736158)
		(stroke
			(width 0.08255)
			(type default)
		)
		(layer "B.Cu")
	)
	(gr_line
		(start 216.938606 -93.99905)
		(end 217.296238 -94.548706)
		(stroke
			(width 0.08255)
			(type default)
		)
		(layer "B.Cu")
	)
	(gr_line
		(start 217.00617 -88.025478)
		(end 217.138758 -88.111584)
		(stroke
			(width 0.08255)
			(type default)
		)
		(layer "B.Cu")
	)
	(gr_line
		(start 217.031824 -86.190074)
		(end 217.16619 -86.822534)
		(stroke
			(width 0.08255)
			(type default)
		)
		(layer "B.Cu")
	)
	(gr_line
		(start 217.036396 -235.160058)
		(end 217.409268 -235.081064)
		(stroke
			(width 0.0635)
			(type default)
		)
		(layer "B.Cu")
	)
	(gr_line
		(start 217.199972 -78.634082)
		(end 217.199972 -78.999842)
		(stroke
			(width 0.08255)
			(type default)
		)
		(layer "B.Cu")
	)
	(gr_arc
		(start 217.199972 -77.965554)
		(mid 217.255081 -78.098676)
		(end 217.388186 -78.153768)
		(stroke
			(width 0.08255)
			(type default)
		)
		(layer "B.Cu")
	)
	(gr_line
		(start 217.199972 -77.600048)
		(end 217.199972 -77.965554)
		(stroke
			(width 0.08255)
			(type default)
		)
		(layer "B.Cu")
	)
	(gr_line
		(start 217.27795 -88.755982)
		(end 217.281506 -88.772238)
		(stroke
			(width 0.08255)
			(type default)
		)
		(layer "B.Cu")
	)
	(gr_line
		(start 217.281506 -88.772238)
		(end 217.289888 -88.785192)
		(stroke
			(width 0.08255)
			(type default)
		)
		(layer "B.Cu")
	)
	(gr_line
		(start 217.284808 -87.38235)
		(end 217.419428 -88.015064)
		(stroke
			(width 0.08255)
			(type default)
		)
		(layer "B.Cu")
	)
	(gr_arc
		(start 217.388186 -78.445868)
		(mid 217.255099 -78.500995)
		(end 217.199972 -78.634082)
		(stroke
			(width 0.08255)
			(type default)
		)
		(layer "B.Cu")
	)
	(gr_line
		(start 217.409268 -235.081064)
		(end 217.524838 -234.90301)
		(stroke
			(width 0.0635)
			(type default)
		)
		(layer "B.Cu")
	)
	(gr_line
		(start 217.876628 -234.52709)
		(end 218.47175 -234.400598)
		(stroke
			(width 0.0635)
			(type default)
		)
		(layer "B.Cu")
	)
	(gr_line
		(start 217.902282 -234.822746)
		(end 218.080082 -234.938316)
		(stroke
			(width 0.0635)
			(type default)
		)
		(layer "B.Cu")
	)
	(gr_line
		(start 218.080082 -234.938316)
		(end 218.4527 -234.859068)
		(stroke
			(width 0.0635)
			(type default)
		)
		(layer "B.Cu")
	)
	(gr_line
		(start 218.4527 -234.859068)
		(end 218.56827 -234.681268)
		(stroke
			(width 0.0635)
			(type default)
		)
		(layer "B.Cu")
	)
	(gr_line
		(start 218.568016 -85.289644)
		(end 218.654122 -85.157056)
		(stroke
			(width 0.08255)
			(type default)
		)
		(layer "B.Cu")
	)
	(gr_line
		(start 218.568016 -85.289644)
		(end 218.670886 -85.774276)
		(stroke
			(width 0.08255)
			(type default)
		)
		(layer "B.Cu")
	)
	(gr_line
		(start 218.670886 -85.774276)
		(end 218.803474 -85.860128)
		(stroke
			(width 0.08255)
			(type default)
		)
		(layer "B.Cu")
	)
	(gr_line
		(start 218.821508 -86.482174)
		(end 218.907614 -86.349586)
		(stroke
			(width 0.08255)
			(type default)
		)
		(layer "B.Cu")
	)
	(gr_line
		(start 218.821508 -86.482174)
		(end 218.924378 -86.966806)
		(stroke
			(width 0.08255)
			(type default)
		)
		(layer "B.Cu")
	)
	(gr_line
		(start 218.919552 -234.305602)
		(end 219.516198 -234.178602)
		(stroke
			(width 0.0635)
			(type default)
		)
		(layer "B.Cu")
	)
	(gr_line
		(start 218.924378 -86.966806)
		(end 219.056966 -87.052658)
		(stroke
			(width 0.08255)
			(type default)
		)
		(layer "B.Cu")
	)
	(gr_line
		(start 218.94546 -234.601004)
		(end 219.123514 -234.716574)
		(stroke
			(width 0.0635)
			(type default)
		)
		(layer "B.Cu")
	)
	(gr_line
		(start 218.949524 -85.129624)
		(end 219.084398 -85.764116)
		(stroke
			(width 0.08255)
			(type default)
		)
		(layer "B.Cu")
	)
	(gr_line
		(start 219.00007 -77.434186)
		(end 219.00007 -77.799946)
		(stroke
			(width 0.08255)
			(type default)
		)
		(layer "B.Cu")
	)
	(gr_arc
		(start 219.00007 -76.765658)
		(mid 219.055181 -76.898778)
		(end 219.188284 -76.953872)
		(stroke
			(width 0.08255)
			(type default)
		)
		(layer "B.Cu")
	)
	(gr_line
		(start 219.00007 -76.399898)
		(end 219.00007 -76.765658)
		(stroke
			(width 0.08255)
			(type default)
		)
		(layer "B.Cu")
	)
	(gr_line
		(start 219.074746 -87.674958)
		(end 219.161106 -87.542116)
		(stroke
			(width 0.08255)
			(type default)
		)
		(layer "B.Cu")
	)
	(gr_line
		(start 219.074746 -87.674958)
		(end 219.17787 -88.159336)
		(stroke
			(width 0.08255)
			(type default)
		)
		(layer "B.Cu")
	)
	(gr_line
		(start 219.123514 -234.716574)
		(end 219.496132 -234.637326)
		(stroke
			(width 0.0635)
			(type default)
		)
		(layer "B.Cu")
	)
	(gr_line
		(start 219.17787 -88.159336)
		(end 219.310458 -88.245442)
		(stroke
			(width 0.08255)
			(type default)
		)
		(layer "B.Cu")
	)
	(gr_arc
		(start 219.188284 -77.245972)
		(mid 219.055197 -77.301099)
		(end 219.00007 -77.434186)
		(stroke
			(width 0.08255)
			(type default)
		)
		(layer "B.Cu")
	)
	(gr_line
		(start 219.203016 -86.32317)
		(end 219.337128 -86.954868)
		(stroke
			(width 0.08255)
			(type default)
		)
		(layer "B.Cu")
	)
	(gr_line
		(start 219.41282 -88.715596)
		(end 219.416376 -88.731852)
		(stroke
			(width 0.08255)
			(type default)
		)
		(layer "B.Cu")
	)
	(gr_line
		(start 219.416376 -88.731852)
		(end 219.425266 -88.745314)
		(stroke
			(width 0.08255)
			(type default)
		)
		(layer "B.Cu")
	)
	(gr_line
		(start 219.456508 -87.515446)
		(end 219.590874 -88.14816)
		(stroke
			(width 0.08255)
			(type default)
		)
		(layer "B.Cu")
	)
	(gr_line
		(start 219.496132 -234.637326)
		(end 219.611702 -234.459526)
		(stroke
			(width 0.0635)
			(type default)
		)
		(layer "B.Cu")
	)
	(gr_line
		(start 219.794582 -239.413034)
		(end 220.403928 -239.332516)
		(stroke
			(width 0.0635)
			(type default)
		)
		(layer "B.Cu")
	)
	(gr_line
		(start 219.799916 -239.709706)
		(end 219.968064 -239.838738)
		(stroke
			(width 0.0635)
			(type default)
		)
		(layer "B.Cu")
	)
	(gr_line
		(start 219.968064 -239.838738)
		(end 220.346016 -239.788954)
		(stroke
			(width 0.0635)
			(type default)
		)
		(layer "B.Cu")
	)
	(gr_line
		(start 220.046296 -228.06406)
		(end 220.065092 -228.06025)
		(stroke
			(width 0.0635)
			(type default)
		)
		(layer "B.Cu")
	)
	(gr_line
		(start 220.065092 -228.06025)
		(end 220.083888 -228.063806)
		(stroke
			(width 0.0635)
			(type default)
		)
		(layer "B.Cu")
	)
	(gr_line
		(start 220.346016 -239.788954)
		(end 220.475048 -239.620552)
		(stroke
			(width 0.0635)
			(type default)
		)
		(layer "B.Cu")
	)
	(gr_line
		(start 220.800168 -78.634082)
		(end 220.800168 -78.999842)
		(stroke
			(width 0.08255)
			(type default)
		)
		(layer "B.Cu")
	)
	(gr_arc
		(start 220.800168 -77.965554)
		(mid 220.855277 -78.098677)
		(end 220.988382 -78.153768)
		(stroke
			(width 0.08255)
			(type default)
		)
		(layer "B.Cu")
	)
	(gr_line
		(start 220.800168 -77.600048)
		(end 220.800168 -77.965554)
		(stroke
			(width 0.08255)
			(type default)
		)
		(layer "B.Cu")
	)
	(gr_line
		(start 220.852492 -239.273334)
		(end 221.459806 -239.19307)
		(stroke
			(width 0.0635)
			(type default)
		)
		(layer "B.Cu")
	)
	(gr_line
		(start 220.857572 -239.570006)
		(end 221.02572 -239.699038)
		(stroke
			(width 0.0635)
			(type default)
		)
		(layer "B.Cu")
	)
	(gr_line
		(start 220.86316 -87.83828)
		(end 220.866716 -87.854536)
		(stroke
			(width 0.08255)
			(type default)
		)
		(layer "B.Cu")
	)
	(gr_line
		(start 220.866716 -87.854536)
		(end 220.875606 -87.867998)
		(stroke
			(width 0.08255)
			(type default)
		)
		(layer "B.Cu")
	)
	(gr_arc
		(start 220.988382 -78.445868)
		(mid 220.855295 -78.500995)
		(end 220.800168 -78.634082)
		(stroke
			(width 0.08255)
			(type default)
		)
		(layer "B.Cu")
	)
	(gr_line
		(start 221.02572 -239.699038)
		(end 221.403418 -239.649254)
		(stroke
			(width 0.0635)
			(type default)
		)
		(layer "B.Cu")
	)
	(gr_line
		(start 221.102936 -88.428068)
		(end 221.135702 -88.273128)
		(stroke
			(width 0.08255)
			(type default)
		)
		(layer "B.Cu")
	)
	(gr_line
		(start 221.102936 -88.428068)
		(end 221.372684 -88.843358)
		(stroke
			(width 0.08255)
			(type default)
		)
		(layer "B.Cu")
	)
	(gr_line
		(start 221.372684 -88.843358)
		(end 221.52737 -88.876378)
		(stroke
			(width 0.08255)
			(type default)
		)
		(layer "B.Cu")
	)
	(gr_line
		(start 221.402402 -88.142826)
		(end 221.75597 -88.687148)
		(stroke
			(width 0.08255)
			(type default)
		)
		(layer "B.Cu")
	)
	(gr_line
		(start 221.403418 -239.649254)
		(end 221.532704 -239.480852)
		(stroke
			(width 0.0635)
			(type default)
		)
		(layer "B.Cu")
	)
	(gr_line
		(start 221.766892 -89.450672)
		(end 221.799658 -89.295732)
		(stroke
			(width 0.08255)
			(type default)
		)
		(layer "B.Cu")
	)
	(gr_line
		(start 221.766892 -89.450672)
		(end 222.03664 -89.865962)
		(stroke
			(width 0.08255)
			(type default)
		)
		(layer "B.Cu")
	)
	(gr_line
		(start 221.909894 -239.133634)
		(end 222.517208 -239.05337)
		(stroke
			(width 0.0635)
			(type default)
		)
		(layer "B.Cu")
	)
	(gr_line
		(start 221.914974 -239.430306)
		(end 222.083376 -239.559338)
		(stroke
			(width 0.0635)
			(type default)
		)
		(layer "B.Cu")
	)
	(gr_line
		(start 222.03664 -89.865962)
		(end 222.191326 -89.898728)
		(stroke
			(width 0.08255)
			(type default)
		)
		(layer "B.Cu")
	)
	(gr_line
		(start 222.06585 -89.164668)
		(end 222.419164 -89.708736)
		(stroke
			(width 0.08255)
			(type default)
		)
		(layer "B.Cu")
	)
	(gr_line
		(start 222.083376 -239.559338)
		(end 222.461074 -239.509554)
		(stroke
			(width 0.0635)
			(type default)
		)
		(layer "B.Cu")
	)
	(gr_line
		(start 222.257112 -86.806532)
		(end 222.260414 -86.822026)
		(stroke
			(width 0.08255)
			(type default)
		)
		(layer "B.Cu")
	)
	(gr_line
		(start 222.260414 -86.822026)
		(end 222.268796 -86.83498)
		(stroke
			(width 0.08255)
			(type default)
		)
		(layer "B.Cu")
	)
	(gr_line
		(start 222.461074 -239.509554)
		(end 222.590106 -239.341152)
		(stroke
			(width 0.0635)
			(type default)
		)
		(layer "B.Cu")
	)
	(gr_line
		(start 222.600012 -77.434186)
		(end 222.600012 -77.799946)
		(stroke
			(width 0.08255)
			(type default)
		)
		(layer "B.Cu")
	)
	(gr_arc
		(start 222.600012 -76.765658)
		(mid 222.655125 -76.898763)
		(end 222.788226 -76.953872)
		(stroke
			(width 0.08255)
			(type default)
		)
		(layer "B.Cu")
	)
	(gr_line
		(start 222.600012 -76.399898)
		(end 222.600012 -76.765658)
		(stroke
			(width 0.08255)
			(type default)
		)
		(layer "B.Cu")
	)
	(gr_arc
		(start 222.788226 -77.245972)
		(mid 222.655139 -77.301099)
		(end 222.600012 -77.434186)
		(stroke
			(width 0.08255)
			(type default)
		)
		(layer "B.Cu")
	)
	(gr_line
		(start 222.967042 -238.993934)
		(end 223.57461 -238.91367)
		(stroke
			(width 0.0635)
			(type default)
		)
		(layer "B.Cu")
	)
	(gr_line
		(start 222.972376 -239.290606)
		(end 223.141032 -239.419638)
		(stroke
			(width 0.0635)
			(type default)
		)
		(layer "B.Cu")
	)
	(gr_line
		(start 223.141032 -239.419638)
		(end 223.51873 -239.3696)
		(stroke
			(width 0.0635)
			(type default)
		)
		(layer "B.Cu")
	)
	(gr_line
		(start 223.338644 -84.297774)
		(end 223.364806 -84.33816)
		(stroke
			(width 0.08255)
			(type default)
		)
		(layer "B.Cu")
	)
	(gr_line
		(start 223.51873 -239.3696)
		(end 223.647762 -239.201198)
		(stroke
			(width 0.0635)
			(type default)
		)
		(layer "B.Cu")
	)
	(gr_line
		(start 224.696274 -90.782394)
		(end 224.72904 -90.627708)
		(stroke
			(width 0.08255)
			(type default)
		)
		(layer "B.Cu")
	)
	(gr_line
		(start 224.696274 -90.782394)
		(end 224.966022 -91.197938)
		(stroke
			(width 0.08255)
			(type default)
		)
		(layer "B.Cu")
	)
	(gr_line
		(start 224.966022 -91.197938)
		(end 225.120708 -91.230704)
		(stroke
			(width 0.08255)
			(type default)
		)
		(layer "B.Cu")
	)
	(gr_line
		(start 224.995486 -90.496898)
		(end 225.349054 -91.04122)
		(stroke
			(width 0.08255)
			(type default)
		)
		(layer "B.Cu")
	)
	(gr_line
		(start 225.096324 -107.286806)
		(end 225.128836 -107.131866)
		(stroke
			(width 0.08255)
			(type default)
		)
		(layer "B.Cu")
	)
	(gr_line
		(start 225.096324 -107.286806)
		(end 225.366326 -107.702096)
		(stroke
			(width 0.08255)
			(type default)
		)
		(layer "B.Cu")
	)
	(gr_line
		(start 225.36023 -91.804998)
		(end 225.392996 -91.650058)
		(stroke
			(width 0.08255)
			(type default)
		)
		(layer "B.Cu")
	)
	(gr_line
		(start 225.36023 -91.804998)
		(end 225.629978 -92.220288)
		(stroke
			(width 0.08255)
			(type default)
		)
		(layer "B.Cu")
	)
	(gr_line
		(start 225.366326 -107.702096)
		(end 225.521266 -107.734862)
		(stroke
			(width 0.08255)
			(type default)
		)
		(layer "B.Cu")
	)
	(gr_line
		(start 225.394774 -107.00004)
		(end 225.75012 -107.54614)
		(stroke
			(width 0.08255)
			(type default)
		)
		(layer "B.Cu")
	)
	(gr_line
		(start 225.629978 -92.220288)
		(end 225.784918 -92.253308)
		(stroke
			(width 0.08255)
			(type default)
		)
		(layer "B.Cu")
	)
	(gr_line
		(start 225.65868 -91.517724)
		(end 226.013518 -92.064078)
		(stroke
			(width 0.08255)
			(type default)
		)
		(layer "B.Cu")
	)
	(gr_line
		(start 225.760788 -108.308902)
		(end 225.793554 -108.153962)
		(stroke
			(width 0.08255)
			(type default)
		)
		(layer "B.Cu")
	)
	(gr_line
		(start 225.760788 -108.308902)
		(end 226.031044 -108.724192)
		(stroke
			(width 0.08255)
			(type default)
		)
		(layer "B.Cu")
	)
	(gr_line
		(start 225.793808 -114.707416)
		(end 225.807016 -114.72799)
		(stroke
			(width 0.08255)
			(type default)
		)
		(layer "B.Cu")
	)
	(gr_line
		(start 225.807016 -114.72799)
		(end 225.828352 -114.74196)
		(stroke
			(width 0.08255)
			(type default)
		)
		(layer "B.Cu")
	)
	(gr_line
		(start 226.031044 -108.724192)
		(end 226.185984 -108.756958)
		(stroke
			(width 0.08255)
			(type default)
		)
		(layer "B.Cu")
	)
	(gr_line
		(start 226.058984 -108.021374)
		(end 226.414838 -108.568236)
		(stroke
			(width 0.08255)
			(type default)
		)
		(layer "B.Cu")
	)
	(gr_line
		(start 227.29571 -113.499646)
		(end 227.30841 -113.51895)
		(stroke
			(width 0.08255)
			(type default)
		)
		(layer "B.Cu")
	)
	(gr_line
		(start 227.308156 -113.51895)
		(end 227.30841 -113.51895)
		(stroke
			(width 0.08255)
			(type default)
		)
		(layer "B.Cu")
	)
	(gr_line
		(start 227.308156 -113.51895)
		(end 227.327714 -113.531396)
		(stroke
			(width 0.08255)
			(type default)
		)
		(layer "B.Cu")
	)
	(gr_line
		(start 227.854256 -98.824542)
		(end 227.887022 -98.669856)
		(stroke
			(width 0.08255)
			(type default)
		)
		(layer "B.Cu")
	)
	(gr_line
		(start 227.854256 -98.824542)
		(end 228.124004 -99.240086)
		(stroke
			(width 0.08255)
			(type default)
		)
		(layer "B.Cu")
	)
	(gr_line
		(start 228.124004 -99.240086)
		(end 228.27869 -99.272852)
		(stroke
			(width 0.08255)
			(type default)
		)
		(layer "B.Cu")
	)
	(gr_line
		(start 228.153214 -98.538538)
		(end 228.506528 -99.08286)
		(stroke
			(width 0.08255)
			(type default)
		)
		(layer "B.Cu")
	)
	(gr_line
		(start 228.518212 -99.847146)
		(end 228.550978 -99.692206)
		(stroke
			(width 0.08255)
			(type default)
		)
		(layer "B.Cu")
	)
	(gr_line
		(start 228.518212 -99.847146)
		(end 228.78796 -100.262436)
		(stroke
			(width 0.08255)
			(type default)
		)
		(layer "B.Cu")
	)
	(gr_line
		(start 228.58476 -112.440466)
		(end 228.59746 -112.460024)
		(stroke
			(width 0.08255)
			(type default)
		)
		(layer "B.Cu")
	)
	(gr_line
		(start 228.59746 -112.460024)
		(end 228.617526 -112.473232)
		(stroke
			(width 0.08255)
			(type default)
		)
		(layer "B.Cu")
	)
	(gr_line
		(start 228.78796 -100.262436)
		(end 228.9429 -100.295456)
		(stroke
			(width 0.08255)
			(type default)
		)
		(layer "B.Cu")
	)
	(gr_line
		(start 228.817424 -99.561396)
		(end 229.171246 -100.106226)
		(stroke
			(width 0.08255)
			(type default)
		)
		(layer "B.Cu")
	)
	(gr_line
		(start 229.182168 -100.869496)
		(end 229.214934 -100.71481)
		(stroke
			(width 0.08255)
			(type default)
		)
		(layer "B.Cu")
	)
	(gr_line
		(start 229.182168 -100.869496)
		(end 229.451916 -101.28504)
		(stroke
			(width 0.08255)
			(type default)
		)
		(layer "B.Cu")
	)
	(gr_line
		(start 229.263956 -97.8154)
		(end 229.296722 -97.660968)
		(stroke
			(width 0.08255)
			(type default)
		)
		(layer "B.Cu")
	)
	(gr_line
		(start 229.263956 -97.8154)
		(end 229.533704 -98.230944)
		(stroke
			(width 0.08255)
			(type default)
		)
		(layer "B.Cu")
	)
	(gr_line
		(start 229.451916 -101.28504)
		(end 229.606602 -101.317806)
		(stroke
			(width 0.08255)
			(type default)
		)
		(layer "B.Cu")
	)
	(gr_line
		(start 229.478586 -110.718346)
		(end 229.491794 -110.73892)
		(stroke
			(width 0.08255)
			(type default)
		)
		(layer "B.Cu")
	)
	(gr_line
		(start 229.48138 -100.584254)
		(end 229.834186 -101.127306)
		(stroke
			(width 0.08255)
			(type default)
		)
		(layer "B.Cu")
	)
	(gr_line
		(start 229.491794 -110.73892)
		(end 229.512368 -110.752128)
		(stroke
			(width 0.08255)
			(type default)
		)
		(layer "B.Cu")
	)
	(gr_line
		(start 229.533704 -98.230944)
		(end 229.68839 -98.26371)
		(stroke
			(width 0.08255)
			(type default)
		)
		(layer "B.Cu")
	)
	(gr_line
		(start 229.562914 -97.52965)
		(end 229.916228 -98.073718)
		(stroke
			(width 0.08255)
			(type default)
		)
		(layer "B.Cu")
	)
	(gr_line
		(start 229.907846 -111.011716)
		(end 229.940866 -111.16691)
		(stroke
			(width 0.08255)
			(type default)
		)
		(layer "B.Cu")
	)
	(gr_line
		(start 229.927912 -98.838004)
		(end 229.960678 -98.683318)
		(stroke
			(width 0.08255)
			(type default)
		)
		(layer "B.Cu")
	)
	(gr_line
		(start 229.927912 -98.838004)
		(end 230.19766 -99.253294)
		(stroke
			(width 0.08255)
			(type default)
		)
		(layer "B.Cu")
	)
	(gr_line
		(start 229.940866 -111.16691)
		(end 230.356156 -111.436658)
		(stroke
			(width 0.08255)
			(type default)
		)
		(layer "B.Cu")
	)
	(gr_line
		(start 230.097076 -110.78337)
		(end 230.641652 -111.137192)
		(stroke
			(width 0.08255)
			(type default)
		)
		(layer "B.Cu")
	)
	(gr_line
		(start 230.19766 -99.253294)
		(end 230.352346 -99.286314)
		(stroke
			(width 0.08255)
			(type default)
		)
		(layer "B.Cu")
	)
	(gr_line
		(start 230.227124 -98.552508)
		(end 230.580692 -99.09683)
		(stroke
			(width 0.08255)
			(type default)
		)
		(layer "B.Cu")
	)
	(gr_line
		(start 230.356156 -111.436658)
		(end 230.511096 -111.403638)
		(stroke
			(width 0.08255)
			(type default)
		)
		(layer "B.Cu")
	)
	(gr_line
		(start 230.547672 -231.834182)
		(end 230.570786 -231.829102)
		(stroke
			(width 0.0635)
			(type default)
		)
		(layer "B.Cu")
	)
	(gr_line
		(start 230.570786 -231.829102)
		(end 230.5939 -231.834182)
		(stroke
			(width 0.0635)
			(type default)
		)
		(layer "B.Cu")
	)
	(gr_line
		(start 230.591868 -99.860608)
		(end 230.624634 -99.705668)
		(stroke
			(width 0.08255)
			(type default)
		)
		(layer "B.Cu")
	)
	(gr_line
		(start 230.591868 -99.860608)
		(end 230.861616 -100.275898)
		(stroke
			(width 0.08255)
			(type default)
		)
		(layer "B.Cu")
	)
	(gr_line
		(start 230.632 -109.329728)
		(end 230.645208 -109.350302)
		(stroke
			(width 0.08255)
			(type default)
		)
		(layer "B.Cu")
	)
	(gr_line
		(start 230.645208 -109.350302)
		(end 230.665782 -109.36351)
		(stroke
			(width 0.08255)
			(type default)
		)
		(layer "B.Cu")
	)
	(gr_line
		(start 230.676704 -106.280204)
		(end 230.70947 -106.125264)
		(stroke
			(width 0.08255)
			(type default)
		)
		(layer "B.Cu")
	)
	(gr_line
		(start 230.676704 -106.280204)
		(end 230.946452 -106.695494)
		(stroke
			(width 0.08255)
			(type default)
		)
		(layer "B.Cu")
	)
	(gr_line
		(start 230.861616 -100.275898)
		(end 231.016302 -100.308664)
		(stroke
			(width 0.08255)
			(type default)
		)
		(layer "B.Cu")
	)
	(gr_line
		(start 230.86822 -118.032022)
		(end 230.88219 -118.032022)
		(stroke
			(width 0.08255)
			(type default)
		)
		(layer "B.Cu")
	)
	(gr_line
		(start 230.86822 -118.032022)
		(end 231.461818 -118.417594)
		(stroke
			(width 0.08255)
			(type default)
		)
		(layer "B.Cu")
	)
	(gr_line
		(start 230.89108 -99.574858)
		(end 231.243886 -100.11791)
		(stroke
			(width 0.08255)
			(type default)
		)
		(layer "B.Cu")
	)
	(gr_line
		(start 230.93045 -111.675926)
		(end 230.963216 -111.830866)
		(stroke
			(width 0.08255)
			(type default)
		)
		(layer "B.Cu")
	)
	(gr_line
		(start 230.946452 -106.695494)
		(end 231.101392 -106.728514)
		(stroke
			(width 0.08255)
			(type default)
		)
		(layer "B.Cu")
	)
	(gr_line
		(start 230.963216 -111.830866)
		(end 231.37876 -112.100614)
		(stroke
			(width 0.08255)
			(type default)
		)
		(layer "B.Cu")
	)
	(gr_line
		(start 230.975662 -105.993946)
		(end 231.3305 -106.5403)
		(stroke
			(width 0.08255)
			(type default)
		)
		(layer "B.Cu")
	)
	(gr_line
		(start 231.043988 -117.783102)
		(end 231.19969 -117.750336)
		(stroke
			(width 0.08255)
			(type default)
		)
		(layer "B.Cu")
	)
	(gr_line
		(start 231.06126 -109.623098)
		(end 231.09428 -109.778292)
		(stroke
			(width 0.08255)
			(type default)
		)
		(layer "B.Cu")
	)
	(gr_line
		(start 231.09428 -109.778292)
		(end 231.50957 -110.04804)
		(stroke
			(width 0.08255)
			(type default)
		)
		(layer "B.Cu")
	)
	(gr_line
		(start 231.118664 -111.446818)
		(end 231.665526 -111.802164)
		(stroke
			(width 0.08255)
			(type default)
		)
		(layer "B.Cu")
	)
	(gr_line
		(start 231.19969 -117.750336)
		(end 231.615234 -118.020084)
		(stroke
			(width 0.08255)
			(type default)
		)
		(layer "B.Cu")
	)
	(gr_line
		(start 231.25049 -109.394752)
		(end 231.795066 -109.748574)
		(stroke
			(width 0.08255)
			(type default)
		)
		(layer "B.Cu")
	)
	(gr_line
		(start 231.34066 -107.302808)
		(end 231.37368 -107.147868)
		(stroke
			(width 0.08255)
			(type default)
		)
		(layer "B.Cu")
	)
	(gr_line
		(start 231.34066 -107.302808)
		(end 231.610408 -107.718098)
		(stroke
			(width 0.08255)
			(type default)
		)
		(layer "B.Cu")
	)
	(gr_line
		(start 231.37876 -112.100614)
		(end 231.5337 -112.067848)
		(stroke
			(width 0.08255)
			(type default)
		)
		(layer "B.Cu")
	)
	(gr_line
		(start 231.494838 -210.323176)
		(end 231.507792 -210.331558)
		(stroke
			(width 0.0635)
			(type default)
		)
		(layer "B.Cu")
	)
	(gr_line
		(start 231.507792 -210.331558)
		(end 231.523032 -210.33486)
		(stroke
			(width 0.0635)
			(type default)
		)
		(layer "B.Cu")
	)
	(gr_line
		(start 231.50957 -110.04804)
		(end 231.66451 -110.01502)
		(stroke
			(width 0.08255)
			(type default)
		)
		(layer "B.Cu")
	)
	(gr_line
		(start 231.610408 -107.718098)
		(end 231.765348 -107.750864)
		(stroke
			(width 0.08255)
			(type default)
		)
		(layer "B.Cu")
	)
	(gr_line
		(start 231.615234 -118.020084)
		(end 231.651048 -118.189248)
		(stroke
			(width 0.08255)
			(type default)
		)
		(layer "B.Cu")
	)
	(gr_line
		(start 231.640126 -107.017312)
		(end 231.993186 -107.560872)
		(stroke
			(width 0.08255)
			(type default)
		)
		(layer "B.Cu")
	)
	(gr_line
		(start 231.938576 -118.72722)
		(end 232.501948 -119.093234)
		(stroke
			(width 0.08255)
			(type default)
		)
		(layer "B.Cu")
	)
	(gr_line
		(start 232.070402 -118.461282)
		(end 232.239312 -118.425468)
		(stroke
			(width 0.08255)
			(type default)
		)
		(layer "B.Cu")
	)
	(gr_line
		(start 232.083864 -110.287308)
		(end 232.11663 -110.442248)
		(stroke
			(width 0.08255)
			(type default)
		)
		(layer "B.Cu")
	)
	(gr_line
		(start 232.11663 -110.442248)
		(end 232.532174 -110.711996)
		(stroke
			(width 0.08255)
			(type default)
		)
		(layer "B.Cu")
	)
	(gr_line
		(start 232.224326 -108.453174)
		(end 232.237534 -108.473748)
		(stroke
			(width 0.08255)
			(type default)
		)
		(layer "B.Cu")
	)
	(gr_line
		(start 232.237534 -108.473748)
		(end 232.258108 -108.486956)
		(stroke
			(width 0.08255)
			(type default)
		)
		(layer "B.Cu")
	)
	(gr_line
		(start 232.239312 -118.425468)
		(end 232.654602 -118.695216)
		(stroke
			(width 0.08255)
			(type default)
		)
		(layer "B.Cu")
	)
	(gr_line
		(start 232.272586 -110.058454)
		(end 232.819448 -110.413546)
		(stroke
			(width 0.08255)
			(type default)
		)
		(layer "B.Cu")
	)
	(gr_line
		(start 232.532174 -110.711996)
		(end 232.687114 -110.67923)
		(stroke
			(width 0.08255)
			(type default)
		)
		(layer "B.Cu")
	)
	(gr_line
		(start 232.654602 -118.695216)
		(end 232.69067 -118.864126)
		(stroke
			(width 0.08255)
			(type default)
		)
		(layer "B.Cu")
	)
	(gr_line
		(start 232.978452 -119.402352)
		(end 233.540554 -119.767096)
		(stroke
			(width 0.08255)
			(type default)
		)
		(layer "B.Cu")
	)
	(gr_line
		(start 233.110024 -119.136414)
		(end 233.278934 -119.100346)
		(stroke
			(width 0.08255)
			(type default)
		)
		(layer "B.Cu")
	)
	(gr_line
		(start 233.278934 -119.100346)
		(end 233.694224 -119.370348)
		(stroke
			(width 0.08255)
			(type default)
		)
		(layer "B.Cu")
	)
	(gr_line
		(start 233.508804 -107.322366)
		(end 233.522012 -107.34294)
		(stroke
			(width 0.08255)
			(type default)
		)
		(layer "B.Cu")
	)
	(gr_line
		(start 233.522012 -107.34294)
		(end 233.542586 -107.356148)
		(stroke
			(width 0.08255)
			(type default)
		)
		(layer "B.Cu")
	)
	(gr_line
		(start 233.694224 -119.370348)
		(end 233.730038 -119.539258)
		(stroke
			(width 0.08255)
			(type default)
		)
		(layer "B.Cu")
	)
	(gr_line
		(start 234.015788 -120.076214)
		(end 234.5817 -120.443752)
		(stroke
			(width 0.08255)
			(type default)
		)
		(layer "B.Cu")
	)
	(gr_line
		(start 234.117134 -117.950234)
		(end 234.149646 -118.105174)
		(stroke
			(width 0.08255)
			(type default)
		)
		(layer "B.Cu")
	)
	(gr_line
		(start 234.149392 -119.811546)
		(end 234.318302 -119.775478)
		(stroke
			(width 0.08255)
			(type default)
		)
		(layer "B.Cu")
	)
	(gr_line
		(start 234.149646 -118.105174)
		(end 234.564936 -118.375176)
		(stroke
			(width 0.08255)
			(type default)
		)
		(layer "B.Cu")
	)
	(gr_line
		(start 234.306872 -117.722142)
		(end 234.851702 -118.076472)
		(stroke
			(width 0.08255)
			(type default)
		)
		(layer "B.Cu")
	)
	(gr_line
		(start 234.318302 -119.775478)
		(end 234.733846 -120.045226)
		(stroke
			(width 0.08255)
			(type default)
		)
		(layer "B.Cu")
	)
	(gr_line
		(start 234.564936 -118.375176)
		(end 234.719876 -118.34241)
		(stroke
			(width 0.08255)
			(type default)
		)
		(layer "B.Cu")
	)
	(gr_line
		(start 234.733846 -120.045226)
		(end 234.76966 -120.21439)
		(stroke
			(width 0.08255)
			(type default)
		)
		(layer "B.Cu")
	)
	(gr_line
		(start 234.860084 -106.222546)
		(end 234.873292 -106.24312)
		(stroke
			(width 0.08255)
			(type default)
		)
		(layer "B.Cu")
	)
	(gr_line
		(start 234.873292 -106.24312)
		(end 234.893866 -106.256328)
		(stroke
			(width 0.08255)
			(type default)
		)
		(layer "B.Cu")
	)
	(gr_line
		(start 235.138976 -118.614952)
		(end 235.171742 -118.769892)
		(stroke
			(width 0.08255)
			(type default)
		)
		(layer "B.Cu")
	)
	(gr_line
		(start 235.171742 -118.769892)
		(end 235.587032 -119.039894)
		(stroke
			(width 0.08255)
			(type default)
		)
		(layer "B.Cu")
	)
	(gr_line
		(start 235.327952 -118.386098)
		(end 235.875322 -118.741952)
		(stroke
			(width 0.08255)
			(type default)
		)
		(layer "B.Cu")
	)
	(gr_line
		(start 235.587032 -119.039894)
		(end 235.741972 -119.007128)
		(stroke
			(width 0.08255)
			(type default)
		)
		(layer "B.Cu")
	)
	(gr_line
		(start 235.80979 -103.501444)
		(end 235.822998 -103.522018)
		(stroke
			(width 0.08255)
			(type default)
		)
		(layer "B.Cu")
	)
	(gr_line
		(start 235.822998 -103.522018)
		(end 235.843572 -103.535226)
		(stroke
			(width 0.08255)
			(type default)
		)
		(layer "B.Cu")
	)
	(gr_line
		(start 236.139736 -209.697574)
		(end 236.153198 -209.706464)
		(stroke
			(width 0.0635)
			(type default)
		)
		(layer "B.Cu")
	)
	(gr_line
		(start 236.153198 -209.706464)
		(end 236.169454 -209.71002)
		(stroke
			(width 0.0635)
			(type default)
		)
		(layer "B.Cu")
	)
	(gr_line
		(start 236.161072 -119.27967)
		(end 236.193838 -119.43461)
		(stroke
			(width 0.08255)
			(type default)
		)
		(layer "B.Cu")
	)
	(gr_line
		(start 236.193838 -119.43461)
		(end 236.609128 -119.704612)
		(stroke
			(width 0.08255)
			(type default)
		)
		(layer "B.Cu")
	)
	(gr_line
		(start 236.349286 -119.050308)
		(end 236.896656 -119.406416)
		(stroke
			(width 0.08255)
			(type default)
		)
		(layer "B.Cu")
	)
	(gr_line
		(start 236.609128 -119.704612)
		(end 236.763814 -119.671846)
		(stroke
			(width 0.08255)
			(type default)
		)
		(layer "B.Cu")
	)
	(gr_line
		(start 237.55096 -104.646984)
		(end 237.583726 -104.80167)
		(stroke
			(width 0.08255)
			(type default)
		)
		(layer "B.Cu")
	)
	(gr_line
		(start 237.583726 -104.80167)
		(end 237.999016 -105.071418)
		(stroke
			(width 0.08255)
			(type default)
		)
		(layer "B.Cu")
	)
	(gr_line
		(start 237.739936 -104.41813)
		(end 238.286798 -104.773222)
		(stroke
			(width 0.08255)
			(type default)
		)
		(layer "B.Cu")
	)
	(gr_line
		(start 237.999016 -105.071418)
		(end 238.153956 -105.038652)
		(stroke
			(width 0.08255)
			(type default)
		)
		(layer "B.Cu")
	)
	(gr_line
		(start 238.57331 -105.310686)
		(end 238.60633 -105.46588)
		(stroke
			(width 0.08255)
			(type default)
		)
		(layer "B.Cu")
	)
	(gr_line
		(start 238.60633 -105.46588)
		(end 239.02162 -105.735628)
		(stroke
			(width 0.08255)
			(type default)
		)
		(layer "B.Cu")
	)
	(gr_line
		(start 238.762032 -105.081832)
		(end 239.308894 -105.436924)
		(stroke
			(width 0.08255)
			(type default)
		)
		(layer "B.Cu")
	)
	(gr_line
		(start 239.02162 -105.735628)
		(end 239.17656 -105.702608)
		(stroke
			(width 0.08255)
			(type default)
		)
		(layer "B.Cu")
	)
	(gr_line
		(start 239.155986 -357.682292)
		(end 239.430052 -357.408226)
		(stroke
			(width 0.127)
			(type default)
		)
		(layer "B.Cu")
	)
	(gr_line
		(start 239.155986 -356.412292)
		(end 239.430052 -356.686358)
		(stroke
			(width 0.127)
			(type default)
		)
		(layer "B.Cu")
	)
	(gr_line
		(start 239.781842 -207.556862)
		(end 239.795304 -207.565752)
		(stroke
			(width 0.0635)
			(type default)
		)
		(layer "B.Cu")
	)
	(gr_line
		(start 239.795304 -207.565752)
		(end 239.81156 -207.569308)
		(stroke
			(width 0.0635)
			(type default)
		)
		(layer "B.Cu")
	)
	(gr_line
		(start 240.64849 -205.311248)
		(end 240.661952 -205.320138)
		(stroke
			(width 0.0635)
			(type default)
		)
		(layer "B.Cu")
	)
	(gr_line
		(start 240.661952 -205.320138)
		(end 240.678208 -205.323694)
		(stroke
			(width 0.0635)
			(type default)
		)
		(layer "B.Cu")
	)
	(gr_line
		(start 242.171474 -203.107798)
		(end 242.184936 -203.116688)
		(stroke
			(width 0.0635)
			(type default)
		)
		(layer "B.Cu")
	)
	(gr_line
		(start 242.184936 -203.116688)
		(end 242.201192 -203.120244)
		(stroke
			(width 0.0635)
			(type default)
		)
		(layer "B.Cu")
	)
	(gr_line
		(start 243.828316 -236.23778)
		(end 243.841778 -236.236002)
		(stroke
			(width 0.0635)
			(type default)
		)
		(layer "B.Cu")
	)
	(gr_line
		(start 243.841778 -236.236002)
		(end 243.85524 -236.238796)
		(stroke
			(width 0.0635)
			(type default)
		)
		(layer "B.Cu")
	)
	(gr_line
		(start 244.088412 -108.89234)
		(end 244.121178 -109.04728)
		(stroke
			(width 0.08255)
			(type default)
		)
		(layer "B.Cu")
	)
	(gr_line
		(start 244.121178 -109.04728)
		(end 244.536468 -109.317028)
		(stroke
			(width 0.08255)
			(type default)
		)
		(layer "B.Cu")
	)
	(gr_line
		(start 244.276118 -108.662724)
		(end 244.825266 -109.01934)
		(stroke
			(width 0.08255)
			(type default)
		)
		(layer "B.Cu")
	)
	(gr_line
		(start 244.311678 -354.0506)
		(end 244.602 -354.340922)
		(stroke
			(width 0.127)
			(type default)
		)
		(layer "B.Cu")
	)
	(gr_line
		(start 244.316758 -367.118138)
		(end 244.450616 -366.98428)
		(stroke
			(width 0.127)
			(type default)
		)
		(layer "B.Cu")
	)
	(gr_line
		(start 244.316758 -366.128554)
		(end 244.450616 -366.262412)
		(stroke
			(width 0.127)
			(type default)
		)
		(layer "B.Cu")
	)
	(gr_line
		(start 244.536468 -109.317028)
		(end 244.691662 -109.284262)
		(stroke
			(width 0.08255)
			(type default)
		)
		(layer "B.Cu")
	)
	(gr_line
		(start 245.110762 -109.556296)
		(end 245.143782 -109.711236)
		(stroke
			(width 0.08255)
			(type default)
		)
		(layer "B.Cu")
	)
	(gr_line
		(start 245.143782 -109.711236)
		(end 245.559072 -109.981238)
		(stroke
			(width 0.08255)
			(type default)
		)
		(layer "B.Cu")
	)
	(gr_line
		(start 245.297198 -109.325664)
		(end 245.848124 -109.68355)
		(stroke
			(width 0.08255)
			(type default)
		)
		(layer "B.Cu")
	)
	(gr_line
		(start 245.323868 -354.340922)
		(end 245.61419 -354.0506)
		(stroke
			(width 0.127)
			(type default)
		)
		(layer "B.Cu")
	)
	(gr_line
		(start 245.559072 -109.981238)
		(end 245.714012 -109.948218)
		(stroke
			(width 0.08255)
			(type default)
		)
		(layer "B.Cu")
	)
	(gr_line
		(start 246.133366 -110.220252)
		(end 246.166132 -110.375446)
		(stroke
			(width 0.08255)
			(type default)
		)
		(layer "B.Cu")
	)
	(gr_line
		(start 246.166132 -110.375446)
		(end 246.581676 -110.645194)
		(stroke
			(width 0.08255)
			(type default)
		)
		(layer "B.Cu")
	)
	(gr_line
		(start 246.321072 -109.990636)
		(end 246.87022 -110.347252)
		(stroke
			(width 0.08255)
			(type default)
		)
		(layer "B.Cu")
	)
	(gr_line
		(start 246.339614 -128.079246)
		(end 246.90578 -128.447038)
		(stroke
			(width 0.08255)
			(type default)
		)
		(layer "B.Cu")
	)
	(gr_line
		(start 246.362474 -162.244532)
		(end 246.383048 -162.25774)
		(stroke
			(width 0.0635)
			(type default)
		)
		(layer "B.Cu")
	)
	(gr_line
		(start 246.383048 -162.25774)
		(end 246.396256 -162.278314)
		(stroke
			(width 0.0635)
			(type default)
		)
		(layer "B.Cu")
	)
	(gr_line
		(start 246.47271 -127.81407)
		(end 246.641874 -127.778256)
		(stroke
			(width 0.08255)
			(type default)
		)
		(layer "B.Cu")
	)
	(gr_line
		(start 246.581676 -110.645194)
		(end 246.736362 -110.612174)
		(stroke
			(width 0.08255)
			(type default)
		)
		(layer "B.Cu")
	)
	(gr_line
		(start 246.641874 -127.778256)
		(end 247.057418 -128.048004)
		(stroke
			(width 0.08255)
			(type default)
		)
		(layer "B.Cu")
	)
	(gr_line
		(start 247.057418 -128.048004)
		(end 247.093486 -128.217168)
		(stroke
			(width 0.08255)
			(type default)
		)
		(layer "B.Cu")
	)
	(gr_line
		(start 247.379744 -128.754632)
		(end 247.94337 -129.120646)
		(stroke
			(width 0.08255)
			(type default)
		)
		(layer "B.Cu")
	)
	(gr_line
		(start 247.512332 -128.489202)
		(end 247.681496 -128.453388)
		(stroke
			(width 0.08255)
			(type default)
		)
		(layer "B.Cu")
	)
	(gr_line
		(start 247.681496 -128.453388)
		(end 248.096786 -128.723136)
		(stroke
			(width 0.08255)
			(type default)
		)
		(layer "B.Cu")
	)
	(gr_line
		(start 248.096786 -128.723136)
		(end 248.1326 -128.892046)
		(stroke
			(width 0.08255)
			(type default)
		)
		(layer "B.Cu")
	)
	(gr_line
		(start 248.114058 -161.458656)
		(end 248.134632 -161.471864)
		(stroke
			(width 0.0635)
			(type default)
		)
		(layer "B.Cu")
	)
	(gr_line
		(start 248.134632 -161.471864)
		(end 248.14784 -161.492438)
		(stroke
			(width 0.0635)
			(type default)
		)
		(layer "B.Cu")
	)
	(gr_line
		(start 248.41962 -129.430018)
		(end 248.984008 -129.79654)
		(stroke
			(width 0.08255)
			(type default)
		)
		(layer "B.Cu")
	)
	(gr_line
		(start 248.551954 -129.164334)
		(end 248.721118 -129.12852)
		(stroke
			(width 0.08255)
			(type default)
		)
		(layer "B.Cu")
	)
	(gr_line
		(start 248.721118 -129.12852)
		(end 249.136408 -129.398268)
		(stroke
			(width 0.08255)
			(type default)
		)
		(layer "B.Cu")
	)
	(gr_line
		(start 249.050048 -366.976406)
		(end 249.515122 -367.44148)
		(stroke
			(width 0.127)
			(type default)
		)
		(layer "B.Cu")
	)
	(gr_line
		(start 249.050048 -366.254284)
		(end 249.515122 -365.78921)
		(stroke
			(width 0.127)
			(type default)
		)
		(layer "B.Cu")
	)
	(gr_line
		(start 249.136408 -129.398268)
		(end 249.172222 -129.567178)
		(stroke
			(width 0.08255)
			(type default)
		)
		(layer "B.Cu")
	)
	(gr_line
		(start 249.16765 -160.246822)
		(end 249.188224 -160.26003)
		(stroke
			(width 0.0635)
			(type default)
		)
		(layer "B.Cu")
	)
	(gr_line
		(start 249.188224 -160.26003)
		(end 249.201432 -160.280604)
		(stroke
			(width 0.0635)
			(type default)
		)
		(layer "B.Cu")
	)
	(gr_line
		(start 249.458988 -130.104896)
		(end 250.022614 -130.47091)
		(stroke
			(width 0.08255)
			(type default)
		)
		(layer "B.Cu")
	)
	(gr_line
		(start 249.591576 -129.839466)
		(end 249.760486 -129.803652)
		(stroke
			(width 0.08255)
			(type default)
		)
		(layer "B.Cu")
	)
	(gr_line
		(start 249.760486 -129.803652)
		(end 250.17603 -130.0734)
		(stroke
			(width 0.08255)
			(type default)
		)
		(layer "B.Cu")
	)
	(gr_line
		(start 250.17603 -130.0734)
		(end 250.211844 -130.24231)
		(stroke
			(width 0.08255)
			(type default)
		)
		(layer "B.Cu")
	)
	(gr_line
		(start 251.15393 -159.630872)
		(end 251.174504 -159.64408)
		(stroke
			(width 0.0635)
			(type default)
		)
		(layer "B.Cu")
	)
	(gr_line
		(start 251.174504 -159.64408)
		(end 251.187712 -159.664654)
		(stroke
			(width 0.0635)
			(type default)
		)
		(layer "B.Cu")
	)
	(gr_line
		(start 252.437646 -158.63189)
		(end 252.45822 -158.645098)
		(stroke
			(width 0.0635)
			(type default)
		)
		(layer "B.Cu")
	)
	(gr_line
		(start 252.45822 -158.645098)
		(end 252.471428 -158.665672)
		(stroke
			(width 0.0635)
			(type default)
		)
		(layer "B.Cu")
	)
	(gr_line
		(start 253.678182 -157.59938)
		(end 253.698756 -157.612588)
		(stroke
			(width 0.0635)
			(type default)
		)
		(layer "B.Cu")
	)
	(gr_line
		(start 253.698756 -157.612588)
		(end 253.711964 -157.633162)
		(stroke
			(width 0.0635)
			(type default)
		)
		(layer "B.Cu")
	)
	(gr_line
		(start 258.645914 -236.5121)
		(end 258.669028 -236.51718)
		(stroke
			(width 0.0635)
			(type default)
		)
		(layer "B.Cu")
	)
	(gr_line
		(start 258.655312 -234.938824)
		(end 258.678426 -234.943904)
		(stroke
			(width 0.0635)
			(type default)
		)
		(layer "B.Cu")
	)
	(gr_line
		(start 258.669028 -236.51718)
		(end 258.692142 -236.5121)
		(stroke
			(width 0.0635)
			(type default)
		)
		(layer "B.Cu")
	)
	(gr_line
		(start 258.678426 -234.943904)
		(end 258.70154 -234.938824)
		(stroke
			(width 0.0635)
			(type default)
		)
		(layer "B.Cu")
	)
	(gr_line
		(start 258.683252 -238.103156)
		(end 258.706366 -238.108236)
		(stroke
			(width 0.0635)
			(type default)
		)
		(layer "B.Cu")
	)
	(gr_line
		(start 258.706366 -238.108236)
		(end 258.72948 -238.103156)
		(stroke
			(width 0.0635)
			(type default)
		)
		(layer "B.Cu")
	)
	(gr_line
		(start 258.74091 -239.701832)
		(end 258.764024 -239.706912)
		(stroke
			(width 0.0635)
			(type default)
		)
		(layer "B.Cu")
	)
	(gr_line
		(start 258.755134 -231.620568)
		(end 258.778248 -231.625648)
		(stroke
			(width 0.0635)
			(type default)
		)
		(layer "B.Cu")
	)
	(gr_line
		(start 258.764024 -239.706912)
		(end 258.787138 -239.701832)
		(stroke
			(width 0.0635)
			(type default)
		)
		(layer "B.Cu")
	)
	(gr_line
		(start 258.778248 -231.625648)
		(end 258.801362 -231.620568)
		(stroke
			(width 0.0635)
			(type default)
		)
		(layer "B.Cu")
	)
	(gr_line
		(start 258.832858 -233.257598)
		(end 258.855972 -233.262678)
		(stroke
			(width 0.0635)
			(type default)
		)
		(layer "B.Cu")
	)
	(gr_line
		(start 258.855972 -233.262678)
		(end 258.879086 -233.257598)
		(stroke
			(width 0.0635)
			(type default)
		)
		(layer "B.Cu")
	)
	(gr_line
		(start 261.83209 -186.582812)
		(end 261.845298 -186.603386)
		(stroke
			(width 0.0635)
			(type default)
		)
		(layer "B.Cu")
	)
	(gr_line
		(start 261.845298 -186.603386)
		(end 261.865872 -186.616594)
		(stroke
			(width 0.0635)
			(type default)
		)
		(layer "B.Cu")
	)
	(gr_line
		(start 261.963916 -204.55509)
		(end 261.977378 -204.56398)
		(stroke
			(width 0.0635)
			(type default)
		)
		(layer "B.Cu")
	)
	(gr_line
		(start 261.977378 -204.56398)
		(end 261.993634 -204.567536)
		(stroke
			(width 0.0635)
			(type default)
		)
		(layer "B.Cu")
	)
	(gr_line
		(start 263.623298 -185.85815)
		(end 263.636506 -185.878724)
		(stroke
			(width 0.0635)
			(type default)
		)
		(layer "B.Cu")
	)
	(gr_line
		(start 263.636506 -185.878724)
		(end 263.65708 -185.891932)
		(stroke
			(width 0.0635)
			(type default)
		)
		(layer "B.Cu")
	)
	(gr_line
		(start 264.724642 -184.719722)
		(end 264.73785 -184.740296)
		(stroke
			(width 0.0635)
			(type default)
		)
		(layer "B.Cu")
	)
	(gr_line
		(start 264.73785 -184.740296)
		(end 264.758424 -184.753504)
		(stroke
			(width 0.0635)
			(type default)
		)
		(layer "B.Cu")
	)
	(gr_line
		(start 265.684254 -138.481562)
		(end 265.71702 -138.636756)
		(stroke
			(width 0.08255)
			(type default)
		)
		(layer "B.Cu")
	)
	(gr_line
		(start 265.71702 -138.636756)
		(end 266.13231 -138.906758)
		(stroke
			(width 0.08255)
			(type default)
		)
		(layer "B.Cu")
	)
	(gr_line
		(start 265.873738 -138.253724)
		(end 266.41806 -138.6078)
		(stroke
			(width 0.08255)
			(type default)
		)
		(layer "B.Cu")
	)
	(gr_line
		(start 266.13231 -138.906758)
		(end 266.28725 -138.873992)
		(stroke
			(width 0.08255)
			(type default)
		)
		(layer "B.Cu")
	)
	(gr_line
		(start 266.564872 -183.879236)
		(end 266.57808 -183.89981)
		(stroke
			(width 0.0635)
			(type default)
		)
		(layer "B.Cu")
	)
	(gr_line
		(start 266.57808 -183.89981)
		(end 266.598654 -183.913018)
		(stroke
			(width 0.0635)
			(type default)
		)
		(layer "B.Cu")
	)
	(gr_line
		(start 266.70635 -139.14628)
		(end 266.739116 -139.301474)
		(stroke
			(width 0.08255)
			(type default)
		)
		(layer "B.Cu")
	)
	(gr_line
		(start 266.739116 -139.301474)
		(end 267.154406 -139.571476)
		(stroke
			(width 0.08255)
			(type default)
		)
		(layer "B.Cu")
	)
	(gr_line
		(start 266.896088 -138.918442)
		(end 267.267944 -139.16025)
		(stroke
			(width 0.08255)
			(type default)
		)
		(layer "B.Cu")
	)
	(gr_line
		(start 267.154406 -139.571476)
		(end 267.309346 -139.53871)
		(stroke
			(width 0.08255)
			(type default)
		)
		(layer "B.Cu")
	)
	(gr_line
		(start 267.214858 -216.308686)
		(end 267.237972 -216.313766)
		(stroke
			(width 0.0635)
			(type default)
		)
		(layer "B.Cu")
	)
	(gr_line
		(start 267.237972 -216.313766)
		(end 267.261086 -216.308686)
		(stroke
			(width 0.0635)
			(type default)
		)
		(layer "B.Cu")
	)
	(gr_line
		(start 267.267944 -139.16025)
		(end 267.440664 -139.272772)
		(stroke
			(width 0.08255)
			(type default)
		)
		(layer "B.Cu")
	)
	(gr_line
		(start 267.27785 -217.935048)
		(end 267.300964 -217.940128)
		(stroke
			(width 0.0635)
			(type default)
		)
		(layer "B.Cu")
	)
	(gr_line
		(start 267.300964 -217.940128)
		(end 267.324078 -217.935048)
		(stroke
			(width 0.0635)
			(type default)
		)
		(layer "B.Cu")
	)
	(gr_line
		(start 267.575792 -182.45963)
		(end 267.589 -182.480204)
		(stroke
			(width 0.0635)
			(type default)
		)
		(layer "B.Cu")
	)
	(gr_line
		(start 267.589 -182.480204)
		(end 267.609574 -182.493412)
		(stroke
			(width 0.0635)
			(type default)
		)
		(layer "B.Cu")
	)
	(gr_line
		(start 268.520418 -180.97246)
		(end 268.533626 -180.993034)
		(stroke
			(width 0.0635)
			(type default)
		)
		(layer "B.Cu")
	)
	(gr_line
		(start 268.533626 -180.993034)
		(end 268.5542 -181.006242)
		(stroke
			(width 0.0635)
			(type default)
		)
		(layer "B.Cu")
	)
	(gr_line
		(start 269.296134 -142.987014)
		(end 269.857474 -143.35125)
		(stroke
			(width 0.08255)
			(type default)
		)
		(layer "B.Cu")
	)
	(gr_line
		(start 269.426944 -142.720568)
		(end 269.595854 -142.684754)
		(stroke
			(width 0.08255)
			(type default)
		)
		(layer "B.Cu")
	)
	(gr_line
		(start 269.595854 -142.684754)
		(end 270.011144 -142.954502)
		(stroke
			(width 0.08255)
			(type default)
		)
		(layer "B.Cu")
	)
	(gr_line
		(start 270.011144 -142.954502)
		(end 270.046958 -143.123158)
		(stroke
			(width 0.08255)
			(type default)
		)
		(layer "B.Cu")
	)
	(gr_line
		(start 270.249904 -214.037926)
		(end 270.273018 -214.043006)
		(stroke
			(width 0.0635)
			(type default)
		)
		(layer "B.Cu")
	)
	(gr_line
		(start 270.273018 -214.043006)
		(end 270.296132 -214.037926)
		(stroke
			(width 0.0635)
			(type default)
		)
		(layer "B.Cu")
	)
	(gr_line
		(start 270.333724 -143.660876)
		(end 270.897604 -144.027144)
		(stroke
			(width 0.08255)
			(type default)
		)
		(layer "B.Cu")
	)
	(gr_line
		(start 270.466312 -143.395446)
		(end 270.635476 -143.359632)
		(stroke
			(width 0.08255)
			(type default)
		)
		(layer "B.Cu")
	)
	(gr_line
		(start 270.635476 -143.359632)
		(end 271.050766 -143.62938)
		(stroke
			(width 0.08255)
			(type default)
		)
		(layer "B.Cu")
	)
	(gr_line
		(start 271.050766 -143.62938)
		(end 271.08658 -143.79829)
		(stroke
			(width 0.08255)
			(type default)
		)
		(layer "B.Cu")
	)
	(gr_line
		(start 271.374616 -144.336516)
		(end 271.93621 -144.70126)
		(stroke
			(width 0.08255)
			(type default)
		)
		(layer "B.Cu")
	)
	(gr_line
		(start 271.505934 -144.070578)
		(end 271.674844 -144.034764)
		(stroke
			(width 0.08255)
			(type default)
		)
		(layer "B.Cu")
	)
	(gr_line
		(start 271.674844 -144.034764)
		(end 272.090388 -144.304512)
		(stroke
			(width 0.08255)
			(type default)
		)
		(layer "B.Cu")
	)
	(gr_line
		(start 272.090388 -144.304512)
		(end 272.126202 -144.473422)
		(stroke
			(width 0.08255)
			(type default)
		)
		(layer "B.Cu")
	)
	(gr_line
		(start 272.2118 -212.024722)
		(end 272.234914 -212.029802)
		(stroke
			(width 0.0635)
			(type default)
		)
		(layer "B.Cu")
	)
	(gr_line
		(start 272.234914 -212.029802)
		(end 272.258028 -212.024722)
		(stroke
			(width 0.0635)
			(type default)
		)
		(layer "B.Cu")
	)
	(gr_line
		(start 272.414746 -145.012156)
		(end 272.97634 -145.3769)
		(stroke
			(width 0.08255)
			(type default)
		)
		(layer "B.Cu")
	)
	(gr_line
		(start 272.545556 -144.74571)
		(end 272.714466 -144.709896)
		(stroke
			(width 0.08255)
			(type default)
		)
		(layer "B.Cu")
	)
	(gr_line
		(start 272.714466 -144.709896)
		(end 273.13001 -144.979644)
		(stroke
			(width 0.08255)
			(type default)
		)
		(layer "B.Cu")
	)
	(gr_line
		(start 273.13001 -144.979644)
		(end 273.165824 -145.148554)
		(stroke
			(width 0.08255)
			(type default)
		)
		(layer "B.Cu")
	)
	(gr_line
		(start 273.25447 -194.012566)
		(end 273.267932 -194.021456)
		(stroke
			(width 0.0635)
			(type default)
		)
		(layer "B.Cu")
	)
	(gr_line
		(start 273.267932 -194.021456)
		(end 273.284188 -194.025012)
		(stroke
			(width 0.0635)
			(type default)
		)
		(layer "B.Cu")
	)
	(gr_line
		(start 273.454114 -145.687034)
		(end 273.536156 -145.740374)
		(stroke
			(width 0.08255)
			(type default)
		)
		(layer "B.Cu")
	)
	(gr_line
		(start 273.456146 -192.255648)
		(end 273.469608 -192.264538)
		(stroke
			(width 0.0635)
			(type default)
		)
		(layer "B.Cu")
	)
	(gr_line
		(start 273.469608 -192.264538)
		(end 273.485864 -192.268094)
		(stroke
			(width 0.0635)
			(type default)
		)
		(layer "B.Cu")
	)
	(gr_line
		(start 273.579082 -190.481712)
		(end 273.592544 -190.490602)
		(stroke
			(width 0.0635)
			(type default)
		)
		(layer "B.Cu")
	)
	(gr_arc
		(start 273.581876 -145.421604)
		(mid 273.624899 -145.44146)
		(end 273.671792 -145.448274)
		(stroke
			(width 0.08255)
			(type default)
		)
		(layer "B.Cu")
	)
	(gr_line
		(start 273.592544 -190.490602)
		(end 273.6088 -190.494158)
		(stroke
			(width 0.0635)
			(type default)
		)
		(layer "B.Cu")
	)
	(gr_line
		(start 274.041108 -143.914114)
		(end 274.081494 -143.94053)
		(stroke
			(width 0.08255)
			(type default)
		)
		(layer "B.Cu")
	)
	(gr_line
		(start 274.117816 -188.795914)
		(end 274.131278 -188.804804)
		(stroke
			(width 0.0635)
			(type default)
		)
		(layer "B.Cu")
	)
	(gr_line
		(start 274.131278 -188.804804)
		(end 274.147534 -188.80836)
		(stroke
			(width 0.0635)
			(type default)
		)
		(layer "B.Cu")
	)
	(gr_line
		(start 274.26539 -142.11427)
		(end 274.305776 -142.140432)
		(stroke
			(width 0.08255)
			(type default)
		)
		(layer "B.Cu")
	)
	(gr_line
		(start 274.751038 -187.130944)
		(end 274.7645 -187.139834)
		(stroke
			(width 0.0635)
			(type default)
		)
		(layer "B.Cu")
	)
	(gr_line
		(start 274.7645 -187.139834)
		(end 274.780756 -187.14339)
		(stroke
			(width 0.0635)
			(type default)
		)
		(layer "B.Cu")
	)
	(gr_line
		(start 275.030438 -140.314426)
		(end 275.070824 -140.340588)
		(stroke
			(width 0.08255)
			(type default)
		)
		(layer "B.Cu")
	)
	(gr_line
		(start 275.537422 -185.540904)
		(end 275.550884 -185.549794)
		(stroke
			(width 0.0635)
			(type default)
		)
		(layer "B.Cu")
	)
	(gr_line
		(start 275.549868 -138.514328)
		(end 275.590254 -138.54049)
		(stroke
			(width 0.08255)
			(type default)
		)
		(layer "B.Cu")
	)
	(gr_line
		(start 275.550884 -185.549794)
		(end 275.56714 -185.55335)
		(stroke
			(width 0.0635)
			(type default)
		)
		(layer "B.Cu")
	)
	(gr_line
		(start 275.724874 -136.714484)
		(end 275.76526 -136.740646)
		(stroke
			(width 0.08255)
			(type default)
		)
		(layer "B.Cu")
	)
	(gr_line
		(start 275.978366 -134.914386)
		(end 276.018752 -134.940548)
		(stroke
			(width 0.08255)
			(type default)
		)
		(layer "B.Cu")
	)
	(gr_line
		(start 276.251162 -133.114288)
		(end 276.291548 -133.14045)
		(stroke
			(width 0.08255)
			(type default)
		)
		(layer "B.Cu")
	)
	(gr_line
		(start 278.23668 -236.89437)
		(end 278.576786 -236.89437)
		(stroke
			(width 0.0635)
			(type default)
		)
		(layer "B.Cu")
	)
	(gr_line
		(start 278.23668 -233.294428)
		(end 278.576786 -233.294428)
		(stroke
			(width 0.0635)
			(type default)
		)
		(layer "B.Cu")
	)
	(gr_line
		(start 278.23668 -229.694486)
		(end 278.576786 -229.694486)
		(stroke
			(width 0.0635)
			(type default)
		)
		(layer "B.Cu")
	)
	(gr_line
		(start 278.23668 -226.094544)
		(end 278.545798 -226.094544)
		(stroke
			(width 0.0635)
			(type default)
		)
		(layer "B.Cu")
	)
	(gr_line
		(start 278.23668 -222.494348)
		(end 278.628602 -222.494348)
		(stroke
			(width 0.0635)
			(type default)
		)
		(layer "B.Cu")
	)
	(gr_line
		(start 278.23668 -218.894406)
		(end 278.58466 -218.894406)
		(stroke
			(width 0.0635)
			(type default)
		)
		(layer "B.Cu")
	)
	(gr_line
		(start 278.23668 -215.294464)
		(end 278.576786 -215.294464)
		(stroke
			(width 0.0635)
			(type default)
		)
		(layer "B.Cu")
	)
	(gr_line
		(start 278.23668 -211.694522)
		(end 278.576786 -211.694522)
		(stroke
			(width 0.0635)
			(type default)
		)
		(layer "B.Cu")
	)
	(gr_line
		(start 278.23668 -208.09458)
		(end 278.576786 -208.09458)
		(stroke
			(width 0.0635)
			(type default)
		)
		(layer "B.Cu")
	)
	(gr_line
		(start 278.23668 -204.494384)
		(end 278.642572 -204.494384)
		(stroke
			(width 0.0635)
			(type default)
		)
		(layer "B.Cu")
	)
	(gr_line
		(start 278.23668 -200.894442)
		(end 278.642572 -200.894442)
		(stroke
			(width 0.0635)
			(type default)
		)
		(layer "B.Cu")
	)
	(gr_line
		(start 278.23668 -197.2945)
		(end 278.642572 -197.2945)
		(stroke
			(width 0.0635)
			(type default)
		)
		(layer "B.Cu")
	)
	(gr_line
		(start 278.23668 -193.694558)
		(end 278.576786 -193.694558)
		(stroke
			(width 0.0635)
			(type default)
		)
		(layer "B.Cu")
	)
	(gr_line
		(start 278.23668 -190.094362)
		(end 278.576786 -190.094362)
		(stroke
			(width 0.0635)
			(type default)
		)
		(layer "B.Cu")
	)
	(gr_line
		(start 278.23668 -186.49442)
		(end 278.576786 -186.49442)
		(stroke
			(width 0.0635)
			(type default)
		)
		(layer "B.Cu")
	)
	(gr_line
		(start 278.23668 -182.894478)
		(end 278.601678 -182.894478)
		(stroke
			(width 0.0635)
			(type default)
		)
		(layer "B.Cu")
	)
	(gr_line
		(start 278.23668 -179.294536)
		(end 278.601678 -179.294536)
		(stroke
			(width 0.0635)
			(type default)
		)
		(layer "B.Cu")
	)
	(gr_line
		(start 278.23668 -175.694594)
		(end 278.601678 -175.694594)
		(stroke
			(width 0.0635)
			(type default)
		)
		(layer "B.Cu")
	)
	(gr_line
		(start 278.23668 -142.894304)
		(end 278.598884 -142.894304)
		(stroke
			(width 0.08255)
			(type default)
		)
		(layer "B.Cu")
	)
	(gr_line
		(start 278.23668 -139.294362)
		(end 278.598884 -139.294362)
		(stroke
			(width 0.08255)
			(type default)
		)
		(layer "B.Cu")
	)
	(gr_line
		(start 278.23668 -135.69442)
		(end 278.598884 -135.69442)
		(stroke
			(width 0.08255)
			(type default)
		)
		(layer "B.Cu")
	)
	(gr_line
		(start 278.23668 -132.094478)
		(end 278.598884 -132.094478)
		(stroke
			(width 0.08255)
			(type default)
		)
		(layer "B.Cu")
	)
	(gr_arc
		(start 278.576786 -236.89437)
		(mid 278.728014 -236.83173)
		(end 278.790654 -236.680502)
		(stroke
			(width 0.0635)
			(type default)
		)
		(layer "B.Cu")
	)
	(gr_arc
		(start 278.576786 -233.294428)
		(mid 278.728014 -233.231788)
		(end 278.790654 -233.08056)
		(stroke
			(width 0.0635)
			(type default)
		)
		(layer "B.Cu")
	)
	(gr_arc
		(start 278.576786 -229.694486)
		(mid 278.728014 -229.631846)
		(end 278.790654 -229.480618)
		(stroke
			(width 0.0635)
			(type default)
		)
		(layer "B.Cu")
	)
	(gr_arc
		(start 278.576786 -215.294464)
		(mid 278.728014 -215.231824)
		(end 278.790654 -215.080596)
		(stroke
			(width 0.0635)
			(type default)
		)
		(layer "B.Cu")
	)
	(gr_arc
		(start 278.576786 -211.694522)
		(mid 278.728014 -211.631882)
		(end 278.790654 -211.480654)
		(stroke
			(width 0.0635)
			(type default)
		)
		(layer "B.Cu")
	)
	(gr_arc
		(start 278.576786 -208.09458)
		(mid 278.728014 -208.03194)
		(end 278.790654 -207.880712)
		(stroke
			(width 0.0635)
			(type default)
		)
		(layer "B.Cu")
	)
	(gr_arc
		(start 278.576786 -193.694558)
		(mid 278.728014 -193.631918)
		(end 278.790654 -193.48069)
		(stroke
			(width 0.0635)
			(type default)
		)
		(layer "B.Cu")
	)
	(gr_arc
		(start 278.576786 -190.094362)
		(mid 278.728014 -190.031722)
		(end 278.790654 -189.880494)
		(stroke
			(width 0.0635)
			(type default)
		)
		(layer "B.Cu")
	)
	(gr_arc
		(start 278.576786 -186.49442)
		(mid 278.728014 -186.43178)
		(end 278.790654 -186.280552)
		(stroke
			(width 0.0635)
			(type default)
		)
		(layer "B.Cu")
	)
	(gr_arc
		(start 278.598884 -142.894304)
		(mid 278.734486 -142.838136)
		(end 278.790654 -142.702534)
		(stroke
			(width 0.08255)
			(type default)
		)
		(layer "B.Cu")
	)
	(gr_arc
		(start 278.598884 -139.294362)
		(mid 278.734486 -139.238194)
		(end 278.790654 -139.102592)
		(stroke
			(width 0.08255)
			(type default)
		)
		(layer "B.Cu")
	)
	(gr_arc
		(start 278.598884 -135.69442)
		(mid 278.734486 -135.638252)
		(end 278.790654 -135.50265)
		(stroke
			(width 0.08255)
			(type default)
		)
		(layer "B.Cu")
	)
	(gr_arc
		(start 278.598884 -132.094478)
		(mid 278.734486 -132.03831)
		(end 278.790654 -131.902708)
		(stroke
			(width 0.08255)
			(type default)
		)
		(layer "B.Cu")
	)
	(gr_arc
		(start 278.601678 -182.894478)
		(mid 278.735304 -182.839128)
		(end 278.790654 -182.705502)
		(stroke
			(width 0.0635)
			(type default)
		)
		(layer "B.Cu")
	)
	(gr_arc
		(start 278.601678 -179.294536)
		(mid 278.735304 -179.239186)
		(end 278.790654 -179.10556)
		(stroke
			(width 0.0635)
			(type default)
		)
		(layer "B.Cu")
	)
	(gr_arc
		(start 278.601678 -175.694594)
		(mid 278.735304 -175.639244)
		(end 278.790654 -175.505618)
		(stroke
			(width 0.0635)
			(type default)
		)
		(layer "B.Cu")
	)
	(gr_arc
		(start 278.642572 -204.494384)
		(mid 278.747282 -204.451012)
		(end 278.790654 -204.346302)
		(stroke
			(width 0.0635)
			(type default)
		)
		(layer "B.Cu")
	)
	(gr_arc
		(start 278.642572 -200.894442)
		(mid 278.747282 -200.85107)
		(end 278.790654 -200.74636)
		(stroke
			(width 0.0635)
			(type default)
		)
		(layer "B.Cu")
	)
	(gr_arc
		(start 278.642572 -197.2945)
		(mid 278.747282 -197.251128)
		(end 278.790654 -197.146418)
		(stroke
			(width 0.0635)
			(type default)
		)
		(layer "B.Cu")
	)
	(gr_arc
		(start 278.790654 -226.3394)
		(mid 278.718937 -226.166261)
		(end 278.545798 -226.094544)
		(stroke
			(width 0.0635)
			(type default)
		)
		(layer "B.Cu")
	)
	(gr_arc
		(start 278.790654 -222.6564)
		(mid 278.74319 -222.541811)
		(end 278.628602 -222.494348)
		(stroke
			(width 0.0635)
			(type default)
		)
		(layer "B.Cu")
	)
	(gr_arc
		(start 278.790654 -219.1004)
		(mid 278.730317 -218.954754)
		(end 278.58466 -218.894406)
		(stroke
			(width 0.0635)
			(type default)
		)
		(layer "B.Cu")
	)
	(gr_arc
		(start 279.082754 -236.680502)
		(mid 279.145397 -236.83172)
		(end 279.296622 -236.89437)
		(stroke
			(width 0.0635)
			(type default)
		)
		(layer "B.Cu")
	)
	(gr_arc
		(start 279.082754 -233.08056)
		(mid 279.145382 -233.231806)
		(end 279.296622 -233.294428)
		(stroke
			(width 0.0635)
			(type default)
		)
		(layer "B.Cu")
	)
	(gr_arc
		(start 279.082754 -229.480618)
		(mid 279.145402 -229.631826)
		(end 279.296622 -229.694486)
		(stroke
			(width 0.0635)
			(type default)
		)
		(layer "B.Cu")
	)
	(gr_arc
		(start 279.082754 -215.080596)
		(mid 279.145394 -215.231818)
		(end 279.296622 -215.294464)
		(stroke
			(width 0.0635)
			(type default)
		)
		(layer "B.Cu")
	)
	(gr_arc
		(start 279.082754 -211.480654)
		(mid 279.14538 -211.631903)
		(end 279.296622 -211.694522)
		(stroke
			(width 0.0635)
			(type default)
		)
		(layer "B.Cu")
	)
	(gr_arc
		(start 279.082754 -207.880712)
		(mid 279.1454 -208.031924)
		(end 279.296622 -208.09458)
		(stroke
			(width 0.0635)
			(type default)
		)
		(layer "B.Cu")
	)
	(gr_arc
		(start 279.082754 -204.346302)
		(mid 279.126129 -204.450998)
		(end 279.230836 -204.494384)
		(stroke
			(width 0.0635)
			(type default)
		)
		(layer "B.Cu")
	)
	(gr_arc
		(start 279.082754 -200.74636)
		(mid 279.126114 -200.851083)
		(end 279.230836 -200.894442)
		(stroke
			(width 0.0635)
			(type default)
		)
		(layer "B.Cu")
	)
	(gr_arc
		(start 279.082754 -197.146418)
		(mid 279.126135 -197.251103)
		(end 279.230836 -197.2945)
		(stroke
			(width 0.0635)
			(type default)
		)
		(layer "B.Cu")
	)
	(gr_arc
		(start 279.082754 -193.48069)
		(mid 279.145392 -193.631916)
		(end 279.296622 -193.694558)
		(stroke
			(width 0.0635)
			(type default)
		)
		(layer "B.Cu")
	)
	(gr_arc
		(start 279.082754 -189.880494)
		(mid 279.145394 -190.031718)
		(end 279.296622 -190.094362)
		(stroke
			(width 0.0635)
			(type default)
		)
		(layer "B.Cu")
	)
	(gr_arc
		(start 279.082754 -186.280552)
		(mid 279.145379 -186.431803)
		(end 279.296622 -186.49442)
		(stroke
			(width 0.0635)
			(type default)
		)
		(layer "B.Cu")
	)
	(gr_arc
		(start 279.082754 -182.705502)
		(mid 279.138106 -182.839116)
		(end 279.27173 -182.894478)
		(stroke
			(width 0.0635)
			(type default)
		)
		(layer "B.Cu")
	)
	(gr_arc
		(start 279.082754 -179.10556)
		(mid 279.138091 -179.239201)
		(end 279.27173 -179.294536)
		(stroke
			(width 0.0635)
			(type default)
		)
		(layer "B.Cu")
	)
	(gr_arc
		(start 279.082754 -175.505618)
		(mid 279.138112 -175.639222)
		(end 279.27173 -175.694594)
		(stroke
			(width 0.0635)
			(type default)
		)
		(layer "B.Cu")
	)
	(gr_arc
		(start 279.082754 -142.702534)
		(mid 279.138936 -142.838105)
		(end 279.274524 -142.894304)
		(stroke
			(width 0.08255)
			(type default)
		)
		(layer "B.Cu")
	)
	(gr_arc
		(start 279.082754 -139.102592)
		(mid 279.138921 -139.238191)
		(end 279.274524 -139.294362)
		(stroke
			(width 0.08255)
			(type default)
		)
		(layer "B.Cu")
	)
	(gr_arc
		(start 279.082754 -135.50265)
		(mid 279.138906 -135.638276)
		(end 279.274524 -135.69442)
		(stroke
			(width 0.08255)
			(type default)
		)
		(layer "B.Cu")
	)
	(gr_arc
		(start 279.082754 -131.902708)
		(mid 279.138926 -132.038296)
		(end 279.274524 -132.094478)
		(stroke
			(width 0.08255)
			(type default)
		)
		(layer "B.Cu")
	)
	(gr_line
		(start 279.230836 -204.494384)
		(end 279.636728 -204.494384)
		(stroke
			(width 0.0635)
			(type default)
		)
		(layer "B.Cu")
	)
	(gr_line
		(start 279.230836 -200.894442)
		(end 279.636728 -200.894442)
		(stroke
			(width 0.0635)
			(type default)
		)
		(layer "B.Cu")
	)
	(gr_line
		(start 279.230836 -197.2945)
		(end 279.636728 -197.2945)
		(stroke
			(width 0.0635)
			(type default)
		)
		(layer "B.Cu")
	)
	(gr_line
		(start 279.236678 -238.694468)
		(end 279.576784 -238.694468)
		(stroke
			(width 0.0635)
			(type default)
		)
		(layer "B.Cu")
	)
	(gr_line
		(start 279.236678 -235.094526)
		(end 279.576784 -235.094526)
		(stroke
			(width 0.0635)
			(type default)
		)
		(layer "B.Cu")
	)
	(gr_line
		(start 279.236678 -231.494584)
		(end 279.576784 -231.494584)
		(stroke
			(width 0.0635)
			(type default)
		)
		(layer "B.Cu")
	)
	(gr_line
		(start 279.236678 -227.894388)
		(end 279.59304 -227.894388)
		(stroke
			(width 0.0635)
			(type default)
		)
		(layer "B.Cu")
	)
	(gr_line
		(start 279.236678 -224.294446)
		(end 279.574498 -224.294446)
		(stroke
			(width 0.0635)
			(type default)
		)
		(layer "B.Cu")
	)
	(gr_line
		(start 279.236678 -220.694504)
		(end 279.606756 -220.694504)
		(stroke
			(width 0.0635)
			(type default)
		)
		(layer "B.Cu")
	)
	(gr_line
		(start 279.236678 -217.094562)
		(end 279.576784 -217.094562)
		(stroke
			(width 0.0635)
			(type default)
		)
		(layer "B.Cu")
	)
	(gr_line
		(start 279.236678 -213.494366)
		(end 279.576784 -213.494366)
		(stroke
			(width 0.0635)
			(type default)
		)
		(layer "B.Cu")
	)
	(gr_line
		(start 279.236678 -209.894424)
		(end 279.576784 -209.894424)
		(stroke
			(width 0.0635)
			(type default)
		)
		(layer "B.Cu")
	)
	(gr_line
		(start 279.236678 -206.294482)
		(end 279.64257 -206.294482)
		(stroke
			(width 0.0635)
			(type default)
		)
		(layer "B.Cu")
	)
	(gr_line
		(start 279.236678 -202.69454)
		(end 279.64257 -202.69454)
		(stroke
			(width 0.0635)
			(type default)
		)
		(layer "B.Cu")
	)
	(gr_line
		(start 279.236678 -199.094344)
		(end 279.64257 -199.094344)
		(stroke
			(width 0.0635)
			(type default)
		)
		(layer "B.Cu")
	)
	(gr_line
		(start 279.236678 -195.494402)
		(end 279.576784 -195.494402)
		(stroke
			(width 0.0635)
			(type default)
		)
		(layer "B.Cu")
	)
	(gr_line
		(start 279.236678 -191.89446)
		(end 279.576784 -191.89446)
		(stroke
			(width 0.0635)
			(type default)
		)
		(layer "B.Cu")
	)
	(gr_line
		(start 279.236678 -188.294518)
		(end 279.576784 -188.294518)
		(stroke
			(width 0.0635)
			(type default)
		)
		(layer "B.Cu")
	)
	(gr_line
		(start 279.236678 -184.694576)
		(end 279.601676 -184.694576)
		(stroke
			(width 0.0635)
			(type default)
		)
		(layer "B.Cu")
	)
	(gr_line
		(start 279.236678 -181.09438)
		(end 279.601676 -181.09438)
		(stroke
			(width 0.0635)
			(type default)
		)
		(layer "B.Cu")
	)
	(gr_line
		(start 279.236678 -177.494438)
		(end 279.601676 -177.494438)
		(stroke
			(width 0.0635)
			(type default)
		)
		(layer "B.Cu")
	)
	(gr_line
		(start 279.236678 -144.694402)
		(end 279.598882 -144.694402)
		(stroke
			(width 0.08255)
			(type default)
		)
		(layer "B.Cu")
	)
	(gr_line
		(start 279.236678 -141.09446)
		(end 279.598882 -141.09446)
		(stroke
			(width 0.08255)
			(type default)
		)
		(layer "B.Cu")
	)
	(gr_line
		(start 279.236678 -137.494518)
		(end 279.598882 -137.494518)
		(stroke
			(width 0.08255)
			(type default)
		)
		(layer "B.Cu")
	)
	(gr_line
		(start 279.236678 -133.894322)
		(end 279.598882 -133.894322)
		(stroke
			(width 0.08255)
			(type default)
		)
		(layer "B.Cu")
	)
	(gr_arc
		(start 279.244806 -222.494348)
		(mid 279.130218 -222.541812)
		(end 279.082754 -222.6564)
		(stroke
			(width 0.0635)
			(type default)
		)
		(layer "B.Cu")
	)
	(gr_line
		(start 279.244806 -222.494348)
		(end 279.636728 -222.494348)
		(stroke
			(width 0.0635)
			(type default)
		)
		(layer "B.Cu")
	)
	(gr_line
		(start 279.27173 -182.894478)
		(end 279.636728 -182.894478)
		(stroke
			(width 0.0635)
			(type default)
		)
		(layer "B.Cu")
	)
	(gr_line
		(start 279.27173 -179.294536)
		(end 279.636728 -179.294536)
		(stroke
			(width 0.0635)
			(type default)
		)
		(layer "B.Cu")
	)
	(gr_line
		(start 279.27173 -175.694594)
		(end 279.636728 -175.694594)
		(stroke
			(width 0.0635)
			(type default)
		)
		(layer "B.Cu")
	)
	(gr_line
		(start 279.274524 -142.894304)
		(end 279.636728 -142.894304)
		(stroke
			(width 0.08255)
			(type default)
		)
		(layer "B.Cu")
	)
	(gr_line
		(start 279.274524 -139.294362)
		(end 279.636728 -139.294362)
		(stroke
			(width 0.08255)
			(type default)
		)
		(layer "B.Cu")
	)
	(gr_line
		(start 279.274524 -135.69442)
		(end 279.636728 -135.69442)
		(stroke
			(width 0.08255)
			(type default)
		)
		(layer "B.Cu")
	)
	(gr_line
		(start 279.274524 -132.094478)
		(end 279.636728 -132.094478)
		(stroke
			(width 0.08255)
			(type default)
		)
		(layer "B.Cu")
	)
	(gr_arc
		(start 279.288748 -218.894406)
		(mid 279.143088 -218.95474)
		(end 279.082754 -219.1004)
		(stroke
			(width 0.0635)
			(type default)
		)
		(layer "B.Cu")
	)
	(gr_line
		(start 279.288748 -218.894406)
		(end 279.636728 -218.894406)
		(stroke
			(width 0.0635)
			(type default)
		)
		(layer "B.Cu")
	)
	(gr_line
		(start 279.296622 -236.89437)
		(end 279.636728 -236.89437)
		(stroke
			(width 0.0635)
			(type default)
		)
		(layer "B.Cu")
	)
	(gr_line
		(start 279.296622 -233.294428)
		(end 279.636728 -233.294428)
		(stroke
			(width 0.0635)
			(type default)
		)
		(layer "B.Cu")
	)
	(gr_line
		(start 279.296622 -229.694486)
		(end 279.636728 -229.694486)
		(stroke
			(width 0.0635)
			(type default)
		)
		(layer "B.Cu")
	)
	(gr_line
		(start 279.296622 -215.294464)
		(end 279.636728 -215.294464)
		(stroke
			(width 0.0635)
			(type default)
		)
		(layer "B.Cu")
	)
	(gr_line
		(start 279.296622 -211.694522)
		(end 279.636728 -211.694522)
		(stroke
			(width 0.0635)
			(type default)
		)
		(layer "B.Cu")
	)
	(gr_line
		(start 279.296622 -208.09458)
		(end 279.636728 -208.09458)
		(stroke
			(width 0.0635)
			(type default)
		)
		(layer "B.Cu")
	)
	(gr_line
		(start 279.296622 -193.694558)
		(end 279.636728 -193.694558)
		(stroke
			(width 0.0635)
			(type default)
		)
		(layer "B.Cu")
	)
	(gr_line
		(start 279.296622 -190.094362)
		(end 279.636728 -190.094362)
		(stroke
			(width 0.0635)
			(type default)
		)
		(layer "B.Cu")
	)
	(gr_line
		(start 279.296622 -186.49442)
		(end 279.636728 -186.49442)
		(stroke
			(width 0.0635)
			(type default)
		)
		(layer "B.Cu")
	)
	(gr_arc
		(start 279.32761 -226.094544)
		(mid 279.154471 -226.166261)
		(end 279.082754 -226.3394)
		(stroke
			(width 0.0635)
			(type default)
		)
		(layer "B.Cu")
	)
	(gr_line
		(start 279.32761 -226.094544)
		(end 279.636728 -226.094544)
		(stroke
			(width 0.0635)
			(type default)
		)
		(layer "B.Cu")
	)
	(gr_arc
		(start 279.576784 -238.694468)
		(mid 279.728012 -238.631828)
		(end 279.790652 -238.4806)
		(stroke
			(width 0.0635)
			(type default)
		)
		(layer "B.Cu")
	)
	(gr_arc
		(start 279.576784 -235.094526)
		(mid 279.728012 -235.031886)
		(end 279.790652 -234.880658)
		(stroke
			(width 0.0635)
			(type default)
		)
		(layer "B.Cu")
	)
	(gr_arc
		(start 279.576784 -231.494584)
		(mid 279.728012 -231.431944)
		(end 279.790652 -231.280716)
		(stroke
			(width 0.0635)
			(type default)
		)
		(layer "B.Cu")
	)
	(gr_arc
		(start 279.576784 -217.094562)
		(mid 279.728012 -217.031922)
		(end 279.790652 -216.880694)
		(stroke
			(width 0.0635)
			(type default)
		)
		(layer "B.Cu")
	)
	(gr_arc
		(start 279.576784 -213.494366)
		(mid 279.728012 -213.431726)
		(end 279.790652 -213.280498)
		(stroke
			(width 0.0635)
			(type default)
		)
		(layer "B.Cu")
	)
	(gr_arc
		(start 279.576784 -209.894424)
		(mid 279.728012 -209.831784)
		(end 279.790652 -209.680556)
		(stroke
			(width 0.0635)
			(type default)
		)
		(layer "B.Cu")
	)
	(gr_arc
		(start 279.576784 -195.494402)
		(mid 279.728012 -195.431762)
		(end 279.790652 -195.280534)
		(stroke
			(width 0.0635)
			(type default)
		)
		(layer "B.Cu")
	)
	(gr_arc
		(start 279.576784 -191.89446)
		(mid 279.728012 -191.83182)
		(end 279.790652 -191.680592)
		(stroke
			(width 0.0635)
			(type default)
		)
		(layer "B.Cu")
	)
	(gr_arc
		(start 279.576784 -188.294518)
		(mid 279.728012 -188.231878)
		(end 279.790652 -188.08065)
		(stroke
			(width 0.0635)
			(type default)
		)
		(layer "B.Cu")
	)
	(gr_arc
		(start 279.598882 -144.694402)
		(mid 279.734484 -144.638234)
		(end 279.790652 -144.502632)
		(stroke
			(width 0.08255)
			(type default)
		)
		(layer "B.Cu")
	)
	(gr_arc
		(start 279.598882 -141.09446)
		(mid 279.734484 -141.038292)
		(end 279.790652 -140.90269)
		(stroke
			(width 0.08255)
			(type default)
		)
		(layer "B.Cu")
	)
	(gr_arc
		(start 279.598882 -137.494518)
		(mid 279.734484 -137.43835)
		(end 279.790652 -137.302748)
		(stroke
			(width 0.08255)
			(type default)
		)
		(layer "B.Cu")
	)
	(gr_arc
		(start 279.598882 -133.894322)
		(mid 279.734484 -133.838154)
		(end 279.790652 -133.702552)
		(stroke
			(width 0.08255)
			(type default)
		)
		(layer "B.Cu")
	)
	(gr_arc
		(start 279.601676 -184.694576)
		(mid 279.735302 -184.639226)
		(end 279.790652 -184.5056)
		(stroke
			(width 0.0635)
			(type default)
		)
		(layer "B.Cu")
	)
	(gr_arc
		(start 279.601676 -181.09438)
		(mid 279.735302 -181.03903)
		(end 279.790652 -180.905404)
		(stroke
			(width 0.0635)
			(type default)
		)
		(layer "B.Cu")
	)
	(gr_arc
		(start 279.601676 -177.494438)
		(mid 279.735302 -177.439088)
		(end 279.790652 -177.305462)
		(stroke
			(width 0.0635)
			(type default)
		)
		(layer "B.Cu")
	)
	(gr_arc
		(start 279.64257 -206.294482)
		(mid 279.74728 -206.25111)
		(end 279.790652 -206.1464)
		(stroke
			(width 0.0635)
			(type default)
		)
		(layer "B.Cu")
	)
	(gr_arc
		(start 279.64257 -202.69454)
		(mid 279.74728 -202.651168)
		(end 279.790652 -202.546458)
		(stroke
			(width 0.0635)
			(type default)
		)
		(layer "B.Cu")
	)
	(gr_arc
		(start 279.64257 -199.094344)
		(mid 279.74728 -199.050972)
		(end 279.790652 -198.946262)
		(stroke
			(width 0.0635)
			(type default)
		)
		(layer "B.Cu")
	)
	(gr_arc
		(start 279.790652 -228.092)
		(mid 279.732775 -227.952253)
		(end 279.59304 -227.894388)
		(stroke
			(width 0.0635)
			(type default)
		)
		(layer "B.Cu")
	)
	(gr_arc
		(start 279.790652 -224.5106)
		(mid 279.727342 -224.357757)
		(end 279.574498 -224.294446)
		(stroke
			(width 0.0635)
			(type default)
		)
		(layer "B.Cu")
	)
	(gr_arc
		(start 279.790652 -220.8784)
		(mid 279.736787 -220.748381)
		(end 279.606756 -220.694504)
		(stroke
			(width 0.0635)
			(type default)
		)
		(layer "B.Cu")
	)
	(gr_arc
		(start 280.082752 -238.4806)
		(mid 280.145394 -238.63182)
		(end 280.29662 -238.694468)
		(stroke
			(width 0.0635)
			(type default)
		)
		(layer "B.Cu")
	)
	(gr_arc
		(start 280.082752 -234.880658)
		(mid 280.145379 -235.031906)
		(end 280.29662 -235.094526)
		(stroke
			(width 0.0635)
			(type default)
		)
		(layer "B.Cu")
	)
	(gr_arc
		(start 280.082752 -231.280716)
		(mid 280.145399 -231.431926)
		(end 280.29662 -231.494584)
		(stroke
			(width 0.0635)
			(type default)
		)
		(layer "B.Cu")
	)
	(gr_arc
		(start 280.082752 -216.880694)
		(mid 280.145392 -217.031918)
		(end 280.29662 -217.094562)
		(stroke
			(width 0.0635)
			(type default)
		)
		(layer "B.Cu")
	)
	(gr_arc
		(start 280.082752 -213.280498)
		(mid 280.145393 -213.43172)
		(end 280.29662 -213.494366)
		(stroke
			(width 0.0635)
			(type default)
		)
		(layer "B.Cu")
	)
	(gr_arc
		(start 280.082752 -209.680556)
		(mid 280.145378 -209.831805)
		(end 280.29662 -209.894424)
		(stroke
			(width 0.0635)
			(type default)
		)
		(layer "B.Cu")
	)
	(gr_arc
		(start 280.082752 -206.1464)
		(mid 280.126126 -206.251098)
		(end 280.230834 -206.294482)
		(stroke
			(width 0.0635)
			(type default)
		)
		(layer "B.Cu")
	)
	(gr_arc
		(start 280.082752 -202.546458)
		(mid 280.126111 -202.651183)
		(end 280.230834 -202.69454)
		(stroke
			(width 0.0635)
			(type default)
		)
		(layer "B.Cu")
	)
	(gr_arc
		(start 280.082752 -198.946262)
		(mid 280.126113 -199.050984)
		(end 280.230834 -199.094344)
		(stroke
			(width 0.0635)
			(type default)
		)
		(layer "B.Cu")
	)
	(gr_arc
		(start 280.082752 -195.280534)
		(mid 280.145406 -195.431732)
		(end 280.29662 -195.494402)
		(stroke
			(width 0.0635)
			(type default)
		)
		(layer "B.Cu")
	)
	(gr_arc
		(start 280.082752 -191.680592)
		(mid 280.145391 -191.831818)
		(end 280.29662 -191.89446)
		(stroke
			(width 0.0635)
			(type default)
		)
		(layer "B.Cu")
	)
	(gr_arc
		(start 280.082752 -188.08065)
		(mid 280.145376 -188.231903)
		(end 280.29662 -188.294518)
		(stroke
			(width 0.0635)
			(type default)
		)
		(layer "B.Cu")
	)
	(gr_arc
		(start 280.082752 -184.5056)
		(mid 280.138103 -184.639216)
		(end 280.271728 -184.694576)
		(stroke
			(width 0.0635)
			(type default)
		)
		(layer "B.Cu")
	)
	(gr_arc
		(start 280.082752 -180.905404)
		(mid 280.138105 -181.039018)
		(end 280.271728 -181.09438)
		(stroke
			(width 0.0635)
			(type default)
		)
		(layer "B.Cu")
	)
	(gr_arc
		(start 280.082752 -177.305462)
		(mid 280.13809 -177.439103)
		(end 280.271728 -177.494438)
		(stroke
			(width 0.0635)
			(type default)
		)
		(layer "B.Cu")
	)
	(gr_arc
		(start 280.082752 -144.502632)
		(mid 280.138933 -144.638205)
		(end 280.274522 -144.694402)
		(stroke
			(width 0.08255)
			(type default)
		)
		(layer "B.Cu")
	)
	(gr_arc
		(start 280.082752 -140.90269)
		(mid 280.138918 -141.038291)
		(end 280.274522 -141.09446)
		(stroke
			(width 0.08255)
			(type default)
		)
		(layer "B.Cu")
	)
	(gr_arc
		(start 280.082752 -137.302748)
		(mid 280.138938 -137.438311)
		(end 280.274522 -137.494518)
		(stroke
			(width 0.08255)
			(type default)
		)
		(layer "B.Cu")
	)
	(gr_arc
		(start 280.082752 -133.702552)
		(mid 280.138904 -133.838177)
		(end 280.274522 -133.894322)
		(stroke
			(width 0.08255)
			(type default)
		)
		(layer "B.Cu")
	)
	(gr_line
		(start 280.230834 -206.294482)
		(end 280.636726 -206.294482)
		(stroke
			(width 0.0635)
			(type default)
		)
		(layer "B.Cu")
	)
	(gr_line
		(start 280.230834 -202.69454)
		(end 280.636726 -202.69454)
		(stroke
			(width 0.0635)
			(type default)
		)
		(layer "B.Cu")
	)
	(gr_line
		(start 280.230834 -199.094344)
		(end 280.636726 -199.094344)
		(stroke
			(width 0.0635)
			(type default)
		)
		(layer "B.Cu")
	)
	(gr_arc
		(start 280.266648 -220.694504)
		(mid 280.136614 -220.748366)
		(end 280.082752 -220.8784)
		(stroke
			(width 0.0635)
			(type default)
		)
		(layer "B.Cu")
	)
	(gr_line
		(start 280.266648 -220.694504)
		(end 280.636726 -220.694504)
		(stroke
			(width 0.0635)
			(type default)
		)
		(layer "B.Cu")
	)
	(gr_line
		(start 280.271728 -184.694576)
		(end 280.636726 -184.694576)
		(stroke
			(width 0.0635)
			(type default)
		)
		(layer "B.Cu")
	)
	(gr_line
		(start 280.271728 -181.09438)
		(end 280.636726 -181.09438)
		(stroke
			(width 0.0635)
			(type default)
		)
		(layer "B.Cu")
	)
	(gr_line
		(start 280.271728 -177.494438)
		(end 280.636726 -177.494438)
		(stroke
			(width 0.0635)
			(type default)
		)
		(layer "B.Cu")
	)
	(gr_line
		(start 280.274522 -144.694402)
		(end 280.636726 -144.694402)
		(stroke
			(width 0.08255)
			(type default)
		)
		(layer "B.Cu")
	)
	(gr_line
		(start 280.274522 -141.09446)
		(end 280.636726 -141.09446)
		(stroke
			(width 0.08255)
			(type default)
		)
		(layer "B.Cu")
	)
	(gr_line
		(start 280.274522 -137.494518)
		(end 280.636726 -137.494518)
		(stroke
			(width 0.08255)
			(type default)
		)
		(layer "B.Cu")
	)
	(gr_line
		(start 280.274522 -133.894322)
		(end 280.636726 -133.894322)
		(stroke
			(width 0.08255)
			(type default)
		)
		(layer "B.Cu")
	)
	(gr_arc
		(start 280.280364 -227.894388)
		(mid 280.140631 -227.952267)
		(end 280.082752 -228.092)
		(stroke
			(width 0.0635)
			(type default)
		)
		(layer "B.Cu")
	)
	(gr_line
		(start 280.280364 -227.894388)
		(end 280.636726 -227.894388)
		(stroke
			(width 0.0635)
			(type default)
		)
		(layer "B.Cu")
	)
	(gr_line
		(start 280.29662 -238.694468)
		(end 280.636726 -238.694468)
		(stroke
			(width 0.0635)
			(type default)
		)
		(layer "B.Cu")
	)
	(gr_line
		(start 280.29662 -235.094526)
		(end 280.636726 -235.094526)
		(stroke
			(width 0.0635)
			(type default)
		)
		(layer "B.Cu")
	)
	(gr_line
		(start 280.29662 -231.494584)
		(end 280.636726 -231.494584)
		(stroke
			(width 0.0635)
			(type default)
		)
		(layer "B.Cu")
	)
	(gr_line
		(start 280.29662 -217.094562)
		(end 280.636726 -217.094562)
		(stroke
			(width 0.0635)
			(type default)
		)
		(layer "B.Cu")
	)
	(gr_line
		(start 280.29662 -213.494366)
		(end 280.636726 -213.494366)
		(stroke
			(width 0.0635)
			(type default)
		)
		(layer "B.Cu")
	)
	(gr_line
		(start 280.29662 -209.894424)
		(end 280.636726 -209.894424)
		(stroke
			(width 0.0635)
			(type default)
		)
		(layer "B.Cu")
	)
	(gr_line
		(start 280.29662 -195.494402)
		(end 280.636726 -195.494402)
		(stroke
			(width 0.0635)
			(type default)
		)
		(layer "B.Cu")
	)
	(gr_line
		(start 280.29662 -191.89446)
		(end 280.636726 -191.89446)
		(stroke
			(width 0.0635)
			(type default)
		)
		(layer "B.Cu")
	)
	(gr_line
		(start 280.29662 -188.294518)
		(end 280.636726 -188.294518)
		(stroke
			(width 0.0635)
			(type default)
		)
		(layer "B.Cu")
	)
	(gr_arc
		(start 280.298906 -224.294446)
		(mid 280.146062 -224.357756)
		(end 280.082752 -224.5106)
		(stroke
			(width 0.0635)
			(type default)
		)
		(layer "B.Cu")
	)
	(gr_line
		(start 280.298906 -224.294446)
		(end 280.636726 -224.294446)
		(stroke
			(width 0.0635)
			(type default)
		)
		(layer "B.Cu")
	)
	(gr_line
		(start 282.83662 -144.694402)
		(end 283.198824 -144.694402)
		(stroke
			(width 0.08255)
			(type default)
		)
		(layer "B.Cu")
	)
	(gr_arc
		(start 283.390594 -144.886172)
		(mid 283.334417 -144.75058)
		(end 283.198824 -144.694402)
		(stroke
			(width 0.08255)
			(type default)
		)
		(layer "B.Cu")
	)
	(gr_arc
		(start 283.874464 -144.694402)
		(mid 283.738862 -144.75057)
		(end 283.682694 -144.886172)
		(stroke
			(width 0.08255)
			(type default)
		)
		(layer "B.Cu")
	)
	(gr_line
		(start 283.874464 -144.694402)
		(end 284.236668 -144.694402)
		(stroke
			(width 0.08255)
			(type default)
		)
		(layer "B.Cu")
	)
	(gr_line
		(start 290.246054 -228.635814)
		(end 290.281106 -228.656134)
		(stroke
			(width 0.0635)
			(type default)
		)
		(layer "B.Cu")
	)
	(gr_line
		(start 290.320476 -174.45863)
		(end 290.336732 -174.455074)
		(stroke
			(width 0.0635)
			(type default)
		)
		(layer "B.Cu")
	)
	(gr_line
		(start 290.336732 -174.455074)
		(end 290.350194 -174.446184)
		(stroke
			(width 0.0635)
			(type default)
		)
		(layer "B.Cu")
	)
	(gr_line
		(start 290.956492 -176.207928)
		(end 290.971986 -176.204626)
		(stroke
			(width 0.0635)
			(type default)
		)
		(layer "B.Cu")
	)
	(gr_line
		(start 290.971986 -176.204626)
		(end 290.985448 -176.19599)
		(stroke
			(width 0.0635)
			(type default)
		)
		(layer "B.Cu")
	)
	(gr_line
		(start 291.47897 -173.712886)
		(end 291.499544 -173.699678)
		(stroke
			(width 0.0635)
			(type default)
		)
		(layer "B.Cu")
	)
	(gr_line
		(start 291.499544 -173.699678)
		(end 291.512752 -173.679104)
		(stroke
			(width 0.0635)
			(type default)
		)
		(layer "B.Cu")
	)
	(gr_line
		(start 291.886386 -177.862738)
		(end 291.902896 -177.859182)
		(stroke
			(width 0.0635)
			(type default)
		)
		(layer "B.Cu")
	)
	(gr_line
		(start 291.902896 -177.859182)
		(end 291.91712 -177.849784)
		(stroke
			(width 0.0635)
			(type default)
		)
		(layer "B.Cu")
	)
	(gr_line
		(start 292.228524 -181.474618)
		(end 292.24986 -181.470808)
		(stroke
			(width 0.0635)
			(type default)
		)
		(layer "B.Cu")
	)
	(gr_line
		(start 292.24986 -181.470808)
		(end 292.26764 -181.459124)
		(stroke
			(width 0.0635)
			(type default)
		)
		(layer "B.Cu")
	)
	(gr_line
		(start 292.353746 -179.548282)
		(end 292.370002 -179.544726)
		(stroke
			(width 0.0635)
			(type default)
		)
		(layer "B.Cu")
	)
	(gr_line
		(start 292.370002 -179.544726)
		(end 292.383464 -179.535836)
		(stroke
			(width 0.0635)
			(type default)
		)
		(layer "B.Cu")
	)
	(gr_line
		(start 293.228014 -174.74184)
		(end 293.247826 -174.72914)
		(stroke
			(width 0.0635)
			(type default)
		)
		(layer "B.Cu")
	)
	(gr_line
		(start 293.247826 -174.72914)
		(end 293.260526 -174.709582)
		(stroke
			(width 0.0635)
			(type default)
		)
		(layer "B.Cu")
	)
	(gr_line
		(start 294.602662 -176.10582)
		(end 294.623236 -176.092612)
		(stroke
			(width 0.0635)
			(type default)
		)
		(layer "B.Cu")
	)
	(gr_line
		(start 294.623236 -176.092612)
		(end 294.636444 -176.072038)
		(stroke
			(width 0.0635)
			(type default)
		)
		(layer "B.Cu")
	)
	(gr_line
		(start 294.724582 -182.62092)
		(end 294.740838 -182.617364)
		(stroke
			(width 0.0635)
			(type default)
		)
		(layer "B.Cu")
	)
	(gr_line
		(start 294.740838 -182.617364)
		(end 294.7543 -182.608474)
		(stroke
			(width 0.0635)
			(type default)
		)
		(layer "B.Cu")
	)
	(gr_line
		(start 297.1419 -176.445926)
		(end 297.162474 -176.432718)
		(stroke
			(width 0.0635)
			(type default)
		)
		(layer "B.Cu")
	)
	(gr_line
		(start 297.162474 -176.432718)
		(end 297.175682 -176.412144)
		(stroke
			(width 0.0635)
			(type default)
		)
		(layer "B.Cu")
	)
	(gr_line
		(start 300.400466 -176.176686)
		(end 300.42104 -176.163478)
		(stroke
			(width 0.0635)
			(type default)
		)
		(layer "B.Cu")
	)
	(gr_line
		(start 300.42104 -176.163478)
		(end 300.434248 -176.142904)
		(stroke
			(width 0.0635)
			(type default)
		)
		(layer "B.Cu")
	)
	(gr_line
		(start 300.501558 -159.837628)
		(end 300.50994 -159.824674)
		(stroke
			(width 0.0635)
			(type default)
		)
		(layer "B.Cu")
	)
	(gr_line
		(start 300.50994 -159.824674)
		(end 300.513242 -159.80918)
		(stroke
			(width 0.0635)
			(type default)
		)
		(layer "B.Cu")
	)
	(gr_line
		(start 302.050196 -177.870358)
		(end 302.07077 -177.85715)
		(stroke
			(width 0.0635)
			(type default)
		)
		(layer "B.Cu")
	)
	(gr_line
		(start 302.07077 -177.85715)
		(end 302.083978 -177.836576)
		(stroke
			(width 0.0635)
			(type default)
		)
		(layer "B.Cu")
	)
	(gr_line
		(start 302.406812 -160.625282)
		(end 302.415702 -160.61182)
		(stroke
			(width 0.0635)
			(type default)
		)
		(layer "B.Cu")
	)
	(gr_line
		(start 302.415702 -160.61182)
		(end 302.419258 -160.595564)
		(stroke
			(width 0.0635)
			(type default)
		)
		(layer "B.Cu")
	)
	(gr_line
		(start 304.306732 -161.181288)
		(end 304.315622 -161.167826)
		(stroke
			(width 0.0635)
			(type default)
		)
		(layer "B.Cu")
	)
	(gr_line
		(start 304.315622 -161.167826)
		(end 304.319178 -161.15157)
		(stroke
			(width 0.0635)
			(type default)
		)
		(layer "B.Cu")
	)
	(gr_line
		(start 306.129944 -131.956302)
		(end 306.257452 -131.355846)
		(stroke
			(width 0.0635)
			(type default)
		)
		(layer "B.Cu")
	)
	(gr_line
		(start 306.300378 -162.361626)
		(end 306.309268 -162.348164)
		(stroke
			(width 0.0635)
			(type default)
		)
		(layer "B.Cu")
	)
	(gr_line
		(start 306.309268 -162.348164)
		(end 306.312824 -162.331908)
		(stroke
			(width 0.0635)
			(type default)
		)
		(layer "B.Cu")
	)
	(gr_line
		(start 306.350924 -130.915156)
		(end 306.479448 -130.309366)
		(stroke
			(width 0.0635)
			(type default)
		)
		(layer "B.Cu")
	)
	(gr_line
		(start 306.411122 -132.050536)
		(end 306.58943 -131.934966)
		(stroke
			(width 0.0635)
			(type default)
		)
		(layer "B.Cu")
	)
	(gr_line
		(start 306.416202 -238.382048)
		(end 306.943506 -238.688626)
		(stroke
			(width 0.0635)
			(type default)
		)
		(layer "B.Cu")
	)
	(gr_line
		(start 306.534566 -238.110014)
		(end 306.739544 -238.055658)
		(stroke
			(width 0.0635)
			(type default)
		)
		(layer "B.Cu")
	)
	(gr_line
		(start 306.5526 -131.38404)
		(end 306.668424 -131.562094)
		(stroke
			(width 0.0635)
			(type default)
		)
		(layer "B.Cu")
	)
	(gr_line
		(start 306.57292 -129.870454)
		(end 306.700682 -129.268982)
		(stroke
			(width 0.0635)
			(type default)
		)
		(layer "B.Cu")
	)
	(gr_line
		(start 306.58943 -131.934966)
		(end 306.668424 -131.562094)
		(stroke
			(width 0.0635)
			(type default)
		)
		(layer "B.Cu")
	)
	(gr_line
		(start 306.63261 -131.007358)
		(end 306.810918 -130.89128)
		(stroke
			(width 0.0635)
			(type default)
		)
		(layer "B.Cu")
	)
	(gr_line
		(start 306.739544 -238.055658)
		(end 307.068728 -238.247428)
		(stroke
			(width 0.0635)
			(type default)
		)
		(layer "B.Cu")
	)
	(gr_line
		(start 306.774342 -130.340354)
		(end 306.890166 -130.518662)
		(stroke
			(width 0.0635)
			(type default)
		)
		(layer "B.Cu")
	)
	(gr_line
		(start 306.794154 -128.828038)
		(end 306.922678 -128.222248)
		(stroke
			(width 0.0635)
			(type default)
		)
		(layer "B.Cu")
	)
	(gr_line
		(start 306.795932 -195.069714)
		(end 306.812188 -195.066158)
		(stroke
			(width 0.0635)
			(type default)
		)
		(layer "B.Cu")
	)
	(gr_line
		(start 306.810918 -130.89128)
		(end 306.890166 -130.518662)
		(stroke
			(width 0.0635)
			(type default)
		)
		(layer "B.Cu")
	)
	(gr_line
		(start 306.812188 -195.066158)
		(end 306.82565 -195.057268)
		(stroke
			(width 0.0635)
			(type default)
		)
		(layer "B.Cu")
	)
	(gr_line
		(start 306.854352 -129.963418)
		(end 307.03266 -129.847848)
		(stroke
			(width 0.0635)
			(type default)
		)
		(layer "B.Cu")
	)
	(gr_line
		(start 306.915312 -192.958974)
		(end 306.931568 -192.955418)
		(stroke
			(width 0.0635)
			(type default)
		)
		(layer "B.Cu")
	)
	(gr_line
		(start 306.931568 -192.955418)
		(end 306.94503 -192.946528)
		(stroke
			(width 0.0635)
			(type default)
		)
		(layer "B.Cu")
	)
	(gr_line
		(start 306.9717 -238.704882)
		(end 307.241956 -238.862362)
		(stroke
			(width 0.0635)
			(type default)
		)
		(layer "B.Cu")
	)
	(gr_line
		(start 306.996084 -129.296922)
		(end 307.111654 -129.47523)
		(stroke
			(width 0.0635)
			(type default)
		)
		(layer "B.Cu")
	)
	(gr_line
		(start 307.03266 -129.847848)
		(end 307.111654 -129.47523)
		(stroke
			(width 0.0635)
			(type default)
		)
		(layer "B.Cu")
	)
	(gr_line
		(start 307.068728 -238.247428)
		(end 307.12283 -238.452152)
		(stroke
			(width 0.0635)
			(type default)
		)
		(layer "B.Cu")
	)
	(gr_line
		(start 307.076094 -128.92024)
		(end 307.254148 -128.804416)
		(stroke
			(width 0.0635)
			(type default)
		)
		(layer "B.Cu")
	)
	(gr_line
		(start 307.123846 -238.455708)
		(end 307.220874 -238.512096)
		(stroke
			(width 0.0635)
			(type default)
		)
		(layer "B.Cu")
	)
	(gr_line
		(start 307.217572 -128.25349)
		(end 307.333396 -128.431544)
		(stroke
			(width 0.0635)
			(type default)
		)
		(layer "B.Cu")
	)
	(gr_line
		(start 307.254148 -128.804416)
		(end 307.333396 -128.431544)
		(stroke
			(width 0.0635)
			(type default)
		)
		(layer "B.Cu")
	)
	(gr_line
		(start 307.338222 -238.918496)
		(end 307.867304 -239.226344)
		(stroke
			(width 0.0635)
			(type default)
		)
		(layer "B.Cu")
	)
	(gr_line
		(start 307.456586 -238.646462)
		(end 307.661564 -238.59236)
		(stroke
			(width 0.0635)
			(type default)
		)
		(layer "B.Cu")
	)
	(gr_line
		(start 307.661564 -238.59236)
		(end 307.991002 -238.783876)
		(stroke
			(width 0.0635)
			(type default)
		)
		(layer "B.Cu")
	)
	(gr_line
		(start 307.739034 -164.894514)
		(end 307.747924 -164.881052)
		(stroke
			(width 0.0635)
			(type default)
		)
		(layer "B.Cu")
	)
	(gr_line
		(start 307.747924 -164.881052)
		(end 307.75148 -164.864796)
		(stroke
			(width 0.0635)
			(type default)
		)
		(layer "B.Cu")
	)
	(gr_line
		(start 307.991002 -238.783876)
		(end 308.045358 -238.988854)
		(stroke
			(width 0.0635)
			(type default)
		)
		(layer "B.Cu")
	)
	(gr_line
		(start 308.07914 -239.349534)
		(end 308.234842 -239.440212)
		(stroke
			(width 0.0635)
			(type default)
		)
		(layer "B.Cu")
	)
	(gr_line
		(start 308.17693 -239.068356)
		(end 308.375304 -239.183926)
		(stroke
			(width 0.0635)
			(type default)
		)
		(layer "B.Cu")
	)
	(gr_line
		(start 308.262528 -239.45596)
		(end 308.787546 -239.761522)
		(stroke
			(width 0.0635)
			(type default)
		)
		(layer "B.Cu")
	)
	(gr_line
		(start 308.375304 -239.183926)
		(end 308.375558 -239.183926)
		(stroke
			(width 0.0635)
			(type default)
		)
		(layer "B.Cu")
	)
	(gr_line
		(start 308.37886 -239.18291)
		(end 308.583838 -239.128808)
		(stroke
			(width 0.0635)
			(type default)
		)
		(layer "B.Cu")
	)
	(gr_line
		(start 308.583838 -239.128808)
		(end 308.913022 -239.320324)
		(stroke
			(width 0.0635)
			(type default)
		)
		(layer "B.Cu")
	)
	(gr_line
		(start 308.913022 -239.320324)
		(end 308.967124 -239.525302)
		(stroke
			(width 0.0635)
			(type default)
		)
		(layer "B.Cu")
	)
	(gr_line
		(start 309.093362 -239.601502)
		(end 309.297324 -239.720374)
		(stroke
			(width 0.0635)
			(type default)
		)
		(layer "B.Cu")
	)
	(gr_line
		(start 309.18531 -239.992916)
		(end 309.70982 -240.298224)
		(stroke
			(width 0.0635)
			(type default)
		)
		(layer "B.Cu")
	)
	(gr_line
		(start 309.297324 -239.720374)
		(end 309.297578 -239.720374)
		(stroke
			(width 0.0635)
			(type default)
		)
		(layer "B.Cu")
	)
	(gr_line
		(start 309.30088 -239.719358)
		(end 309.505858 -239.665256)
		(stroke
			(width 0.0635)
			(type default)
		)
		(layer "B.Cu")
	)
	(gr_line
		(start 309.468266 -191.30772)
		(end 309.48884 -191.294512)
		(stroke
			(width 0.0635)
			(type default)
		)
		(layer "B.Cu")
	)
	(gr_line
		(start 309.48884 -191.294512)
		(end 309.502048 -191.273938)
		(stroke
			(width 0.0635)
			(type default)
		)
		(layer "B.Cu")
	)
	(gr_line
		(start 309.505858 -239.665256)
		(end 309.835042 -239.856772)
		(stroke
			(width 0.0635)
			(type default)
		)
		(layer "B.Cu")
	)
	(gr_line
		(start 309.68823 -166.126922)
		(end 309.69712 -166.11346)
		(stroke
			(width 0.0635)
			(type default)
		)
		(layer "B.Cu")
	)
	(gr_line
		(start 309.69712 -166.11346)
		(end 309.700676 -166.097204)
		(stroke
			(width 0.0635)
			(type default)
		)
		(layer "B.Cu")
	)
	(gr_line
		(start 309.835042 -239.856772)
		(end 309.889144 -240.06175)
		(stroke
			(width 0.0635)
			(type default)
		)
		(layer "B.Cu")
	)
	(gr_line
		(start 310.327548 -121.983246)
		(end 310.331104 -121.96699)
		(stroke
			(width 0.0635)
			(type default)
		)
		(layer "B.Cu")
	)
	(gr_line
		(start 310.331104 -121.96699)
		(end 310.339994 -121.953528)
		(stroke
			(width 0.0635)
			(type default)
		)
		(layer "B.Cu")
	)
	(gr_line
		(start 311.25033 -192.183766)
		(end 311.270904 -192.170558)
		(stroke
			(width 0.0635)
			(type default)
		)
		(layer "B.Cu")
	)
	(gr_line
		(start 311.270904 -192.170558)
		(end 311.284112 -192.149984)
		(stroke
			(width 0.0635)
			(type default)
		)
		(layer "B.Cu")
	)
	(gr_line
		(start 311.711086 -232.601008)
		(end 312.305192 -232.75671)
		(stroke
			(width 0.0635)
			(type default)
		)
		(layer "B.Cu")
	)
	(gr_line
		(start 311.75325 -232.307384)
		(end 311.936384 -232.199942)
		(stroke
			(width 0.0635)
			(type default)
		)
		(layer "B.Cu")
	)
	(gr_line
		(start 311.835038 -124.386086)
		(end 311.838594 -124.36983)
		(stroke
			(width 0.0635)
			(type default)
		)
		(layer "B.Cu")
	)
	(gr_line
		(start 311.838594 -124.36983)
		(end 311.847484 -124.356368)
		(stroke
			(width 0.0635)
			(type default)
		)
		(layer "B.Cu")
	)
	(gr_line
		(start 311.936384 -232.199942)
		(end 312.304938 -232.296462)
		(stroke
			(width 0.0635)
			(type default)
		)
		(layer "B.Cu")
	)
	(gr_line
		(start 312.304938 -232.296462)
		(end 312.412126 -232.47985)
		(stroke
			(width 0.0635)
			(type default)
		)
		(layer "B.Cu")
	)
	(gr_line
		(start 312.743342 -232.871264)
		(end 313.336686 -233.026712)
		(stroke
			(width 0.0635)
			(type default)
		)
		(layer "B.Cu")
	)
	(gr_line
		(start 312.785252 -232.57764)
		(end 312.968386 -232.470198)
		(stroke
			(width 0.0635)
			(type default)
		)
		(layer "B.Cu")
	)
	(gr_line
		(start 312.968386 -232.470198)
		(end 313.33694 -232.566972)
		(stroke
			(width 0.0635)
			(type default)
		)
		(layer "B.Cu")
	)
	(gr_line
		(start 313.33694 -232.566972)
		(end 313.444128 -232.750106)
		(stroke
			(width 0.0635)
			(type default)
		)
		(layer "B.Cu")
	)
	(gr_line
		(start 313.775598 -233.14152)
		(end 314.36818 -233.296714)
		(stroke
			(width 0.0635)
			(type default)
		)
		(layer "B.Cu")
	)
	(gr_line
		(start 313.804554 -125.678438)
		(end 313.80811 -125.662182)
		(stroke
			(width 0.0635)
			(type default)
		)
		(layer "B.Cu")
	)
	(gr_line
		(start 313.80811 -125.662182)
		(end 313.817 -125.64872)
		(stroke
			(width 0.0635)
			(type default)
		)
		(layer "B.Cu")
	)
	(gr_line
		(start 313.814714 -184.631584)
		(end 313.823604 -184.618122)
		(stroke
			(width 0.0635)
			(type default)
		)
		(layer "B.Cu")
	)
	(gr_line
		(start 313.817 -232.847896)
		(end 314.000388 -232.740708)
		(stroke
			(width 0.0635)
			(type default)
		)
		(layer "B.Cu")
	)
	(gr_line
		(start 313.823604 -184.618122)
		(end 313.82716 -184.601866)
		(stroke
			(width 0.0635)
			(type default)
		)
		(layer "B.Cu")
	)
	(gr_line
		(start 314.000388 -232.740708)
		(end 314.368942 -232.837228)
		(stroke
			(width 0.0635)
			(type default)
		)
		(layer "B.Cu")
	)
	(gr_line
		(start 314.368942 -232.837228)
		(end 314.47613 -233.020362)
		(stroke
			(width 0.0635)
			(type default)
		)
		(layer "B.Cu")
	)
	(gr_line
		(start 314.8076 -233.411776)
		(end 315.400182 -233.56697)
		(stroke
			(width 0.0635)
			(type default)
		)
		(layer "B.Cu")
	)
	(gr_line
		(start 314.849002 -233.118152)
		(end 315.03239 -233.010964)
		(stroke
			(width 0.0635)
			(type default)
		)
		(layer "B.Cu")
	)
	(gr_line
		(start 315.03239 -233.010964)
		(end 315.400944 -233.107484)
		(stroke
			(width 0.0635)
			(type default)
		)
		(layer "B.Cu")
	)
	(gr_line
		(start 315.400944 -233.107484)
		(end 315.508132 -233.290618)
		(stroke
			(width 0.0635)
			(type default)
		)
		(layer "B.Cu")
	)
	(gr_line
		(start 315.569854 -126.677674)
		(end 315.57341 -126.661418)
		(stroke
			(width 0.0635)
			(type default)
		)
		(layer "B.Cu")
	)
	(gr_line
		(start 315.57341 -126.661418)
		(end 315.5823 -126.647956)
		(stroke
			(width 0.0635)
			(type default)
		)
		(layer "B.Cu")
	)
	(gr_line
		(start 317.495682 -128.026668)
		(end 317.499238 -128.010412)
		(stroke
			(width 0.0635)
			(type default)
		)
		(layer "B.Cu")
	)
	(gr_line
		(start 317.499238 -128.010412)
		(end 317.508128 -127.99695)
		(stroke
			(width 0.0635)
			(type default)
		)
		(layer "B.Cu")
	)
	(gr_line
		(start 317.808102 -245.009924)
		(end 317.843154 -245.030244)
		(stroke
			(width 0.0635)
			(type default)
		)
		(layer "B.Cu")
	)
	(gr_line
		(start 319.2145 -128.627124)
		(end 319.482724 -128.627124)
		(stroke
			(width 0.0635)
			(type default)
		)
		(layer "B.Cu")
	)
	(gr_line
		(start 319.2145 -13.6271)
		(end 319.4685 -13.6271)
		(stroke
			(width 0.0635)
			(type default)
		)
		(layer "B.Cu")
	)
	(gr_arc
		(start 319.22466 -244.738144)
		(mid 319.350384 -244.686068)
		(end 319.40246 -244.560344)
		(stroke
			(width 0.0635)
			(type default)
		)
		(layer "B.Cu")
	)
	(gr_arc
		(start 319.40246 -245.208044)
		(mid 319.350397 -245.082306)
		(end 319.22466 -245.030244)
		(stroke
			(width 0.0635)
			(type default)
		)
		(layer "B.Cu")
	)
	(gr_line
		(start 319.40246 -245.208044)
		(end 319.40246 -245.455694)
		(stroke
			(width 0.0635)
			(type default)
		)
		(layer "B.Cu")
	)
	(gr_line
		(start 319.40246 -244.312694)
		(end 319.40246 -244.560344)
		(stroke
			(width 0.0635)
			(type default)
		)
		(layer "B.Cu")
	)
	(gr_arc
		(start 319.63995 -128.78435)
		(mid 319.5939 -128.673174)
		(end 319.482724 -128.627124)
		(stroke
			(width 0.0635)
			(type default)
		)
		(layer "B.Cu")
	)
	(gr_arc
		(start 319.63995 -13.79855)
		(mid 319.589733 -13.677317)
		(end 319.4685 -13.6271)
		(stroke
			(width 0.0635)
			(type default)
		)
		(layer "B.Cu")
	)
	(gr_arc
		(start 320.089276 -128.627124)
		(mid 319.978134 -128.673186)
		(end 319.93205 -128.78435)
		(stroke
			(width 0.0635)
			(type default)
		)
		(layer "B.Cu")
	)
	(gr_line
		(start 320.089276 -128.627124)
		(end 320.3575 -128.627124)
		(stroke
			(width 0.0635)
			(type default)
		)
		(layer "B.Cu")
	)
	(gr_arc
		(start 320.1035 -13.6271)
		(mid 319.982249 -13.677314)
		(end 319.93205 -13.79855)
		(stroke
			(width 0.0635)
			(type default)
		)
		(layer "B.Cu")
	)
	(gr_line
		(start 320.1035 -13.6271)
		(end 320.3575 -13.6271)
		(stroke
			(width 0.0635)
			(type default)
		)
		(layer "B.Cu")
	)
	(gr_line
		(start 320.3575 -152.487884)
		(end 320.484754 -151.889206)
		(stroke
			(width 0.0635)
			(type default)
		)
		(layer "B.Cu")
	)
	(gr_line
		(start 320.579242 -151.445214)
		(end 320.706496 -150.847298)
		(stroke
			(width 0.0635)
			(type default)
		)
		(layer "B.Cu")
	)
	(gr_line
		(start 320.638424 -152.583388)
		(end 320.816478 -152.467818)
		(stroke
			(width 0.0635)
			(type default)
		)
		(layer "B.Cu")
	)
	(gr_line
		(start 320.780156 -151.917146)
		(end 320.895726 -152.0952)
		(stroke
			(width 0.0635)
			(type default)
		)
		(layer "B.Cu")
	)
	(gr_line
		(start 320.801492 -150.400258)
		(end 320.928492 -149.803104)
		(stroke
			(width 0.0635)
			(type default)
		)
		(layer "B.Cu")
	)
	(gr_line
		(start 320.816478 -152.467818)
		(end 320.895726 -152.0952)
		(stroke
			(width 0.0635)
			(type default)
		)
		(layer "B.Cu")
	)
	(gr_line
		(start 320.86042 -151.539956)
		(end 321.03822 -151.424386)
		(stroke
			(width 0.0635)
			(type default)
		)
		(layer "B.Cu")
	)
	(gr_line
		(start 321.001898 -150.873714)
		(end 321.117468 -151.051768)
		(stroke
			(width 0.0635)
			(type default)
		)
		(layer "B.Cu")
	)
	(gr_line
		(start 321.023234 -149.357334)
		(end 321.150488 -148.758402)
		(stroke
			(width 0.0635)
			(type default)
		)
		(layer "B.Cu")
	)
	(gr_line
		(start 321.03822 -151.424386)
		(end 321.117468 -151.051768)
		(stroke
			(width 0.0635)
			(type default)
		)
		(layer "B.Cu")
	)
	(gr_line
		(start 321.082162 -150.496524)
		(end 321.260216 -150.380954)
		(stroke
			(width 0.0635)
			(type default)
		)
		(layer "B.Cu")
	)
	(gr_line
		(start 321.223894 -149.830282)
		(end 321.339464 -150.008336)
		(stroke
			(width 0.0635)
			(type default)
		)
		(layer "B.Cu")
	)
	(gr_line
		(start 321.260216 -150.380954)
		(end 321.339464 -150.008336)
		(stroke
			(width 0.0635)
			(type default)
		)
		(layer "B.Cu")
	)
	(gr_line
		(start 321.304158 -149.453092)
		(end 321.482212 -149.337522)
		(stroke
			(width 0.0635)
			(type default)
		)
		(layer "B.Cu")
	)
	(gr_line
		(start 321.346068 -176.120298)
		(end 321.679062 -175.607472)
		(stroke
			(width 0.0635)
			(type default)
		)
		(layer "B.Cu")
	)
	(gr_line
		(start 321.44589 -148.78685)
		(end 321.56146 -148.964904)
		(stroke
			(width 0.0635)
			(type default)
		)
		(layer "B.Cu")
	)
	(gr_line
		(start 321.482212 -149.337522)
		(end 321.56146 -148.964904)
		(stroke
			(width 0.0635)
			(type default)
		)
		(layer "B.Cu")
	)
	(gr_line
		(start 321.57416 -176.309782)
		(end 321.781678 -176.26584)
		(stroke
			(width 0.0635)
			(type default)
		)
		(layer "B.Cu")
	)
	(gr_line
		(start 321.781678 -176.26584)
		(end 321.989196 -175.946308)
		(stroke
			(width 0.0635)
			(type default)
		)
		(layer "B.Cu")
	)
	(gr_line
		(start 321.928744 -175.223424)
		(end 322.258944 -174.714916)
		(stroke
			(width 0.0635)
			(type default)
		)
		(layer "B.Cu")
	)
	(gr_line
		(start 321.945254 -175.738536)
		(end 321.989196 -175.946308)
		(stroke
			(width 0.0635)
			(type default)
		)
		(layer "B.Cu")
	)
	(gr_line
		(start 322.155058 -175.415194)
		(end 322.362576 -175.371252)
		(stroke
			(width 0.0635)
			(type default)
		)
		(layer "B.Cu")
	)
	(gr_line
		(start 322.362576 -175.371252)
		(end 322.570094 -175.05172)
		(stroke
			(width 0.0635)
			(type default)
		)
		(layer "B.Cu")
	)
	(gr_line
		(start 322.509134 -174.329598)
		(end 322.840604 -173.819058)
		(stroke
			(width 0.0635)
			(type default)
		)
		(layer "B.Cu")
	)
	(gr_line
		(start 322.526152 -174.843948)
		(end 322.570094 -175.05172)
		(stroke
			(width 0.0635)
			(type default)
		)
		(layer "B.Cu")
	)
	(gr_line
		(start 322.575936 -143.460216)
		(end 322.581016 -143.437102)
		(stroke
			(width 0.0635)
			(type default)
		)
		(layer "B.Cu")
	)
	(gr_line
		(start 322.57619 -143.413988)
		(end 322.581016 -143.437102)
		(stroke
			(width 0.0635)
			(type default)
		)
		(layer "B.Cu")
	)
	(gr_line
		(start 322.735956 -174.520606)
		(end 322.943728 -174.47641)
		(stroke
			(width 0.0635)
			(type default)
		)
		(layer "B.Cu")
	)
	(gr_line
		(start 322.943728 -174.47641)
		(end 323.151246 -174.156878)
		(stroke
			(width 0.0635)
			(type default)
		)
		(layer "B.Cu")
	)
	(gr_line
		(start 323.090286 -173.434756)
		(end 323.421248 -172.924978)
		(stroke
			(width 0.0635)
			(type default)
		)
		(layer "B.Cu")
	)
	(gr_line
		(start 323.107304 -173.949106)
		(end 323.151246 -174.156878)
		(stroke
			(width 0.0635)
			(type default)
		)
		(layer "B.Cu")
	)
	(gr_line
		(start 323.317108 -173.625764)
		(end 323.52488 -173.581822)
		(stroke
			(width 0.0635)
			(type default)
		)
		(layer "B.Cu")
	)
	(gr_line
		(start 323.52488 -173.581822)
		(end 323.732398 -173.26229)
		(stroke
			(width 0.0635)
			(type default)
		)
		(layer "B.Cu")
	)
	(gr_line
		(start 323.688202 -173.054518)
		(end 323.732398 -173.26229)
		(stroke
			(width 0.0635)
			(type default)
		)
		(layer "B.Cu")
	)
	(gr_line
		(start 333.49184 -86.303612)
		(end 333.833724 -85.777324)
		(stroke
			(width 0.0635)
			(type default)
		)
		(layer "B.Cu")
	)
	(gr_line
		(start 333.71917 -86.49462)
		(end 333.940404 -86.44763)
		(stroke
			(width 0.0635)
			(type default)
		)
		(layer "B.Cu")
	)
	(gr_line
		(start 333.940404 -86.44763)
		(end 334.147922 -86.128098)
		(stroke
			(width 0.0635)
			(type default)
		)
		(layer "B.Cu")
	)
	(gr_line
		(start 334.083914 -85.392006)
		(end 334.425798 -84.865464)
		(stroke
			(width 0.0635)
			(type default)
		)
		(layer "B.Cu")
	)
	(gr_line
		(start 334.100932 -85.90661)
		(end 334.147922 -86.128098)
		(stroke
			(width 0.0635)
			(type default)
		)
		(layer "B.Cu")
	)
	(gr_line
		(start 334.31099 -85.583014)
		(end 334.532732 -85.53577)
		(stroke
			(width 0.0635)
			(type default)
		)
		(layer "B.Cu")
	)
	(gr_line
		(start 334.442054 -84.840826)
		(end 334.659224 -84.506054)
		(stroke
			(width 0.0635)
			(type default)
		)
		(layer "B.Cu")
	)
	(gr_line
		(start 334.487774 -192.144904)
		(end 334.50403 -192.141348)
		(stroke
			(width 0.0635)
			(type default)
		)
		(layer "B.Cu")
	)
	(gr_line
		(start 334.50403 -192.141348)
		(end 334.517492 -192.132458)
		(stroke
			(width 0.0635)
			(type default)
		)
		(layer "B.Cu")
	)
	(gr_line
		(start 334.532732 -85.53577)
		(end 334.739996 -85.216238)
		(stroke
			(width 0.0635)
			(type default)
		)
		(layer "B.Cu")
	)
	(gr_line
		(start 334.67675 -84.479384)
		(end 335.017872 -83.954112)
		(stroke
			(width 0.0635)
			(type default)
		)
		(layer "B.Cu")
	)
	(gr_line
		(start 334.692244 -84.991448)
		(end 334.899762 -84.671916)
		(stroke
			(width 0.0635)
			(type default)
		)
		(layer "B.Cu")
	)
	(gr_line
		(start 334.693006 -84.995004)
		(end 334.739996 -85.216238)
		(stroke
			(width 0.0635)
			(type default)
		)
		(layer "B.Cu")
	)
	(gr_line
		(start 334.722978 -195.228972)
		(end 334.738218 -195.22567)
		(stroke
			(width 0.0635)
			(type default)
		)
		(layer "B.Cu")
	)
	(gr_line
		(start 334.738218 -195.22567)
		(end 334.751172 -195.217288)
		(stroke
			(width 0.0635)
			(type default)
		)
		(layer "B.Cu")
	)
	(gr_line
		(start 334.903318 -84.671154)
		(end 335.124806 -84.624164)
		(stroke
			(width 0.0635)
			(type default)
		)
		(layer "B.Cu")
	)
	(gr_line
		(start 335.124806 -84.624164)
		(end 335.332324 -84.304632)
		(stroke
			(width 0.0635)
			(type default)
		)
		(layer "B.Cu")
	)
	(gr_line
		(start 335.268316 -83.568286)
		(end 335.610708 -83.040982)
		(stroke
			(width 0.0635)
			(type default)
		)
		(layer "B.Cu")
	)
	(gr_line
		(start 335.28508 -84.083398)
		(end 335.332324 -84.304632)
		(stroke
			(width 0.0635)
			(type default)
		)
		(layer "B.Cu")
	)
	(gr_line
		(start 335.495392 -83.759548)
		(end 335.71688 -83.712558)
		(stroke
			(width 0.0635)
			(type default)
		)
		(layer "B.Cu")
	)
	(gr_line
		(start 335.71688 -83.712558)
		(end 335.924398 -83.393026)
		(stroke
			(width 0.0635)
			(type default)
		)
		(layer "B.Cu")
	)
	(gr_line
		(start 335.877408 -83.171284)
		(end 335.924398 -83.393026)
		(stroke
			(width 0.0635)
			(type default)
		)
		(layer "B.Cu")
	)
	(gr_line
		(start 337.460082 -80.729836)
		(end 337.460844 -80.728566)
		(stroke
			(width 0.0635)
			(type default)
		)
		(layer "B.Cu")
	)
	(gr_line
		(start 337.460844 -80.728566)
		(end 337.461352 -80.727042)
		(stroke
			(width 0.0635)
			(type default)
		)
		(layer "B.Cu")
	)
	(gr_line
		(start 341.517732 -195.382896)
		(end 341.533226 -195.379594)
		(stroke
			(width 0.0635)
			(type default)
		)
		(layer "B.Cu")
	)
	(gr_line
		(start 341.533226 -195.379594)
		(end 341.54618 -195.371212)
		(stroke
			(width 0.0635)
			(type default)
		)
		(layer "B.Cu")
	)
	(gr_line
		(start 343.01557 -196.688456)
		(end 343.031826 -196.6849)
		(stroke
			(width 0.0635)
			(type default)
		)
		(layer "B.Cu")
	)
	(gr_line
		(start 343.031826 -196.6849)
		(end 343.045288 -196.67601)
		(stroke
			(width 0.0635)
			(type default)
		)
		(layer "B.Cu")
	)
	(gr_line
		(start 343.19591 -80.409288)
		(end 343.209118 -80.388714)
		(stroke
			(width 0.0635)
			(type default)
		)
		(layer "B.Cu")
	)
	(gr_line
		(start 343.209118 -80.388714)
		(end 343.229692 -80.375506)
		(stroke
			(width 0.0635)
			(type default)
		)
		(layer "B.Cu")
	)
	(gr_line
		(start 344.834718 -81.603342)
		(end 344.847926 -81.582768)
		(stroke
			(width 0.0635)
			(type default)
		)
		(layer "B.Cu")
	)
	(gr_line
		(start 344.847926 -81.582768)
		(end 344.8685 -81.56956)
		(stroke
			(width 0.0635)
			(type default)
		)
		(layer "B.Cu")
	)
	(gr_line
		(start 346.657676 -83.110578)
		(end 346.670884 -83.090004)
		(stroke
			(width 0.0635)
			(type default)
		)
		(layer "B.Cu")
	)
	(gr_line
		(start 346.670884 -83.090004)
		(end 346.691458 -83.076796)
		(stroke
			(width 0.0635)
			(type default)
		)
		(layer "B.Cu")
	)
	(gr_line
		(start 350.196658 -245.030244)
		(end 350.210374 -245.035324)
		(stroke
			(width 0.0635)
			(type default)
		)
		(layer "B.Cu")
	)
	(gr_line
		(start 350.764602 -128.627124)
		(end 351.029524 -128.627124)
		(stroke
			(width 0.0635)
			(type default)
		)
		(layer "B.Cu")
	)
	(gr_line
		(start 350.764602 -13.6271)
		(end 351.0153 -13.6271)
		(stroke
			(width 0.0635)
			(type default)
		)
		(layer "B.Cu")
	)
	(gr_arc
		(start 350.788224 -244.743224)
		(mid 350.897244 -244.698066)
		(end 350.942402 -244.589046)
		(stroke
			(width 0.0635)
			(type default)
		)
		(layer "B.Cu")
	)
	(gr_arc
		(start 350.942402 -245.189502)
		(mid 350.897246 -245.080472)
		(end 350.788224 -245.035324)
		(stroke
			(width 0.0635)
			(type default)
		)
		(layer "B.Cu")
	)
	(gr_line
		(start 350.942402 -245.189502)
		(end 350.942402 -245.460774)
		(stroke
			(width 0.0635)
			(type default)
		)
		(layer "B.Cu")
	)
	(gr_line
		(start 350.942402 -244.317774)
		(end 350.942402 -244.589046)
		(stroke
			(width 0.0635)
			(type default)
		)
		(layer "B.Cu")
	)
	(gr_arc
		(start 351.190052 -128.787652)
		(mid 351.143034 -128.674142)
		(end 351.029524 -128.627124)
		(stroke
			(width 0.0635)
			(type default)
		)
		(layer "B.Cu")
	)
	(gr_arc
		(start 351.190052 -13.801852)
		(mid 351.138868 -13.678284)
		(end 351.0153 -13.6271)
		(stroke
			(width 0.0635)
			(type default)
		)
		(layer "B.Cu")
	)
	(gr_line
		(start 351.45599 -130.292856)
		(end 351.482152 -130.25247)
		(stroke
			(width 0.0635)
			(type default)
		)
		(layer "B.Cu")
	)
	(gr_arc
		(start 351.64268 -128.627124)
		(mid 351.529166 -128.674146)
		(end 351.482152 -128.787652)
		(stroke
			(width 0.0635)
			(type default)
		)
		(layer "B.Cu")
	)
	(gr_line
		(start 351.64268 -128.627124)
		(end 351.907602 -128.627124)
		(stroke
			(width 0.0635)
			(type default)
		)
		(layer "B.Cu")
	)
	(gr_arc
		(start 351.656904 -13.6271)
		(mid 351.533316 -13.678279)
		(end 351.482152 -13.801852)
		(stroke
			(width 0.0635)
			(type default)
		)
		(layer "B.Cu")
	)
	(gr_line
		(start 351.656904 -13.6271)
		(end 351.907602 -13.6271)
		(stroke
			(width 0.0635)
			(type default)
		)
		(layer "B.Cu")
	)
	(gr_line
		(start 355.827584 -178.293522)
		(end 355.848158 -178.280314)
		(stroke
			(width 0.0635)
			(type default)
		)
		(layer "B.Cu")
	)
	(gr_line
		(start 355.848158 -178.280314)
		(end 355.861366 -178.25974)
		(stroke
			(width 0.0635)
			(type default)
		)
		(layer "B.Cu")
	)
	(gr_line
		(start 360.558588 -239.008412)
		(end 361.144058 -239.180624)
		(stroke
			(width 0.0635)
			(type default)
		)
		(layer "B.Cu")
	)
	(gr_line
		(start 360.608626 -238.716058)
		(end 360.795062 -238.614458)
		(stroke
			(width 0.0635)
			(type default)
		)
		(layer "B.Cu")
	)
	(gr_line
		(start 360.795062 -238.614458)
		(end 361.160568 -238.722154)
		(stroke
			(width 0.0635)
			(type default)
		)
		(layer "B.Cu")
	)
	(gr_line
		(start 361.160568 -238.722154)
		(end 361.262168 -238.908336)
		(stroke
			(width 0.0635)
			(type default)
		)
		(layer "B.Cu")
	)
	(gr_line
		(start 361.58297 -239.310164)
		(end 362.16971 -239.482884)
		(stroke
			(width 0.0635)
			(type default)
		)
		(layer "B.Cu")
	)
	(gr_line
		(start 361.632246 -239.017302)
		(end 361.818428 -238.915702)
		(stroke
			(width 0.0635)
			(type default)
		)
		(layer "B.Cu")
	)
	(gr_line
		(start 361.818428 -238.915702)
		(end 362.183934 -239.023398)
		(stroke
			(width 0.0635)
			(type default)
		)
		(layer "B.Cu")
	)
	(gr_line
		(start 362.183934 -239.023398)
		(end 362.285534 -239.20958)
		(stroke
			(width 0.0635)
			(type default)
		)
		(layer "B.Cu")
	)
	(gr_line
		(start 362.605066 -239.611154)
		(end 363.19333 -239.784128)
		(stroke
			(width 0.0635)
			(type default)
		)
		(layer "B.Cu")
	)
	(gr_line
		(start 362.655612 -239.318546)
		(end 362.841794 -239.2172)
		(stroke
			(width 0.0635)
			(type default)
		)
		(layer "B.Cu")
	)
	(gr_line
		(start 362.841794 -239.2172)
		(end 363.2073 -239.324642)
		(stroke
			(width 0.0635)
			(type default)
		)
		(layer "B.Cu")
	)
	(gr_line
		(start 363.016546 -69.784468)
		(end 363.546136 -69.440552)
		(stroke
			(width 0.0635)
			(type default)
		)
		(layer "B.Cu")
	)
	(gr_line
		(start 363.147864 -70.050406)
		(end 363.369606 -70.097396)
		(stroke
			(width 0.0635)
			(type default)
		)
		(layer "B.Cu")
	)
	(gr_line
		(start 363.2073 -239.324642)
		(end 363.3089 -239.510824)
		(stroke
			(width 0.0635)
			(type default)
		)
		(layer "B.Cu")
	)
	(gr_line
		(start 363.369606 -70.097396)
		(end 363.689138 -69.890132)
		(stroke
			(width 0.0635)
			(type default)
		)
		(layer "B.Cu")
	)
	(gr_line
		(start 363.628686 -239.912398)
		(end 364.215934 -240.085118)
		(stroke
			(width 0.0635)
			(type default)
		)
		(layer "B.Cu")
	)
	(gr_line
		(start 363.678978 -239.61979)
		(end 363.86516 -239.51819)
		(stroke
			(width 0.0635)
			(type default)
		)
		(layer "B.Cu")
	)
	(gr_line
		(start 363.689138 -69.890132)
		(end 363.736128 -69.668136)
		(stroke
			(width 0.0635)
			(type default)
		)
		(layer "B.Cu")
	)
	(gr_line
		(start 363.86516 -239.51819)
		(end 364.230666 -239.625886)
		(stroke
			(width 0.0635)
			(type default)
		)
		(layer "B.Cu")
	)
	(gr_line
		(start 363.929168 -69.191886)
		(end 364.457996 -68.848478)
		(stroke
			(width 0.0635)
			(type default)
		)
		(layer "B.Cu")
	)
	(gr_line
		(start 364.05947 -69.458332)
		(end 364.281212 -69.505322)
		(stroke
			(width 0.0635)
			(type default)
		)
		(layer "B.Cu")
	)
	(gr_line
		(start 364.230666 -239.625886)
		(end 364.332266 -239.812068)
		(stroke
			(width 0.0635)
			(type default)
		)
		(layer "B.Cu")
	)
	(gr_line
		(start 364.281212 -69.505322)
		(end 364.600744 -69.298058)
		(stroke
			(width 0.0635)
			(type default)
		)
		(layer "B.Cu")
	)
	(gr_line
		(start 364.600744 -69.298058)
		(end 364.647988 -69.076062)
		(stroke
			(width 0.0635)
			(type default)
		)
		(layer "B.Cu")
	)
	(gr_line
		(start 364.841028 -68.599812)
		(end 365.368078 -68.257674)
		(stroke
			(width 0.0635)
			(type default)
		)
		(layer "B.Cu")
	)
	(gr_line
		(start 364.97133 -68.866258)
		(end 365.193072 -68.913248)
		(stroke
			(width 0.0635)
			(type default)
		)
		(layer "B.Cu")
	)
	(gr_line
		(start 365.193072 -68.913248)
		(end 365.512604 -68.705984)
		(stroke
			(width 0.0635)
			(type default)
		)
		(layer "B.Cu")
	)
	(gr_line
		(start 365.35741 -181.838092)
		(end 365.86922 -181.50586)
		(stroke
			(width 0.0635)
			(type default)
		)
		(layer "B.Cu")
	)
	(gr_line
		(start 365.488728 -182.104284)
		(end 365.696246 -182.148226)
		(stroke
			(width 0.0635)
			(type default)
		)
		(layer "B.Cu")
	)
	(gr_line
		(start 365.512604 -68.705984)
		(end 365.559594 -68.483988)
		(stroke
			(width 0.0635)
			(type default)
		)
		(layer "B.Cu")
	)
	(gr_line
		(start 365.696246 -182.148226)
		(end 366.015778 -181.940708)
		(stroke
			(width 0.0635)
			(type default)
		)
		(layer "B.Cu")
	)
	(gr_line
		(start 365.752888 -68.007484)
		(end 366.280954 -67.664838)
		(stroke
			(width 0.0635)
			(type default)
		)
		(layer "B.Cu")
	)
	(gr_line
		(start 365.882936 -68.274184)
		(end 366.104932 -68.321174)
		(stroke
			(width 0.0635)
			(type default)
		)
		(layer "B.Cu")
	)
	(gr_line
		(start 366.015778 -181.940708)
		(end 366.05972 -181.73319)
		(stroke
			(width 0.0635)
			(type default)
		)
		(layer "B.Cu")
	)
	(gr_line
		(start 366.104932 -68.321174)
		(end 366.424464 -68.11391)
		(stroke
			(width 0.0635)
			(type default)
		)
		(layer "B.Cu")
	)
	(gr_line
		(start 366.253522 -181.256178)
		(end 366.764062 -180.924454)
		(stroke
			(width 0.0635)
			(type default)
		)
		(layer "B.Cu")
	)
	(gr_line
		(start 366.383316 -181.523132)
		(end 366.590834 -181.567328)
		(stroke
			(width 0.0635)
			(type default)
		)
		(layer "B.Cu")
	)
	(gr_line
		(start 366.424464 -68.11391)
		(end 366.471454 -67.891914)
		(stroke
			(width 0.0635)
			(type default)
		)
		(layer "B.Cu")
	)
	(gr_line
		(start 366.590834 -181.567328)
		(end 366.910366 -181.35981)
		(stroke
			(width 0.0635)
			(type default)
		)
		(layer "B.Cu")
	)
	(gr_line
		(start 366.910366 -181.35981)
		(end 366.954308 -181.152292)
		(stroke
			(width 0.0635)
			(type default)
		)
		(layer "B.Cu")
	)
	(gr_line
		(start 367.14811 -180.67528)
		(end 367.658142 -180.344064)
		(stroke
			(width 0.0635)
			(type default)
		)
		(layer "B.Cu")
	)
	(gr_line
		(start 367.277904 -180.942234)
		(end 367.485422 -180.986176)
		(stroke
			(width 0.0635)
			(type default)
		)
		(layer "B.Cu")
	)
	(gr_line
		(start 367.485422 -180.986176)
		(end 367.804954 -180.778658)
		(stroke
			(width 0.0635)
			(type default)
		)
		(layer "B.Cu")
	)
	(gr_line
		(start 367.804954 -180.778658)
		(end 367.84915 -180.57114)
		(stroke
			(width 0.0635)
			(type default)
		)
		(layer "B.Cu")
	)
	(gr_line
		(start 368.042952 -180.094128)
		(end 368.553492 -179.762404)
		(stroke
			(width 0.0635)
			(type default)
		)
		(layer "B.Cu")
	)
	(gr_line
		(start 368.172746 -180.361082)
		(end 368.380264 -180.405278)
		(stroke
			(width 0.0635)
			(type default)
		)
		(layer "B.Cu")
	)
	(gr_line
		(start 368.380264 -180.405278)
		(end 368.699796 -180.19776)
		(stroke
			(width 0.0635)
			(type default)
		)
		(layer "B.Cu")
	)
	(gr_line
		(start 368.699796 -180.19776)
		(end 368.743738 -179.990242)
		(stroke
			(width 0.0635)
			(type default)
		)
		(layer "B.Cu")
	)
	(gr_line
		(start 374.132856 -60.307474)
		(end 374.661684 -59.964066)
		(stroke
			(width 0.0635)
			(type default)
		)
		(layer "B.Cu")
	)
	(gr_line
		(start 374.263412 -60.57392)
		(end 374.4849 -60.621164)
		(stroke
			(width 0.0635)
			(type default)
		)
		(layer "B.Cu")
	)
	(gr_line
		(start 374.4849 -60.621164)
		(end 374.804686 -60.413646)
		(stroke
			(width 0.0635)
			(type default)
		)
		(layer "B.Cu")
	)
	(gr_line
		(start 374.804686 -60.413646)
		(end 374.851676 -60.19165)
		(stroke
			(width 0.0635)
			(type default)
		)
		(layer "B.Cu")
	)
	(gr_line
		(start 375.044716 -59.7154)
		(end 375.571766 -59.373262)
		(stroke
			(width 0.0635)
			(type default)
		)
		(layer "B.Cu")
	)
	(gr_line
		(start 375.175018 -59.981846)
		(end 375.39676 -60.02909)
		(stroke
			(width 0.0635)
			(type default)
		)
		(layer "B.Cu")
	)
	(gr_line
		(start 375.39676 -60.02909)
		(end 375.716292 -59.821572)
		(stroke
			(width 0.0635)
			(type default)
		)
		(layer "B.Cu")
	)
	(gr_line
		(start 375.716292 -59.821572)
		(end 375.763282 -59.59983)
		(stroke
			(width 0.0635)
			(type default)
		)
		(layer "B.Cu")
	)
	(gr_line
		(start 375.956576 -59.123072)
		(end 376.484642 -58.780426)
		(stroke
			(width 0.0635)
			(type default)
		)
		(layer "B.Cu")
	)
	(gr_line
		(start 376.086878 -59.389772)
		(end 376.30862 -59.437016)
		(stroke
			(width 0.0635)
			(type default)
		)
		(layer "B.Cu")
	)
	(gr_line
		(start 376.30862 -59.437016)
		(end 376.628152 -59.229498)
		(stroke
			(width 0.0635)
			(type default)
		)
		(layer "B.Cu")
	)
	(gr_line
		(start 376.628152 -59.229498)
		(end 376.675142 -59.007502)
		(stroke
			(width 0.0635)
			(type default)
		)
		(layer "B.Cu")
	)
	(gr_line
		(start 376.867674 -58.531506)
		(end 377.39574 -58.188606)
		(stroke
			(width 0.0635)
			(type default)
		)
		(layer "B.Cu")
	)
	(gr_line
		(start 376.998484 -58.797698)
		(end 377.220226 -58.844942)
		(stroke
			(width 0.0635)
			(type default)
		)
		(layer "B.Cu")
	)
	(gr_line
		(start 377.165616 -144.917668)
		(end 377.497594 -144.406366)
		(stroke
			(width 0.0635)
			(type default)
		)
		(layer "B.Cu")
	)
	(gr_line
		(start 377.220226 -58.844942)
		(end 377.539758 -58.637424)
		(stroke
			(width 0.0635)
			(type default)
		)
		(layer "B.Cu")
	)
	(gr_line
		(start 377.393454 -145.10766)
		(end 377.600972 -145.063718)
		(stroke
			(width 0.0635)
			(type default)
		)
		(layer "B.Cu")
	)
	(gr_line
		(start 377.539758 -58.637424)
		(end 377.586748 -58.415682)
		(stroke
			(width 0.0635)
			(type default)
		)
		(layer "B.Cu")
	)
	(gr_line
		(start 377.600972 -145.063718)
		(end 377.80849 -144.744186)
		(stroke
			(width 0.0635)
			(type default)
		)
		(layer "B.Cu")
	)
	(gr_line
		(start 377.74626 -144.023334)
		(end 378.079254 -143.510508)
		(stroke
			(width 0.0635)
			(type default)
		)
		(layer "B.Cu")
	)
	(gr_line
		(start 377.764294 -144.536668)
		(end 377.80849 -144.744186)
		(stroke
			(width 0.0635)
			(type default)
		)
		(layer "B.Cu")
	)
	(gr_line
		(start 377.804172 -22.79142)
		(end 378.147072 -22.263354)
		(stroke
			(width 0.0635)
			(type default)
		)
		(layer "B.Cu")
	)
	(gr_line
		(start 377.974352 -144.213072)
		(end 378.18187 -144.168876)
		(stroke
			(width 0.0635)
			(type default)
		)
		(layer "B.Cu")
	)
	(gr_line
		(start 378.03201 -22.981412)
		(end 378.253498 -22.934168)
		(stroke
			(width 0.0635)
			(type default)
		)
		(layer "B.Cu")
	)
	(gr_line
		(start 378.18187 -144.168876)
		(end 378.389388 -143.849344)
		(stroke
			(width 0.0635)
			(type default)
		)
		(layer "B.Cu")
	)
	(gr_line
		(start 378.253498 -22.934168)
		(end 378.461016 -22.614636)
		(stroke
			(width 0.0635)
			(type default)
		)
		(layer "B.Cu")
	)
	(gr_line
		(start 378.32792 -143.12773)
		(end 378.659898 -142.616428)
		(stroke
			(width 0.0635)
			(type default)
		)
		(layer "B.Cu")
	)
	(gr_line
		(start 378.345446 -143.641826)
		(end 378.389388 -143.849344)
		(stroke
			(width 0.0635)
			(type default)
		)
		(layer "B.Cu")
	)
	(gr_line
		(start 378.397008 -21.878544)
		(end 378.7394 -21.35124)
		(stroke
			(width 0.0635)
			(type default)
		)
		(layer "B.Cu")
	)
	(gr_line
		(start 378.414026 -22.393402)
		(end 378.461016 -22.614636)
		(stroke
			(width 0.0635)
			(type default)
		)
		(layer "B.Cu")
	)
	(gr_line
		(start 378.555504 -143.31823)
		(end 378.763022 -143.274288)
		(stroke
			(width 0.0635)
			(type default)
		)
		(layer "B.Cu")
	)
	(gr_line
		(start 378.624338 -22.069552)
		(end 378.845572 -22.022562)
		(stroke
			(width 0.0635)
			(type default)
		)
		(layer "B.Cu")
	)
	(gr_line
		(start 378.763022 -143.274288)
		(end 378.97054 -142.954756)
		(stroke
			(width 0.0635)
			(type default)
		)
		(layer "B.Cu")
	)
	(gr_line
		(start 378.845572 -22.022562)
		(end 379.05309 -21.70303)
		(stroke
			(width 0.0635)
			(type default)
		)
		(layer "B.Cu")
	)
	(gr_line
		(start 378.908564 -142.23365)
		(end 379.241558 -141.720824)
		(stroke
			(width 0.0635)
			(type default)
		)
		(layer "B.Cu")
	)
	(gr_line
		(start 378.926344 -142.747492)
		(end 378.97054 -142.954756)
		(stroke
			(width 0.0635)
			(type default)
		)
		(layer "B.Cu")
	)
	(gr_line
		(start 378.988574 -20.967446)
		(end 379.331474 -20.43938)
		(stroke
			(width 0.0635)
			(type default)
		)
		(layer "B.Cu")
	)
	(gr_line
		(start 379.0061 -21.481542)
		(end 379.05309 -21.70303)
		(stroke
			(width 0.0635)
			(type default)
		)
		(layer "B.Cu")
	)
	(gr_line
		(start 379.136402 -142.423642)
		(end 379.34392 -142.3797)
		(stroke
			(width 0.0635)
			(type default)
		)
		(layer "B.Cu")
	)
	(gr_line
		(start 379.216158 -21.157946)
		(end 379.437646 -21.110702)
		(stroke
			(width 0.0635)
			(type default)
		)
		(layer "B.Cu")
	)
	(gr_line
		(start 379.34392 -142.3797)
		(end 379.551438 -142.060168)
		(stroke
			(width 0.0635)
			(type default)
		)
		(layer "B.Cu")
	)
	(gr_line
		(start 379.437646 -21.110702)
		(end 379.645164 -20.79117)
		(stroke
			(width 0.0635)
			(type default)
		)
		(layer "B.Cu")
	)
	(gr_line
		(start 379.507496 -141.85265)
		(end 379.551438 -142.060168)
		(stroke
			(width 0.0635)
			(type default)
		)
		(layer "B.Cu")
	)
	(gr_line
		(start 379.581156 -20.055078)
		(end 379.923548 -19.527774)
		(stroke
			(width 0.0635)
			(type default)
		)
		(layer "B.Cu")
	)
	(gr_line
		(start 379.598174 -20.569936)
		(end 379.645164 -20.79117)
		(stroke
			(width 0.0635)
			(type default)
		)
		(layer "B.Cu")
	)
	(gr_line
		(start 379.808486 -20.246086)
		(end 380.02972 -20.199096)
		(stroke
			(width 0.0635)
			(type default)
		)
		(layer "B.Cu")
	)
	(gr_line
		(start 380.02972 -20.199096)
		(end 380.237238 -19.879564)
		(stroke
			(width 0.0635)
			(type default)
		)
		(layer "B.Cu")
	)
	(gr_line
		(start 380.190248 -19.658076)
		(end 380.237238 -19.879564)
		(stroke
			(width 0.0635)
			(type default)
		)
		(layer "B.Cu")
	)
	(gr_line
		(start 380.977394 -245.019068)
		(end 380.980442 -245.020084)
		(stroke
			(width 0.0635)
			(type default)
		)
		(layer "B.Cu")
	)
	(gr_arc
		(start 382.284224 -244.727984)
		(mid 382.431321 -244.667055)
		(end 382.49225 -244.519958)
		(stroke
			(width 0.0635)
			(type default)
		)
		(layer "B.Cu")
	)
	(gr_line
		(start 382.31445 -128.627124)
		(end 382.576324 -128.627124)
		(stroke
			(width 0.0635)
			(type default)
		)
		(layer "B.Cu")
	)
	(gr_line
		(start 382.31445 -13.6271)
		(end 382.5875 -13.6271)
		(stroke
			(width 0.0635)
			(type default)
		)
		(layer "B.Cu")
	)
	(gr_arc
		(start 382.49225 -245.22811)
		(mid 382.431326 -245.080998)
		(end 382.284224 -245.020084)
		(stroke
			(width 0.0635)
			(type default)
		)
		(layer "B.Cu")
	)
	(gr_line
		(start 382.49225 -245.22811)
		(end 382.49225 -245.445534)
		(stroke
			(width 0.0635)
			(type default)
		)
		(layer "B.Cu")
	)
	(gr_line
		(start 382.49225 -244.302534)
		(end 382.49225 -244.519958)
		(stroke
			(width 0.0635)
			(type default)
		)
		(layer "B.Cu")
	)
	(gr_line
		(start 382.49606 -137.245852)
		(end 382.50495 -137.23239)
		(stroke
			(width 0.0635)
			(type default)
		)
		(layer "B.Cu")
	)
	(gr_line
		(start 382.50495 -137.23239)
		(end 382.508506 -137.216134)
		(stroke
			(width 0.0635)
			(type default)
		)
		(layer "B.Cu")
	)
	(gr_arc
		(start 382.7399 -128.7907)
		(mid 382.69199 -128.675034)
		(end 382.576324 -128.627124)
		(stroke
			(width 0.0635)
			(type default)
		)
		(layer "B.Cu")
	)
	(gr_arc
		(start 382.7399 -13.7795)
		(mid 382.695263 -13.671737)
		(end 382.5875 -13.6271)
		(stroke
			(width 0.0635)
			(type default)
		)
		(layer "B.Cu")
	)
	(gr_line
		(start 383.005838 -15.317978)
		(end 383.032 -15.277592)
		(stroke
			(width 0.0635)
			(type default)
		)
		(layer "B.Cu")
	)
	(gr_arc
		(start 383.1844 -13.6271)
		(mid 383.076637 -13.671737)
		(end 383.032 -13.7795)
		(stroke
			(width 0.0635)
			(type default)
		)
		(layer "B.Cu")
	)
	(gr_line
		(start 383.1844 -13.6271)
		(end 383.45745 -13.6271)
		(stroke
			(width 0.0635)
			(type default)
		)
		(layer "B.Cu")
	)
	(gr_arc
		(start 383.195576 -128.627124)
		(mid 383.079926 -128.675043)
		(end 383.032 -128.7907)
		(stroke
			(width 0.0635)
			(type default)
		)
		(layer "B.Cu")
	)
	(gr_line
		(start 383.195576 -128.627124)
		(end 383.45745 -128.627124)
		(stroke
			(width 0.0635)
			(type default)
		)
		(layer "B.Cu")
	)
	(gr_line
		(start 393.304014 -52.806092)
		(end 393.81557 -52.47386)
		(stroke
			(width 0.0635)
			(type default)
		)
		(layer "B.Cu")
	)
	(gr_line
		(start 393.434316 -53.072792)
		(end 393.641834 -53.116988)
		(stroke
			(width 0.0635)
			(type default)
		)
		(layer "B.Cu")
	)
	(gr_line
		(start 393.641834 -53.116988)
		(end 393.961366 -52.90947)
		(stroke
			(width 0.0635)
			(type default)
		)
		(layer "B.Cu")
	)
	(gr_line
		(start 393.961366 -52.90947)
		(end 394.005308 -52.701952)
		(stroke
			(width 0.0635)
			(type default)
		)
		(layer "B.Cu")
	)
	(gr_line
		(start 394.198602 -52.225194)
		(end 394.70965 -51.89347)
		(stroke
			(width 0.0635)
			(type default)
		)
		(layer "B.Cu")
	)
	(gr_line
		(start 394.328904 -52.491894)
		(end 394.536422 -52.535836)
		(stroke
			(width 0.0635)
			(type default)
		)
		(layer "B.Cu")
	)
	(gr_line
		(start 394.536422 -52.535836)
		(end 394.855954 -52.328318)
		(stroke
			(width 0.0635)
			(type default)
		)
		(layer "B.Cu")
	)
	(gr_line
		(start 394.855954 -52.328318)
		(end 394.90015 -52.1208)
		(stroke
			(width 0.0635)
			(type default)
		)
		(layer "B.Cu")
	)
	(gr_line
		(start 395.093952 -51.643788)
		(end 395.604492 -51.312064)
		(stroke
			(width 0.0635)
			(type default)
		)
		(layer "B.Cu")
	)
	(gr_line
		(start 395.223746 -51.910742)
		(end 395.431264 -51.954938)
		(stroke
			(width 0.0635)
			(type default)
		)
		(layer "B.Cu")
	)
	(gr_line
		(start 395.431264 -51.954938)
		(end 395.750796 -51.74742)
		(stroke
			(width 0.0635)
			(type default)
		)
		(layer "B.Cu")
	)
	(gr_line
		(start 395.750796 -51.74742)
		(end 395.794738 -51.539902)
		(stroke
			(width 0.0635)
			(type default)
		)
		(layer "B.Cu")
	)
	(gr_line
		(start 395.987778 -51.063398)
		(end 396.498826 -50.73142)
		(stroke
			(width 0.0635)
			(type default)
		)
		(layer "B.Cu")
	)
	(gr_line
		(start 396.118334 -51.329844)
		(end 396.325852 -51.373786)
		(stroke
			(width 0.0635)
			(type default)
		)
		(layer "B.Cu")
	)
	(gr_line
		(start 396.325852 -51.373786)
		(end 396.645384 -51.166268)
		(stroke
			(width 0.0635)
			(type default)
		)
		(layer "B.Cu")
	)
	(gr_line
		(start 396.645384 -51.166268)
		(end 396.68958 -50.95875)
		(stroke
			(width 0.0635)
			(type default)
		)
		(layer "B.Cu")
	)
	(gr_line
		(start 404.084282 -236.180122)
		(end 404.68804 -236.26572)
		(stroke
			(width 0.0635)
			(type default)
		)
		(layer "B.Cu")
	)
	(gr_line
		(start 404.090632 -235.88345)
		(end 404.26005 -235.755942)
		(stroke
			(width 0.0635)
			(type default)
		)
		(layer "B.Cu")
	)
	(gr_line
		(start 404.26005 -235.755942)
		(end 404.63724 -235.809282)
		(stroke
			(width 0.0635)
			(type default)
		)
		(layer "B.Cu")
	)
	(gr_line
		(start 404.367492 -150.028148)
		(end 404.388066 -150.01494)
		(stroke
			(width 0.0635)
			(type default)
		)
		(layer "B.Cu")
	)
	(gr_line
		(start 404.388066 -150.01494)
		(end 404.401274 -149.994366)
		(stroke
			(width 0.0635)
			(type default)
		)
		(layer "B.Cu")
	)
	(gr_line
		(start 404.63724 -235.809282)
		(end 404.764748 -235.978954)
		(stroke
			(width 0.0635)
			(type default)
		)
		(layer "B.Cu")
	)
	(gr_line
		(start 405.139652 -236.329728)
		(end 405.745442 -236.41558)
		(stroke
			(width 0.0635)
			(type default)
		)
		(layer "B.Cu")
	)
	(gr_line
		(start 405.146764 -236.033056)
		(end 405.316436 -235.905548)
		(stroke
			(width 0.0635)
			(type default)
		)
		(layer "B.Cu")
	)
	(gr_line
		(start 405.316436 -235.905548)
		(end 405.693626 -235.959142)
		(stroke
			(width 0.0635)
			(type default)
		)
		(layer "B.Cu")
	)
	(gr_line
		(start 405.693626 -235.959142)
		(end 405.821134 -236.12856)
		(stroke
			(width 0.0635)
			(type default)
		)
		(layer "B.Cu")
	)
	(gr_line
		(start 405.883872 -147.174712)
		(end 406.217882 -146.660362)
		(stroke
			(width 0.0635)
			(type default)
		)
		(layer "B.Cu")
	)
	(gr_line
		(start 406.112472 -147.363942)
		(end 406.31999 -147.319746)
		(stroke
			(width 0.0635)
			(type default)
		)
		(layer "B.Cu")
	)
	(gr_line
		(start 406.195022 -236.479334)
		(end 406.80259 -236.56544)
		(stroke
			(width 0.0635)
			(type default)
		)
		(layer "B.Cu")
	)
	(gr_line
		(start 406.202896 -236.182662)
		(end 406.372568 -236.055408)
		(stroke
			(width 0.0635)
			(type default)
		)
		(layer "B.Cu")
	)
	(gr_line
		(start 406.31999 -147.319746)
		(end 406.527508 -147.000214)
		(stroke
			(width 0.0635)
			(type default)
		)
		(layer "B.Cu")
	)
	(gr_line
		(start 406.372568 -236.055408)
		(end 406.749758 -236.108748)
		(stroke
			(width 0.0635)
			(type default)
		)
		(layer "B.Cu")
	)
	(gr_line
		(start 406.465024 -146.27987)
		(end 406.798526 -145.766282)
		(stroke
			(width 0.0635)
			(type default)
		)
		(layer "B.Cu")
	)
	(gr_line
		(start 406.478232 -37.70884)
		(end 406.4889 -37.700204)
		(stroke
			(width 0.0635)
			(type default)
		)
		(layer "B.Cu")
	)
	(gr_line
		(start 406.483566 -146.792696)
		(end 406.527508 -147.000214)
		(stroke
			(width 0.0635)
			(type default)
		)
		(layer "B.Cu")
	)
	(gr_line
		(start 406.4889 -37.700204)
		(end 406.495504 -37.689028)
		(stroke
			(width 0.0635)
			(type default)
		)
		(layer "B.Cu")
	)
	(gr_line
		(start 406.693624 -146.4691)
		(end 406.901142 -146.425158)
		(stroke
			(width 0.0635)
			(type default)
		)
		(layer "B.Cu")
	)
	(gr_line
		(start 406.749758 -236.108748)
		(end 406.877266 -236.27842)
		(stroke
			(width 0.0635)
			(type default)
		)
		(layer "B.Cu")
	)
	(gr_line
		(start 406.901142 -146.425158)
		(end 407.10866 -146.105626)
		(stroke
			(width 0.0635)
			(type default)
		)
		(layer "B.Cu")
	)
	(gr_line
		(start 407.045922 -145.385282)
		(end 407.38044 -144.87017)
		(stroke
			(width 0.0635)
			(type default)
		)
		(layer "B.Cu")
	)
	(gr_line
		(start 407.064464 -145.898108)
		(end 407.10866 -146.105626)
		(stroke
			(width 0.0635)
			(type default)
		)
		(layer "B.Cu")
	)
	(gr_line
		(start 407.251916 -236.629194)
		(end 407.85796 -236.715046)
		(stroke
			(width 0.0635)
			(type default)
		)
		(layer "B.Cu")
	)
	(gr_line
		(start 407.259282 -236.332522)
		(end 407.428954 -236.205014)
		(stroke
			(width 0.0635)
			(type default)
		)
		(layer "B.Cu")
	)
	(gr_line
		(start 407.274522 -145.574512)
		(end 407.48204 -145.53057)
		(stroke
			(width 0.0635)
			(type default)
		)
		(layer "B.Cu")
	)
	(gr_line
		(start 407.428954 -236.205014)
		(end 407.806144 -236.258354)
		(stroke
			(width 0.0635)
			(type default)
		)
		(layer "B.Cu")
	)
	(gr_line
		(start 407.48204 -145.53057)
		(end 407.689558 -145.211038)
		(stroke
			(width 0.0635)
			(type default)
		)
		(layer "B.Cu")
	)
	(gr_line
		(start 407.484834 -243.52123)
		(end 408.069542 -243.703348)
		(stroke
			(width 0.0635)
			(type default)
		)
		(layer "B.Cu")
	)
	(gr_line
		(start 407.539698 -243.229638)
		(end 407.727658 -243.131086)
		(stroke
			(width 0.0635)
			(type default)
		)
		(layer "B.Cu")
	)
	(gr_line
		(start 407.625804 -144.492218)
		(end 407.96083 -143.97609)
		(stroke
			(width 0.0635)
			(type default)
		)
		(layer "B.Cu")
	)
	(gr_line
		(start 407.645616 -145.003266)
		(end 407.689558 -145.211038)
		(stroke
			(width 0.0635)
			(type default)
		)
		(layer "B.Cu")
	)
	(gr_line
		(start 407.727658 -243.131086)
		(end 408.091386 -243.24437)
		(stroke
			(width 0.0635)
			(type default)
		)
		(layer "B.Cu")
	)
	(gr_line
		(start 407.806144 -236.258354)
		(end 407.933652 -236.428026)
		(stroke
			(width 0.0635)
			(type default)
		)
		(layer "B.Cu")
	)
	(gr_line
		(start 407.85542 -144.679924)
		(end 408.063192 -144.635728)
		(stroke
			(width 0.0635)
			(type default)
		)
		(layer "B.Cu")
	)
	(gr_line
		(start 408.063192 -144.635728)
		(end 408.27071 -144.316196)
		(stroke
			(width 0.0635)
			(type default)
		)
		(layer "B.Cu")
	)
	(gr_line
		(start 408.071066 -151.821388)
		(end 408.583892 -151.488648)
		(stroke
			(width 0.0635)
			(type default)
		)
		(layer "B.Cu")
	)
	(gr_line
		(start 408.091386 -243.24437)
		(end 408.190192 -243.432076)
		(stroke
			(width 0.0635)
			(type default)
		)
		(layer "B.Cu")
	)
	(gr_line
		(start 408.202384 -152.08758)
		(end 408.409902 -152.131776)
		(stroke
			(width 0.0635)
			(type default)
		)
		(layer "B.Cu")
	)
	(gr_line
		(start 408.226514 -144.108678)
		(end 408.27071 -144.316196)
		(stroke
			(width 0.0635)
			(type default)
		)
		(layer "B.Cu")
	)
	(gr_line
		(start 408.409902 -152.131776)
		(end 408.729434 -151.924258)
		(stroke
			(width 0.0635)
			(type default)
		)
		(layer "B.Cu")
	)
	(gr_line
		(start 408.50439 -243.83873)
		(end 409.089352 -244.020848)
		(stroke
			(width 0.0635)
			(type default)
		)
		(layer "B.Cu")
	)
	(gr_line
		(start 408.558492 -243.546884)
		(end 408.746198 -243.448078)
		(stroke
			(width 0.0635)
			(type default)
		)
		(layer "B.Cu")
	)
	(gr_line
		(start 408.729434 -151.924258)
		(end 408.773376 -151.71674)
		(stroke
			(width 0.0635)
			(type default)
		)
		(layer "B.Cu")
	)
	(gr_line
		(start 408.746198 -243.448078)
		(end 409.109926 -243.561362)
		(stroke
			(width 0.0635)
			(type default)
		)
		(layer "B.Cu")
	)
	(gr_line
		(start 408.965908 -151.24049)
		(end 409.477718 -150.908258)
		(stroke
			(width 0.0635)
			(type default)
		)
		(layer "B.Cu")
	)
	(gr_line
		(start 409.096972 -151.506682)
		(end 409.30449 -151.550624)
		(stroke
			(width 0.0635)
			(type default)
		)
		(layer "B.Cu")
	)
	(gr_line
		(start 409.109926 -243.561362)
		(end 409.208732 -243.749322)
		(stroke
			(width 0.0635)
			(type default)
		)
		(layer "B.Cu")
	)
	(gr_line
		(start 409.30449 -151.550624)
		(end 409.624022 -151.343106)
		(stroke
			(width 0.0635)
			(type default)
		)
		(layer "B.Cu")
	)
	(gr_line
		(start 409.522168 -244.155468)
		(end 410.106114 -244.337332)
		(stroke
			(width 0.0635)
			(type default)
		)
		(layer "B.Cu")
	)
	(gr_line
		(start 409.577032 -243.863876)
		(end 409.764738 -243.765324)
		(stroke
			(width 0.0635)
			(type default)
		)
		(layer "B.Cu")
	)
	(gr_line
		(start 409.624022 -151.343106)
		(end 409.668218 -151.135588)
		(stroke
			(width 0.0635)
			(type default)
		)
		(layer "B.Cu")
	)
	(gr_line
		(start 409.764738 -243.765324)
		(end 410.128466 -243.878608)
		(stroke
			(width 0.0635)
			(type default)
		)
		(layer "B.Cu")
	)
	(gr_line
		(start 409.86075 -150.659592)
		(end 410.371036 -150.328376)
		(stroke
			(width 0.0635)
			(type default)
		)
		(layer "B.Cu")
	)
	(gr_line
		(start 409.99156 -150.92553)
		(end 410.199332 -150.969726)
		(stroke
			(width 0.0635)
			(type default)
		)
		(layer "B.Cu")
	)
	(gr_line
		(start 410.128466 -243.878608)
		(end 410.227272 -244.066314)
		(stroke
			(width 0.0635)
			(type default)
		)
		(layer "B.Cu")
	)
	(gr_line
		(start 410.199332 -150.969726)
		(end 410.518864 -150.762208)
		(stroke
			(width 0.0635)
			(type default)
		)
		(layer "B.Cu")
	)
	(gr_line
		(start 410.518864 -150.762208)
		(end 410.562806 -150.55469)
		(stroke
			(width 0.0635)
			(type default)
		)
		(layer "B.Cu")
	)
	(gr_line
		(start 410.757116 -150.077424)
		(end 411.26791 -149.7457)
		(stroke
			(width 0.0635)
			(type default)
		)
		(layer "B.Cu")
	)
	(gr_line
		(start 410.886402 -150.344632)
		(end 411.09392 -150.388574)
		(stroke
			(width 0.0635)
			(type default)
		)
		(layer "B.Cu")
	)
	(gr_line
		(start 411.09392 -150.388574)
		(end 411.413452 -150.18131)
		(stroke
			(width 0.0635)
			(type default)
		)
		(layer "B.Cu")
	)
	(gr_line
		(start 411.413452 -150.18131)
		(end 411.457902 -149.973538)
		(stroke
			(width 0.0635)
			(type default)
		)
		(layer "B.Cu")
	)
	(gr_line
		(start 412.75127 -245.160546)
		(end 412.756604 -245.162324)
		(stroke
			(width 0.0635)
			(type default)
		)
		(layer "B.Cu")
	)
	(gr_line
		(start 413.864552 -128.627124)
		(end 414.148524 -128.627124)
		(stroke
			(width 0.0635)
			(type default)
		)
		(layer "B.Cu")
	)
	(gr_line
		(start 413.864552 -13.6271)
		(end 414.1343 -13.6271)
		(stroke
			(width 0.0635)
			(type default)
		)
		(layer "B.Cu")
	)
	(gr_arc
		(start 413.907224 -244.870224)
		(mid 414.002774 -244.830646)
		(end 414.042352 -244.735096)
		(stroke
			(width 0.0635)
			(type default)
		)
		(layer "B.Cu")
	)
	(gr_arc
		(start 414.042352 -245.297452)
		(mid 414.002758 -245.201925)
		(end 413.907224 -245.162324)
		(stroke
			(width 0.0635)
			(type default)
		)
		(layer "B.Cu")
	)
	(gr_line
		(start 414.042352 -245.297452)
		(end 414.042352 -245.587774)
		(stroke
			(width 0.0635)
			(type default)
		)
		(layer "B.Cu")
	)
	(gr_line
		(start 414.042352 -244.444774)
		(end 414.042352 -244.735096)
		(stroke
			(width 0.0635)
			(type default)
		)
		(layer "B.Cu")
	)
	(gr_line
		(start 414.222438 -134.87146)
		(end 414.231328 -134.857998)
		(stroke
			(width 0.0635)
			(type default)
		)
		(layer "B.Cu")
	)
	(gr_line
		(start 414.231328 -134.857998)
		(end 414.234884 -134.841742)
		(stroke
			(width 0.0635)
			(type default)
		)
		(layer "B.Cu")
	)
	(gr_arc
		(start 414.290002 -128.768602)
		(mid 414.248564 -128.668562)
		(end 414.148524 -128.627124)
		(stroke
			(width 0.0635)
			(type default)
		)
		(layer "B.Cu")
	)
	(gr_arc
		(start 414.290002 -13.782802)
		(mid 414.244398 -13.672704)
		(end 414.1343 -13.6271)
		(stroke
			(width 0.0635)
			(type default)
		)
		(layer "B.Cu")
	)
	(gr_line
		(start 414.58134 -14.807184)
		(end 414.582102 -14.80439)
		(stroke
			(width 0.0635)
			(type default)
		)
		(layer "B.Cu")
	)
	(gr_arc
		(start 414.72358 -128.627124)
		(mid 414.623554 -128.668569)
		(end 414.582102 -128.768602)
		(stroke
			(width 0.0635)
			(type default)
		)
		(layer "B.Cu")
	)
	(gr_line
		(start 414.72358 -128.627124)
		(end 415.007552 -128.627124)
		(stroke
			(width 0.0635)
			(type default)
		)
		(layer "B.Cu")
	)
	(gr_arc
		(start 414.737804 -13.6271)
		(mid 414.627704 -13.672703)
		(end 414.582102 -13.782802)
		(stroke
			(width 0.0635)
			(type default)
		)
		(layer "B.Cu")
	)
	(gr_line
		(start 414.737804 -13.6271)
		(end 415.007552 -13.6271)
		(stroke
			(width 0.0635)
			(type default)
		)
		(layer "B.Cu")
	)
	(gr_line
		(start 423.746676 -33.03651)
		(end 423.760138 -33.02762)
		(stroke
			(width 0.0635)
			(type default)
		)
		(layer "B.Cu")
	)
	(gr_line
		(start 423.760138 -33.02762)
		(end 423.776394 -33.024064)
		(stroke
			(width 0.0635)
			(type default)
		)
		(layer "B.Cu")
	)
	(gr_line
		(start 427.658784 -141.379448)
		(end 427.672246 -141.370558)
		(stroke
			(width 0.0635)
			(type default)
		)
		(layer "B.Cu")
	)
	(gr_line
		(start 427.672246 -141.370558)
		(end 427.688502 -141.367002)
		(stroke
			(width 0.0635)
			(type default)
		)
		(layer "B.Cu")
	)
	(gr_line
		(start 434.826156 -236.18825)
		(end 435.435248 -236.262926)
		(stroke
			(width 0.0635)
			(type default)
		)
		(layer "B.Cu")
	)
	(gr_line
		(start 434.82895 -235.891832)
		(end 434.996336 -235.761022)
		(stroke
			(width 0.0635)
			(type default)
		)
		(layer "B.Cu")
	)
	(gr_line
		(start 434.996336 -235.761022)
		(end 435.374542 -235.80725)
		(stroke
			(width 0.0635)
			(type default)
		)
		(layer "B.Cu")
	)
	(gr_line
		(start 435.374542 -235.80725)
		(end 435.505098 -235.974636)
		(stroke
			(width 0.0635)
			(type default)
		)
		(layer "B.Cu")
	)
	(gr_line
		(start 435.887114 -236.318298)
		(end 436.49392 -236.39272)
		(stroke
			(width 0.0635)
			(type default)
		)
		(layer "B.Cu")
	)
	(gr_line
		(start 435.887876 -236.021626)
		(end 436.055262 -235.890816)
		(stroke
			(width 0.0635)
			(type default)
		)
		(layer "B.Cu")
	)
	(gr_line
		(start 436.055262 -235.890816)
		(end 436.433468 -235.937298)
		(stroke
			(width 0.0635)
			(type default)
		)
		(layer "B.Cu")
	)
	(gr_line
		(start 436.433468 -235.937298)
		(end 436.564024 -236.10443)
		(stroke
			(width 0.0635)
			(type default)
		)
		(layer "B.Cu")
	)
	(gr_line
		(start 436.945786 -236.448092)
		(end 437.552846 -236.522514)
		(stroke
			(width 0.0635)
			(type default)
		)
		(layer "B.Cu")
	)
	(gr_line
		(start 436.946802 -236.15142)
		(end 437.114188 -236.02061)
		(stroke
			(width 0.0635)
			(type default)
		)
		(layer "B.Cu")
	)
	(gr_line
		(start 437.114188 -236.02061)
		(end 437.492394 -236.067092)
		(stroke
			(width 0.0635)
			(type default)
		)
		(layer "B.Cu")
	)
	(gr_line
		(start 437.233568 -132.883402)
		(end 437.24703 -132.874512)
		(stroke
			(width 0.0635)
			(type default)
		)
		(layer "B.Cu")
	)
	(gr_line
		(start 437.24703 -132.874512)
		(end 437.263286 -132.870956)
		(stroke
			(width 0.0635)
			(type default)
		)
		(layer "B.Cu")
	)
	(gr_line
		(start 437.492394 -236.067092)
		(end 437.62295 -236.234224)
		(stroke
			(width 0.0635)
			(type default)
		)
		(layer "B.Cu")
	)
	(gr_line
		(start 438.004458 -236.577886)
		(end 438.612534 -236.652562)
		(stroke
			(width 0.0635)
			(type default)
		)
		(layer "B.Cu")
	)
	(gr_line
		(start 438.005728 -236.281214)
		(end 438.17286 -236.150404)
		(stroke
			(width 0.0635)
			(type default)
		)
		(layer "B.Cu")
	)
	(gr_line
		(start 438.17286 -236.150404)
		(end 438.551066 -236.196886)
		(stroke
			(width 0.0635)
			(type default)
		)
		(layer "B.Cu")
	)
	(gr_line
		(start 438.551066 -236.196886)
		(end 438.681876 -236.364018)
		(stroke
			(width 0.0635)
			(type default)
		)
		(layer "B.Cu")
	)
	(gr_line
		(start 444.862204 -245.027958)
		(end 444.873634 -245.032022)
		(stroke
			(width 0.0635)
			(type default)
		)
		(layer "B.Cu")
	)
	(gr_line
		(start 445.342264 -16.671544)
		(end 445.38646 -16.642842)
		(stroke
			(width 0.0635)
			(type default)
		)
		(layer "B.Cu")
	)
	(gr_line
		(start 445.38646 -16.642842)
		(end 445.407288 -16.594074)
		(stroke
			(width 0.0635)
			(type default)
		)
		(layer "B.Cu")
	)
	(gr_line
		(start 445.4144 -128.627124)
		(end 445.669924 -128.627124)
		(stroke
			(width 0.0635)
			(type default)
		)
		(layer "B.Cu")
	)
	(gr_line
		(start 445.4144 -13.6271)
		(end 445.6811 -13.6271)
		(stroke
			(width 0.0635)
			(type default)
		)
		(layer "B.Cu")
	)
	(gr_line
		(start 445.437006 -131.432554)
		(end 445.520318 -131.414774)
		(stroke
			(width 0.0635)
			(type default)
		)
		(layer "B.Cu")
	)
	(gr_arc
		(start 445.472058 -244.739922)
		(mid 445.564195 -244.701757)
		(end 445.60236 -244.60962)
		(stroke
			(width 0.0635)
			(type default)
		)
		(layer "B.Cu")
	)
	(gr_line
		(start 445.520318 -131.414774)
		(end 445.566292 -131.343908)
		(stroke
			(width 0.0635)
			(type default)
		)
		(layer "B.Cu")
	)
	(gr_arc
		(start 445.60236 -245.16842)
		(mid 445.562415 -245.071973)
		(end 445.465962 -245.032022)
		(stroke
			(width 0.0635)
			(type default)
		)
		(layer "B.Cu")
	)
	(gr_line
		(start 445.60236 -245.16842)
		(end 445.60236 -245.455694)
		(stroke
			(width 0.0635)
			(type default)
		)
		(layer "B.Cu")
	)
	(gr_line
		(start 445.60236 -244.312694)
		(end 445.60236 -244.60962)
		(stroke
			(width 0.0635)
			(type default)
		)
		(layer "B.Cu")
	)
	(gr_arc
		(start 445.83985 -128.79705)
		(mid 445.79008 -128.676894)
		(end 445.669924 -128.627124)
		(stroke
			(width 0.0635)
			(type default)
		)
		(layer "B.Cu")
	)
	(gr_arc
		(start 445.83985 -13.78585)
		(mid 445.793353 -13.673597)
		(end 445.6811 -13.6271)
		(stroke
			(width 0.0635)
			(type default)
		)
		(layer "B.Cu")
	)
	(gr_line
		(start 446.105788 -130.512312)
		(end 446.13195 -130.471926)
		(stroke
			(width 0.0635)
			(type default)
		)
		(layer "B.Cu")
	)
	(gr_arc
		(start 446.2907 -13.6271)
		(mid 446.178429 -13.673594)
		(end 446.13195 -13.78585)
		(stroke
			(width 0.0635)
			(type default)
		)
		(layer "B.Cu")
	)
	(gr_line
		(start 446.2907 -13.6271)
		(end 446.5574 -13.6271)
		(stroke
			(width 0.0635)
			(type default)
		)
		(layer "B.Cu")
	)
	(gr_arc
		(start 446.301876 -128.627124)
		(mid 446.181753 -128.676906)
		(end 446.13195 -128.79705)
		(stroke
			(width 0.0635)
			(type default)
		)
		(layer "B.Cu")
	)
	(gr_line
		(start 446.301876 -128.627124)
		(end 446.5574 -128.627124)
		(stroke
			(width 0.0635)
			(type default)
		)
		(layer "B.Cu")
	)
	(gr_line
		(start 467.399116 -24.049736)
		(end 467.423754 -24.044656)
		(stroke
			(width 0.0635)
			(type default)
		)
		(layer "B.Cu")
	)
	(gr_line
		(start 467.423754 -24.044656)
		(end 467.444074 -24.029162)
		(stroke
			(width 0.0635)
			(type default)
		)
		(layer "B.Cu")
	)
	(gr_line
		(start 471.91676 -245.028466)
		(end 471.922602 -245.030244)
		(stroke
			(width 0.0635)
			(type default)
		)
		(layer "B.Cu")
	)
	(gr_line
		(start 475.764606 -131.447032)
		(end 475.780862 -131.443476)
		(stroke
			(width 0.0635)
			(type default)
		)
		(layer "B.Cu")
	)
	(gr_line
		(start 475.780862 -131.443476)
		(end 475.794324 -131.434586)
		(stroke
			(width 0.0635)
			(type default)
		)
		(layer "B.Cu")
	)
	(gr_line
		(start 476.697802 -17.067022)
		(end 476.703644 -17.06245)
		(stroke
			(width 0.0635)
			(type default)
		)
		(layer "B.Cu")
	)
	(gr_line
		(start 476.703644 -17.06245)
		(end 476.707454 -17.057116)
		(stroke
			(width 0.0635)
			(type default)
		)
		(layer "B.Cu")
	)
	(gr_line
		(start 476.964502 -128.627124)
		(end 477.242124 -128.627124)
		(stroke
			(width 0.0635)
			(type default)
		)
		(layer "B.Cu")
	)
	(gr_line
		(start 476.964502 -13.6271)
		(end 477.2279 -13.6271)
		(stroke
			(width 0.0635)
			(type default)
		)
		(layer "B.Cu")
	)
	(gr_arc
		(start 476.985584 -244.738144)
		(mid 477.103585 -244.689267)
		(end 477.152462 -244.571266)
		(stroke
			(width 0.0635)
			(type default)
		)
		(layer "B.Cu")
	)
	(gr_arc
		(start 477.152462 -245.197122)
		(mid 477.103591 -245.079113)
		(end 476.985584 -245.030244)
		(stroke
			(width 0.0635)
			(type default)
		)
		(layer "B.Cu")
	)
	(gr_line
		(start 477.152462 -245.197122)
		(end 477.152462 -245.455694)
		(stroke
			(width 0.0635)
			(type default)
		)
		(layer "B.Cu")
	)
	(gr_line
		(start 477.152462 -244.312694)
		(end 477.152462 -244.571266)
		(stroke
			(width 0.0635)
			(type default)
		)
		(layer "B.Cu")
	)
	(gr_line
		(start 477.192086 -130.527298)
		(end 477.212152 -130.51409)
		(stroke
			(width 0.0635)
			(type default)
		)
		(layer "B.Cu")
	)
	(gr_line
		(start 477.212152 -130.51409)
		(end 477.224852 -130.494532)
		(stroke
			(width 0.0635)
			(type default)
		)
		(layer "B.Cu")
	)
	(gr_arc
		(start 477.389952 -128.774952)
		(mid 477.346654 -128.670422)
		(end 477.242124 -128.627124)
		(stroke
			(width 0.0635)
			(type default)
		)
		(layer "B.Cu")
	)
	(gr_arc
		(start 477.389952 -13.789152)
		(mid 477.342488 -13.674564)
		(end 477.2279 -13.6271)
		(stroke
			(width 0.0635)
			(type default)
		)
		(layer "B.Cu")
	)
	(gr_line
		(start 477.64827 -15.769082)
		(end 477.682052 -15.7226)
		(stroke
			(width 0.0635)
			(type default)
		)
		(layer "B.Cu")
	)
	(gr_line
		(start 477.65589 -129.831592)
		(end 477.682052 -129.791206)
		(stroke
			(width 0.0635)
			(type default)
		)
		(layer "B.Cu")
	)
	(gr_arc
		(start 477.82988 -128.627124)
		(mid 477.725346 -128.670426)
		(end 477.682052 -128.774952)
		(stroke
			(width 0.0635)
			(type default)
		)
		(layer "B.Cu")
	)
	(gr_line
		(start 477.82988 -128.627124)
		(end 478.107502 -128.627124)
		(stroke
			(width 0.0635)
			(type default)
		)
		(layer "B.Cu")
	)
	(gr_arc
		(start 477.8375 -13.6271)
		(mid 477.727599 -13.672633)
		(end 477.682052 -13.782548)
		(stroke
			(width 0.0635)
			(type default)
		)
		(layer "B.Cu")
	)
	(gr_line
		(start 477.8375 -13.6271)
		(end 478.107502 -13.6271)
		(stroke
			(width 0.0635)
			(type default)
		)
		(layer "B.Cu")
	)
	(gr_line
		(start 0 -370.000022)
		(end 0 -0.999998)
		(stroke
			(width 1.524)
			(type default)
		)
		(layer "In1.Cu")
	)
	(gr_arc
		(start 0 -370.000022)
		(mid 0.292893 -370.707127)
		(end 0.999998 -371.00002)
		(stroke
			(width 1.524)
			(type default)
		)
		(layer "In1.Cu")
	)
	(gr_arc
		(start 0.999998 0)
		(mid 0.292893 -0.292893)
		(end 0 -0.999998)
		(stroke
			(width 1.524)
			(type default)
		)
		(layer "In1.Cu")
	)
	(gr_line
		(start 0.999998 0)
		(end 198.000112 0)
		(stroke
			(width 1.524)
			(type default)
		)
		(layer "In1.Cu")
	)
	(gr_line
		(start 1.999996 -371.00002)
		(end 0.999998 -371.00002)
		(stroke
			(width 1.524)
			(type default)
		)
		(layer "In1.Cu")
	)
	(gr_line
		(start 2.999994 -384.999992)
		(end 2.999994 -372.000018)
		(stroke
			(width 1.524)
			(type default)
		)
		(layer "In1.Cu")
	)
	(gr_arc
		(start 2.999994 -384.999992)
		(mid 3.292883 -385.707105)
		(end 3.999992 -385.99999)
		(stroke
			(width 1.524)
			(type default)
		)
		(layer "In1.Cu")
	)
	(gr_arc
		(start 2.999994 -372.000018)
		(mid 2.707101 -371.292913)
		(end 1.999996 -371.00002)
		(stroke
			(width 1.524)
			(type default)
		)
		(layer "In1.Cu")
	)
	(gr_line
		(start 15.249906 -385.99999)
		(end 3.999992 -385.99999)
		(stroke
			(width 1.524)
			(type default)
		)
		(layer "In1.Cu")
	)
	(gr_arc
		(start 15.249906 -385.99999)
		(mid 15.957005 -385.707095)
		(end 16.249904 -384.999992)
		(stroke
			(width 1.524)
			(type default)
		)
		(layer "In1.Cu")
	)
	(gr_line
		(start 16.249904 -383.29997)
		(end 16.249904 -384.999992)
		(stroke
			(width 1.524)
			(type default)
		)
		(layer "In1.Cu")
	)
	(gr_arc
		(start 17.249902 -382.299972)
		(mid 16.542797 -382.592865)
		(end 16.249904 -383.29997)
		(stroke
			(width 1.524)
			(type default)
		)
		(layer "In1.Cu")
	)
	(gr_line
		(start 23.750016 -382.299972)
		(end 17.249902 -382.299972)
		(stroke
			(width 1.524)
			(type default)
		)
		(layer "In1.Cu")
	)
	(gr_line
		(start 24.750014 -384.999992)
		(end 24.750014 -383.29997)
		(stroke
			(width 1.524)
			(type default)
		)
		(layer "In1.Cu")
	)
	(gr_arc
		(start 24.750014 -384.999992)
		(mid 25.042905 -385.707098)
		(end 25.750012 -385.99999)
		(stroke
			(width 1.524)
			(type default)
		)
		(layer "In1.Cu")
	)
	(gr_arc
		(start 24.750014 -383.29997)
		(mid 24.457121 -382.592865)
		(end 23.750016 -382.299972)
		(stroke
			(width 1.524)
			(type default)
		)
		(layer "In1.Cu")
	)
	(gr_line
		(start 28.843986 -250.350274)
		(end 28.843986 -247.149874)
		(stroke
			(width 0.2)
			(type default)
		)
		(layer "In1.Cu")
	)
	(gr_line
		(start 28.843986 -247.149874)
		(end 31.206186 -247.149874)
		(stroke
			(width 0.2)
			(type default)
		)
		(layer "In1.Cu")
	)
	(gr_line
		(start 28.843986 -246.540274)
		(end 28.843986 -243.339874)
		(stroke
			(width 0.2)
			(type default)
		)
		(layer "In1.Cu")
	)
	(gr_line
		(start 28.843986 -243.339874)
		(end 31.206186 -243.339874)
		(stroke
			(width 0.2)
			(type default)
		)
		(layer "In1.Cu")
	)
	(gr_line
		(start 28.843986 -135.35025)
		(end 28.843986 -132.14985)
		(stroke
			(width 0.2)
			(type default)
		)
		(layer "In1.Cu")
	)
	(gr_line
		(start 28.843986 -132.14985)
		(end 31.206186 -132.14985)
		(stroke
			(width 0.2)
			(type default)
		)
		(layer "In1.Cu")
	)
	(gr_line
		(start 28.843986 -131.54025)
		(end 28.843986 -128.33985)
		(stroke
			(width 0.2)
			(type default)
		)
		(layer "In1.Cu")
	)
	(gr_line
		(start 28.843986 -128.33985)
		(end 31.206186 -128.33985)
		(stroke
			(width 0.2)
			(type default)
		)
		(layer "In1.Cu")
	)
	(gr_line
		(start 28.843986 -20.350226)
		(end 28.843986 -17.149826)
		(stroke
			(width 0.2)
			(type default)
		)
		(layer "In1.Cu")
	)
	(gr_line
		(start 28.843986 -17.149826)
		(end 31.206186 -17.149826)
		(stroke
			(width 0.2)
			(type default)
		)
		(layer "In1.Cu")
	)
	(gr_line
		(start 28.843986 -16.540226)
		(end 28.843986 -13.339826)
		(stroke
			(width 0.2)
			(type default)
		)
		(layer "In1.Cu")
	)
	(gr_line
		(start 28.843986 -13.339826)
		(end 31.206186 -13.339826)
		(stroke
			(width 0.2)
			(type default)
		)
		(layer "In1.Cu")
	)
	(gr_line
		(start 31.206186 -250.350274)
		(end 28.843986 -250.350274)
		(stroke
			(width 0.2)
			(type default)
		)
		(layer "In1.Cu")
	)
	(gr_line
		(start 31.206186 -247.149874)
		(end 31.206186 -250.350274)
		(stroke
			(width 0.2)
			(type default)
		)
		(layer "In1.Cu")
	)
	(gr_line
		(start 31.206186 -246.540274)
		(end 28.843986 -246.540274)
		(stroke
			(width 0.2)
			(type default)
		)
		(layer "In1.Cu")
	)
	(gr_line
		(start 31.206186 -243.339874)
		(end 31.206186 -246.540274)
		(stroke
			(width 0.2)
			(type default)
		)
		(layer "In1.Cu")
	)
	(gr_line
		(start 31.206186 -135.35025)
		(end 28.843986 -135.35025)
		(stroke
			(width 0.2)
			(type default)
		)
		(layer "In1.Cu")
	)
	(gr_line
		(start 31.206186 -132.14985)
		(end 31.206186 -135.35025)
		(stroke
			(width 0.2)
			(type default)
		)
		(layer "In1.Cu")
	)
	(gr_line
		(start 31.206186 -131.54025)
		(end 28.843986 -131.54025)
		(stroke
			(width 0.2)
			(type default)
		)
		(layer "In1.Cu")
	)
	(gr_line
		(start 31.206186 -128.33985)
		(end 31.206186 -131.54025)
		(stroke
			(width 0.2)
			(type default)
		)
		(layer "In1.Cu")
	)
	(gr_line
		(start 31.206186 -20.350226)
		(end 28.843986 -20.350226)
		(stroke
			(width 0.2)
			(type default)
		)
		(layer "In1.Cu")
	)
	(gr_line
		(start 31.206186 -17.149826)
		(end 31.206186 -20.350226)
		(stroke
			(width 0.2)
			(type default)
		)
		(layer "In1.Cu")
	)
	(gr_line
		(start 31.206186 -16.540226)
		(end 28.843986 -16.540226)
		(stroke
			(width 0.2)
			(type default)
		)
		(layer "In1.Cu")
	)
	(gr_line
		(start 31.206186 -13.339826)
		(end 31.206186 -16.540226)
		(stroke
			(width 0.2)
			(type default)
		)
		(layer "In1.Cu")
	)
	(gr_arc
		(start 32.006286 -245.321074)
		(mid 32.021165 -245.356995)
		(end 32.057086 -245.371874)
		(stroke
			(width 0.2)
			(type default)
		)
		(layer "In1.Cu")
	)
	(gr_line
		(start 32.006286 -245.117874)
		(end 32.006286 -245.321074)
		(stroke
			(width 0.2)
			(type default)
		)
		(layer "In1.Cu")
	)
	(gr_arc
		(start 32.006286 -244.762274)
		(mid 32.021165 -244.798195)
		(end 32.057086 -244.813074)
		(stroke
			(width 0.2)
			(type default)
		)
		(layer "In1.Cu")
	)
	(gr_line
		(start 32.006286 -244.559074)
		(end 32.006286 -244.762274)
		(stroke
			(width 0.2)
			(type default)
		)
		(layer "In1.Cu")
	)
	(gr_arc
		(start 32.006286 -130.32105)
		(mid 32.021165 -130.356971)
		(end 32.057086 -130.37185)
		(stroke
			(width 0.2)
			(type default)
		)
		(layer "In1.Cu")
	)
	(gr_line
		(start 32.006286 -130.11785)
		(end 32.006286 -130.32105)
		(stroke
			(width 0.2)
			(type default)
		)
		(layer "In1.Cu")
	)
	(gr_arc
		(start 32.006286 -129.76225)
		(mid 32.021165 -129.798171)
		(end 32.057086 -129.81305)
		(stroke
			(width 0.2)
			(type default)
		)
		(layer "In1.Cu")
	)
	(gr_line
		(start 32.006286 -129.55905)
		(end 32.006286 -129.76225)
		(stroke
			(width 0.2)
			(type default)
		)
		(layer "In1.Cu")
	)
	(gr_arc
		(start 32.006286 -15.321026)
		(mid 32.021165 -15.356947)
		(end 32.057086 -15.371826)
		(stroke
			(width 0.2)
			(type default)
		)
		(layer "In1.Cu")
	)
	(gr_line
		(start 32.006286 -15.117826)
		(end 32.006286 -15.321026)
		(stroke
			(width 0.2)
			(type default)
		)
		(layer "In1.Cu")
	)
	(gr_arc
		(start 32.006286 -14.762226)
		(mid 32.021165 -14.798147)
		(end 32.057086 -14.813026)
		(stroke
			(width 0.2)
			(type default)
		)
		(layer "In1.Cu")
	)
	(gr_line
		(start 32.006286 -14.559026)
		(end 32.006286 -14.762226)
		(stroke
			(width 0.2)
			(type default)
		)
		(layer "In1.Cu")
	)
	(gr_arc
		(start 32.023812 -249.385074)
		(mid 32.508952 -249.870214)
		(end 32.994092 -249.385074)
		(stroke
			(width 0.2)
			(type default)
		)
		(layer "In1.Cu")
	)
	(gr_line
		(start 32.023812 -248.115074)
		(end 32.023812 -249.385074)
		(stroke
			(width 0.2)
			(type default)
		)
		(layer "In1.Cu")
	)
	(gr_arc
		(start 32.023812 -134.384796)
		(mid 32.508825 -134.87019)
		(end 32.994092 -134.38505)
		(stroke
			(width 0.2)
			(type default)
		)
		(layer "In1.Cu")
	)
	(gr_line
		(start 32.023812 -133.11505)
		(end 32.023812 -134.384796)
		(stroke
			(width 0.2)
			(type default)
		)
		(layer "In1.Cu")
	)
	(gr_arc
		(start 32.023812 -19.385026)
		(mid 32.508952 -19.870166)
		(end 32.994092 -19.385026)
		(stroke
			(width 0.2)
			(type default)
		)
		(layer "In1.Cu")
	)
	(gr_line
		(start 32.023812 -18.115026)
		(end 32.023812 -19.385026)
		(stroke
			(width 0.2)
			(type default)
		)
		(layer "In1.Cu")
	)
	(gr_line
		(start 32.057086 -245.371874)
		(end 32.869886 -245.371874)
		(stroke
			(width 0.2)
			(type default)
		)
		(layer "In1.Cu")
	)
	(gr_arc
		(start 32.057086 -245.067074)
		(mid 32.021165 -245.081953)
		(end 32.006286 -245.117874)
		(stroke
			(width 0.2)
			(type default)
		)
		(layer "In1.Cu")
	)
	(gr_line
		(start 32.057086 -244.813074)
		(end 32.869886 -244.813074)
		(stroke
			(width 0.2)
			(type default)
		)
		(layer "In1.Cu")
	)
	(gr_arc
		(start 32.057086 -244.508274)
		(mid 32.021165 -244.523153)
		(end 32.006286 -244.559074)
		(stroke
			(width 0.2)
			(type default)
		)
		(layer "In1.Cu")
	)
	(gr_line
		(start 32.057086 -130.37185)
		(end 32.869886 -130.37185)
		(stroke
			(width 0.2)
			(type default)
		)
		(layer "In1.Cu")
	)
	(gr_arc
		(start 32.057086 -130.06705)
		(mid 32.021165 -130.081929)
		(end 32.006286 -130.11785)
		(stroke
			(width 0.2)
			(type default)
		)
		(layer "In1.Cu")
	)
	(gr_line
		(start 32.057086 -129.81305)
		(end 32.869886 -129.81305)
		(stroke
			(width 0.2)
			(type default)
		)
		(layer "In1.Cu")
	)
	(gr_arc
		(start 32.057086 -129.50825)
		(mid 32.021165 -129.523129)
		(end 32.006286 -129.55905)
		(stroke
			(width 0.2)
			(type default)
		)
		(layer "In1.Cu")
	)
	(gr_line
		(start 32.057086 -15.371826)
		(end 32.869886 -15.371826)
		(stroke
			(width 0.2)
			(type default)
		)
		(layer "In1.Cu")
	)
	(gr_arc
		(start 32.057086 -15.067026)
		(mid 32.021165 -15.081905)
		(end 32.006286 -15.117826)
		(stroke
			(width 0.2)
			(type default)
		)
		(layer "In1.Cu")
	)
	(gr_line
		(start 32.057086 -14.813026)
		(end 32.869886 -14.813026)
		(stroke
			(width 0.2)
			(type default)
		)
		(layer "In1.Cu")
	)
	(gr_arc
		(start 32.057086 -14.508226)
		(mid 32.021165 -14.523105)
		(end 32.006286 -14.559026)
		(stroke
			(width 0.2)
			(type default)
		)
		(layer "In1.Cu")
	)
	(gr_arc
		(start 32.869886 -245.371874)
		(mid 32.905807 -245.356995)
		(end 32.920686 -245.321074)
		(stroke
			(width 0.2)
			(type default)
		)
		(layer "In1.Cu")
	)
	(gr_line
		(start 32.869886 -245.067074)
		(end 32.057086 -245.067074)
		(stroke
			(width 0.2)
			(type default)
		)
		(layer "In1.Cu")
	)
	(gr_arc
		(start 32.869886 -244.813074)
		(mid 32.905807 -244.798195)
		(end 32.920686 -244.762274)
		(stroke
			(width 0.2)
			(type default)
		)
		(layer "In1.Cu")
	)
	(gr_line
		(start 32.869886 -244.508274)
		(end 32.057086 -244.508274)
		(stroke
			(width 0.2)
			(type default)
		)
		(layer "In1.Cu")
	)
	(gr_arc
		(start 32.869886 -130.37185)
		(mid 32.905807 -130.356971)
		(end 32.920686 -130.32105)
		(stroke
			(width 0.2)
			(type default)
		)
		(layer "In1.Cu")
	)
	(gr_line
		(start 32.869886 -130.06705)
		(end 32.057086 -130.06705)
		(stroke
			(width 0.2)
			(type default)
		)
		(layer "In1.Cu")
	)
	(gr_arc
		(start 32.869886 -129.81305)
		(mid 32.905807 -129.798171)
		(end 32.920686 -129.76225)
		(stroke
			(width 0.2)
			(type default)
		)
		(layer "In1.Cu")
	)
	(gr_line
		(start 32.869886 -129.50825)
		(end 32.057086 -129.50825)
		(stroke
			(width 0.2)
			(type default)
		)
		(layer "In1.Cu")
	)
	(gr_arc
		(start 32.869886 -15.371826)
		(mid 32.905807 -15.356947)
		(end 32.920686 -15.321026)
		(stroke
			(width 0.2)
			(type default)
		)
		(layer "In1.Cu")
	)
	(gr_line
		(start 32.869886 -15.067026)
		(end 32.057086 -15.067026)
		(stroke
			(width 0.2)
			(type default)
		)
		(layer "In1.Cu")
	)
	(gr_arc
		(start 32.869886 -14.813026)
		(mid 32.905807 -14.798147)
		(end 32.920686 -14.762226)
		(stroke
			(width 0.2)
			(type default)
		)
		(layer "In1.Cu")
	)
	(gr_line
		(start 32.869886 -14.508226)
		(end 32.057086 -14.508226)
		(stroke
			(width 0.2)
			(type default)
		)
		(layer "In1.Cu")
	)
	(gr_line
		(start 32.920686 -245.321074)
		(end 32.920686 -245.117874)
		(stroke
			(width 0.2)
			(type default)
		)
		(layer "In1.Cu")
	)
	(gr_arc
		(start 32.920686 -245.117874)
		(mid 32.905807 -245.081953)
		(end 32.869886 -245.067074)
		(stroke
			(width 0.2)
			(type default)
		)
		(layer "In1.Cu")
	)
	(gr_line
		(start 32.920686 -244.762274)
		(end 32.920686 -244.559074)
		(stroke
			(width 0.2)
			(type default)
		)
		(layer "In1.Cu")
	)
	(gr_arc
		(start 32.920686 -244.559074)
		(mid 32.905807 -244.523153)
		(end 32.869886 -244.508274)
		(stroke
			(width 0.2)
			(type default)
		)
		(layer "In1.Cu")
	)
	(gr_line
		(start 32.920686 -130.32105)
		(end 32.920686 -130.11785)
		(stroke
			(width 0.2)
			(type default)
		)
		(layer "In1.Cu")
	)
	(gr_arc
		(start 32.920686 -130.11785)
		(mid 32.905807 -130.081929)
		(end 32.869886 -130.06705)
		(stroke
			(width 0.2)
			(type default)
		)
		(layer "In1.Cu")
	)
	(gr_line
		(start 32.920686 -129.76225)
		(end 32.920686 -129.55905)
		(stroke
			(width 0.2)
			(type default)
		)
		(layer "In1.Cu")
	)
	(gr_arc
		(start 32.920686 -129.55905)
		(mid 32.905807 -129.523129)
		(end 32.869886 -129.50825)
		(stroke
			(width 0.2)
			(type default)
		)
		(layer "In1.Cu")
	)
	(gr_line
		(start 32.920686 -15.321026)
		(end 32.920686 -15.117826)
		(stroke
			(width 0.2)
			(type default)
		)
		(layer "In1.Cu")
	)
	(gr_arc
		(start 32.920686 -15.117826)
		(mid 32.905807 -15.081905)
		(end 32.869886 -15.067026)
		(stroke
			(width 0.2)
			(type default)
		)
		(layer "In1.Cu")
	)
	(gr_line
		(start 32.920686 -14.762226)
		(end 32.920686 -14.559026)
		(stroke
			(width 0.2)
			(type default)
		)
		(layer "In1.Cu")
	)
	(gr_arc
		(start 32.920686 -14.559026)
		(mid 32.905807 -14.523105)
		(end 32.869886 -14.508226)
		(stroke
			(width 0.2)
			(type default)
		)
		(layer "In1.Cu")
	)
	(gr_line
		(start 32.994092 -249.385074)
		(end 32.994092 -248.115328)
		(stroke
			(width 0.2)
			(type default)
		)
		(layer "In1.Cu")
	)
	(gr_arc
		(start 32.994092 -248.115328)
		(mid 32.509079 -247.629934)
		(end 32.023812 -248.115074)
		(stroke
			(width 0.2)
			(type default)
		)
		(layer "In1.Cu")
	)
	(gr_line
		(start 32.994092 -134.38505)
		(end 32.994092 -133.11505)
		(stroke
			(width 0.2)
			(type default)
		)
		(layer "In1.Cu")
	)
	(gr_arc
		(start 32.994092 -133.11505)
		(mid 32.508952 -132.62991)
		(end 32.023812 -133.11505)
		(stroke
			(width 0.2)
			(type default)
		)
		(layer "In1.Cu")
	)
	(gr_line
		(start 32.994092 -19.385026)
		(end 32.994092 -18.11528)
		(stroke
			(width 0.2)
			(type default)
		)
		(layer "In1.Cu")
	)
	(gr_arc
		(start 32.994092 -18.11528)
		(mid 32.509079 -17.629886)
		(end 32.023812 -18.115026)
		(stroke
			(width 0.2)
			(type default)
		)
		(layer "In1.Cu")
	)
	(gr_arc
		(start 33.800542 -245.56212)
		(mid 34.285555 -246.047514)
		(end 34.770822 -245.562374)
		(stroke
			(width 0.2)
			(type default)
		)
		(layer "In1.Cu")
	)
	(gr_line
		(start 33.800542 -244.419374)
		(end 33.800542 -245.56212)
		(stroke
			(width 0.2)
			(type default)
		)
		(layer "In1.Cu")
	)
	(gr_arc
		(start 33.800542 -130.56235)
		(mid 34.285682 -131.04749)
		(end 34.770822 -130.56235)
		(stroke
			(width 0.2)
			(type default)
		)
		(layer "In1.Cu")
	)
	(gr_line
		(start 33.800542 -129.41935)
		(end 33.800542 -130.56235)
		(stroke
			(width 0.2)
			(type default)
		)
		(layer "In1.Cu")
	)
	(gr_arc
		(start 33.800542 -15.562326)
		(mid 34.285682 -16.047466)
		(end 34.770822 -15.562326)
		(stroke
			(width 0.2)
			(type default)
		)
		(layer "In1.Cu")
	)
	(gr_line
		(start 33.800542 -14.419326)
		(end 33.800542 -15.562326)
		(stroke
			(width 0.2)
			(type default)
		)
		(layer "In1.Cu")
	)
	(gr_line
		(start 34.770822 -245.562374)
		(end 34.770822 -244.419374)
		(stroke
			(width 0.2)
			(type default)
		)
		(layer "In1.Cu")
	)
	(gr_arc
		(start 34.770822 -244.419374)
		(mid 34.285682 -243.934234)
		(end 33.800542 -244.419374)
		(stroke
			(width 0.2)
			(type default)
		)
		(layer "In1.Cu")
	)
	(gr_line
		(start 34.770822 -130.56235)
		(end 34.770822 -129.419604)
		(stroke
			(width 0.2)
			(type default)
		)
		(layer "In1.Cu")
	)
	(gr_arc
		(start 34.770822 -129.419604)
		(mid 34.285809 -128.93421)
		(end 33.800542 -129.41935)
		(stroke
			(width 0.2)
			(type default)
		)
		(layer "In1.Cu")
	)
	(gr_line
		(start 34.770822 -15.562326)
		(end 34.770822 -14.41958)
		(stroke
			(width 0.2)
			(type default)
		)
		(layer "In1.Cu")
	)
	(gr_arc
		(start 34.770822 -14.41958)
		(mid 34.285809 -13.934186)
		(end 33.800542 -14.419326)
		(stroke
			(width 0.2)
			(type default)
		)
		(layer "In1.Cu")
	)
	(gr_line
		(start 60.393834 -250.350274)
		(end 60.393834 -247.149874)
		(stroke
			(width 0.2)
			(type default)
		)
		(layer "In1.Cu")
	)
	(gr_line
		(start 60.393834 -247.149874)
		(end 62.756034 -247.149874)
		(stroke
			(width 0.2)
			(type default)
		)
		(layer "In1.Cu")
	)
	(gr_line
		(start 60.393834 -246.540274)
		(end 60.393834 -243.339874)
		(stroke
			(width 0.2)
			(type default)
		)
		(layer "In1.Cu")
	)
	(gr_line
		(start 60.393834 -243.339874)
		(end 62.756034 -243.339874)
		(stroke
			(width 0.2)
			(type default)
		)
		(layer "In1.Cu")
	)
	(gr_line
		(start 60.393834 -135.35025)
		(end 60.393834 -132.14985)
		(stroke
			(width 0.2)
			(type default)
		)
		(layer "In1.Cu")
	)
	(gr_line
		(start 60.393834 -132.14985)
		(end 62.756034 -132.14985)
		(stroke
			(width 0.2)
			(type default)
		)
		(layer "In1.Cu")
	)
	(gr_line
		(start 60.393834 -131.54025)
		(end 60.393834 -128.33985)
		(stroke
			(width 0.2)
			(type default)
		)
		(layer "In1.Cu")
	)
	(gr_line
		(start 60.393834 -128.33985)
		(end 62.756034 -128.33985)
		(stroke
			(width 0.2)
			(type default)
		)
		(layer "In1.Cu")
	)
	(gr_line
		(start 60.393834 -20.350226)
		(end 60.393834 -17.149826)
		(stroke
			(width 0.2)
			(type default)
		)
		(layer "In1.Cu")
	)
	(gr_line
		(start 60.393834 -17.149826)
		(end 62.756034 -17.149826)
		(stroke
			(width 0.2)
			(type default)
		)
		(layer "In1.Cu")
	)
	(gr_line
		(start 60.393834 -16.540226)
		(end 60.393834 -13.339826)
		(stroke
			(width 0.2)
			(type default)
		)
		(layer "In1.Cu")
	)
	(gr_line
		(start 60.393834 -13.339826)
		(end 62.756034 -13.339826)
		(stroke
			(width 0.2)
			(type default)
		)
		(layer "In1.Cu")
	)
	(gr_line
		(start 62.756034 -250.350274)
		(end 60.393834 -250.350274)
		(stroke
			(width 0.2)
			(type default)
		)
		(layer "In1.Cu")
	)
	(gr_line
		(start 62.756034 -247.149874)
		(end 62.756034 -250.350274)
		(stroke
			(width 0.2)
			(type default)
		)
		(layer "In1.Cu")
	)
	(gr_line
		(start 62.756034 -246.540274)
		(end 60.393834 -246.540274)
		(stroke
			(width 0.2)
			(type default)
		)
		(layer "In1.Cu")
	)
	(gr_line
		(start 62.756034 -243.339874)
		(end 62.756034 -246.540274)
		(stroke
			(width 0.2)
			(type default)
		)
		(layer "In1.Cu")
	)
	(gr_line
		(start 62.756034 -135.35025)
		(end 60.393834 -135.35025)
		(stroke
			(width 0.2)
			(type default)
		)
		(layer "In1.Cu")
	)
	(gr_line
		(start 62.756034 -132.14985)
		(end 62.756034 -135.35025)
		(stroke
			(width 0.2)
			(type default)
		)
		(layer "In1.Cu")
	)
	(gr_line
		(start 62.756034 -131.54025)
		(end 60.393834 -131.54025)
		(stroke
			(width 0.2)
			(type default)
		)
		(layer "In1.Cu")
	)
	(gr_line
		(start 62.756034 -128.33985)
		(end 62.756034 -131.54025)
		(stroke
			(width 0.2)
			(type default)
		)
		(layer "In1.Cu")
	)
	(gr_line
		(start 62.756034 -20.350226)
		(end 60.393834 -20.350226)
		(stroke
			(width 0.2)
			(type default)
		)
		(layer "In1.Cu")
	)
	(gr_line
		(start 62.756034 -17.149826)
		(end 62.756034 -20.350226)
		(stroke
			(width 0.2)
			(type default)
		)
		(layer "In1.Cu")
	)
	(gr_line
		(start 62.756034 -16.540226)
		(end 60.393834 -16.540226)
		(stroke
			(width 0.2)
			(type default)
		)
		(layer "In1.Cu")
	)
	(gr_line
		(start 62.756034 -13.339826)
		(end 62.756034 -16.540226)
		(stroke
			(width 0.2)
			(type default)
		)
		(layer "In1.Cu")
	)
	(gr_arc
		(start 63.556134 -245.321074)
		(mid 63.571013 -245.356995)
		(end 63.606934 -245.371874)
		(stroke
			(width 0.2)
			(type default)
		)
		(layer "In1.Cu")
	)
	(gr_line
		(start 63.556134 -245.117874)
		(end 63.556134 -245.321074)
		(stroke
			(width 0.2)
			(type default)
		)
		(layer "In1.Cu")
	)
	(gr_arc
		(start 63.556134 -244.762274)
		(mid 63.571013 -244.798195)
		(end 63.606934 -244.813074)
		(stroke
			(width 0.2)
			(type default)
		)
		(layer "In1.Cu")
	)
	(gr_line
		(start 63.556134 -244.559074)
		(end 63.556134 -244.762274)
		(stroke
			(width 0.2)
			(type default)
		)
		(layer "In1.Cu")
	)
	(gr_arc
		(start 63.556134 -130.32105)
		(mid 63.571013 -130.356971)
		(end 63.606934 -130.37185)
		(stroke
			(width 0.2)
			(type default)
		)
		(layer "In1.Cu")
	)
	(gr_line
		(start 63.556134 -130.11785)
		(end 63.556134 -130.32105)
		(stroke
			(width 0.2)
			(type default)
		)
		(layer "In1.Cu")
	)
	(gr_arc
		(start 63.556134 -129.76225)
		(mid 63.571013 -129.798171)
		(end 63.606934 -129.81305)
		(stroke
			(width 0.2)
			(type default)
		)
		(layer "In1.Cu")
	)
	(gr_line
		(start 63.556134 -129.55905)
		(end 63.556134 -129.76225)
		(stroke
			(width 0.2)
			(type default)
		)
		(layer "In1.Cu")
	)
	(gr_arc
		(start 63.556134 -15.321026)
		(mid 63.571013 -15.356947)
		(end 63.606934 -15.371826)
		(stroke
			(width 0.2)
			(type default)
		)
		(layer "In1.Cu")
	)
	(gr_line
		(start 63.556134 -15.117826)
		(end 63.556134 -15.321026)
		(stroke
			(width 0.2)
			(type default)
		)
		(layer "In1.Cu")
	)
	(gr_arc
		(start 63.556134 -14.762226)
		(mid 63.571013 -14.798147)
		(end 63.606934 -14.813026)
		(stroke
			(width 0.2)
			(type default)
		)
		(layer "In1.Cu")
	)
	(gr_line
		(start 63.556134 -14.559026)
		(end 63.556134 -14.762226)
		(stroke
			(width 0.2)
			(type default)
		)
		(layer "In1.Cu")
	)
	(gr_arc
		(start 63.57366 -249.385074)
		(mid 64.0588 -249.870214)
		(end 64.54394 -249.385074)
		(stroke
			(width 0.2)
			(type default)
		)
		(layer "In1.Cu")
	)
	(gr_line
		(start 63.57366 -248.115074)
		(end 63.57366 -249.385074)
		(stroke
			(width 0.2)
			(type default)
		)
		(layer "In1.Cu")
	)
	(gr_arc
		(start 63.57366 -134.384796)
		(mid 64.058673 -134.87019)
		(end 64.54394 -134.38505)
		(stroke
			(width 0.2)
			(type default)
		)
		(layer "In1.Cu")
	)
	(gr_line
		(start 63.57366 -133.11505)
		(end 63.57366 -134.384796)
		(stroke
			(width 0.2)
			(type default)
		)
		(layer "In1.Cu")
	)
	(gr_arc
		(start 63.57366 -19.385026)
		(mid 64.0588 -19.870166)
		(end 64.54394 -19.385026)
		(stroke
			(width 0.2)
			(type default)
		)
		(layer "In1.Cu")
	)
	(gr_line
		(start 63.57366 -18.115026)
		(end 63.57366 -19.385026)
		(stroke
			(width 0.2)
			(type default)
		)
		(layer "In1.Cu")
	)
	(gr_line
		(start 63.606934 -245.371874)
		(end 64.419734 -245.371874)
		(stroke
			(width 0.2)
			(type default)
		)
		(layer "In1.Cu")
	)
	(gr_arc
		(start 63.606934 -245.067074)
		(mid 63.571013 -245.081953)
		(end 63.556134 -245.117874)
		(stroke
			(width 0.2)
			(type default)
		)
		(layer "In1.Cu")
	)
	(gr_line
		(start 63.606934 -244.813074)
		(end 64.419734 -244.813074)
		(stroke
			(width 0.2)
			(type default)
		)
		(layer "In1.Cu")
	)
	(gr_arc
		(start 63.606934 -244.508274)
		(mid 63.571013 -244.523153)
		(end 63.556134 -244.559074)
		(stroke
			(width 0.2)
			(type default)
		)
		(layer "In1.Cu")
	)
	(gr_line
		(start 63.606934 -130.37185)
		(end 64.419734 -130.37185)
		(stroke
			(width 0.2)
			(type default)
		)
		(layer "In1.Cu")
	)
	(gr_arc
		(start 63.606934 -130.06705)
		(mid 63.571013 -130.081929)
		(end 63.556134 -130.11785)
		(stroke
			(width 0.2)
			(type default)
		)
		(layer "In1.Cu")
	)
	(gr_line
		(start 63.606934 -129.81305)
		(end 64.419734 -129.81305)
		(stroke
			(width 0.2)
			(type default)
		)
		(layer "In1.Cu")
	)
	(gr_arc
		(start 63.606934 -129.50825)
		(mid 63.571013 -129.523129)
		(end 63.556134 -129.55905)
		(stroke
			(width 0.2)
			(type default)
		)
		(layer "In1.Cu")
	)
	(gr_line
		(start 63.606934 -15.371826)
		(end 64.419734 -15.371826)
		(stroke
			(width 0.2)
			(type default)
		)
		(layer "In1.Cu")
	)
	(gr_arc
		(start 63.606934 -15.067026)
		(mid 63.571013 -15.081905)
		(end 63.556134 -15.117826)
		(stroke
			(width 0.2)
			(type default)
		)
		(layer "In1.Cu")
	)
	(gr_line
		(start 63.606934 -14.813026)
		(end 64.419734 -14.813026)
		(stroke
			(width 0.2)
			(type default)
		)
		(layer "In1.Cu")
	)
	(gr_arc
		(start 63.606934 -14.508226)
		(mid 63.571013 -14.523105)
		(end 63.556134 -14.559026)
		(stroke
			(width 0.2)
			(type default)
		)
		(layer "In1.Cu")
	)
	(gr_arc
		(start 64.419734 -245.371874)
		(mid 64.455655 -245.356995)
		(end 64.470534 -245.321074)
		(stroke
			(width 0.2)
			(type default)
		)
		(layer "In1.Cu")
	)
	(gr_line
		(start 64.419734 -245.067074)
		(end 63.606934 -245.067074)
		(stroke
			(width 0.2)
			(type default)
		)
		(layer "In1.Cu")
	)
	(gr_arc
		(start 64.419734 -244.813074)
		(mid 64.455655 -244.798195)
		(end 64.470534 -244.762274)
		(stroke
			(width 0.2)
			(type default)
		)
		(layer "In1.Cu")
	)
	(gr_line
		(start 64.419734 -244.508274)
		(end 63.606934 -244.508274)
		(stroke
			(width 0.2)
			(type default)
		)
		(layer "In1.Cu")
	)
	(gr_arc
		(start 64.419734 -130.37185)
		(mid 64.455655 -130.356971)
		(end 64.470534 -130.32105)
		(stroke
			(width 0.2)
			(type default)
		)
		(layer "In1.Cu")
	)
	(gr_line
		(start 64.419734 -130.06705)
		(end 63.606934 -130.06705)
		(stroke
			(width 0.2)
			(type default)
		)
		(layer "In1.Cu")
	)
	(gr_arc
		(start 64.419734 -129.81305)
		(mid 64.455655 -129.798171)
		(end 64.470534 -129.76225)
		(stroke
			(width 0.2)
			(type default)
		)
		(layer "In1.Cu")
	)
	(gr_line
		(start 64.419734 -129.50825)
		(end 63.606934 -129.50825)
		(stroke
			(width 0.2)
			(type default)
		)
		(layer "In1.Cu")
	)
	(gr_arc
		(start 64.419734 -15.371826)
		(mid 64.455655 -15.356947)
		(end 64.470534 -15.321026)
		(stroke
			(width 0.2)
			(type default)
		)
		(layer "In1.Cu")
	)
	(gr_line
		(start 64.419734 -15.067026)
		(end 63.606934 -15.067026)
		(stroke
			(width 0.2)
			(type default)
		)
		(layer "In1.Cu")
	)
	(gr_arc
		(start 64.419734 -14.813026)
		(mid 64.455655 -14.798147)
		(end 64.470534 -14.762226)
		(stroke
			(width 0.2)
			(type default)
		)
		(layer "In1.Cu")
	)
	(gr_line
		(start 64.419734 -14.508226)
		(end 63.606934 -14.508226)
		(stroke
			(width 0.2)
			(type default)
		)
		(layer "In1.Cu")
	)
	(gr_line
		(start 64.470534 -245.321074)
		(end 64.470534 -245.117874)
		(stroke
			(width 0.2)
			(type default)
		)
		(layer "In1.Cu")
	)
	(gr_arc
		(start 64.470534 -245.117874)
		(mid 64.455655 -245.081953)
		(end 64.419734 -245.067074)
		(stroke
			(width 0.2)
			(type default)
		)
		(layer "In1.Cu")
	)
	(gr_line
		(start 64.470534 -244.762274)
		(end 64.470534 -244.559074)
		(stroke
			(width 0.2)
			(type default)
		)
		(layer "In1.Cu")
	)
	(gr_arc
		(start 64.470534 -244.559074)
		(mid 64.455655 -244.523153)
		(end 64.419734 -244.508274)
		(stroke
			(width 0.2)
			(type default)
		)
		(layer "In1.Cu")
	)
	(gr_line
		(start 64.470534 -130.32105)
		(end 64.470534 -130.11785)
		(stroke
			(width 0.2)
			(type default)
		)
		(layer "In1.Cu")
	)
	(gr_arc
		(start 64.470534 -130.11785)
		(mid 64.455655 -130.081929)
		(end 64.419734 -130.06705)
		(stroke
			(width 0.2)
			(type default)
		)
		(layer "In1.Cu")
	)
	(gr_line
		(start 64.470534 -129.76225)
		(end 64.470534 -129.55905)
		(stroke
			(width 0.2)
			(type default)
		)
		(layer "In1.Cu")
	)
	(gr_arc
		(start 64.470534 -129.55905)
		(mid 64.455655 -129.523129)
		(end 64.419734 -129.50825)
		(stroke
			(width 0.2)
			(type default)
		)
		(layer "In1.Cu")
	)
	(gr_line
		(start 64.470534 -15.321026)
		(end 64.470534 -15.117826)
		(stroke
			(width 0.2)
			(type default)
		)
		(layer "In1.Cu")
	)
	(gr_arc
		(start 64.470534 -15.117826)
		(mid 64.455655 -15.081905)
		(end 64.419734 -15.067026)
		(stroke
			(width 0.2)
			(type default)
		)
		(layer "In1.Cu")
	)
	(gr_line
		(start 64.470534 -14.762226)
		(end 64.470534 -14.559026)
		(stroke
			(width 0.2)
			(type default)
		)
		(layer "In1.Cu")
	)
	(gr_arc
		(start 64.470534 -14.559026)
		(mid 64.455655 -14.523105)
		(end 64.419734 -14.508226)
		(stroke
			(width 0.2)
			(type default)
		)
		(layer "In1.Cu")
	)
	(gr_line
		(start 64.54394 -249.385074)
		(end 64.54394 -248.115328)
		(stroke
			(width 0.2)
			(type default)
		)
		(layer "In1.Cu")
	)
	(gr_arc
		(start 64.54394 -248.115328)
		(mid 64.058927 -247.629934)
		(end 63.57366 -248.115074)
		(stroke
			(width 0.2)
			(type default)
		)
		(layer "In1.Cu")
	)
	(gr_line
		(start 64.54394 -134.38505)
		(end 64.54394 -133.11505)
		(stroke
			(width 0.2)
			(type default)
		)
		(layer "In1.Cu")
	)
	(gr_arc
		(start 64.54394 -133.11505)
		(mid 64.0588 -132.62991)
		(end 63.57366 -133.11505)
		(stroke
			(width 0.2)
			(type default)
		)
		(layer "In1.Cu")
	)
	(gr_line
		(start 64.54394 -19.385026)
		(end 64.54394 -18.11528)
		(stroke
			(width 0.2)
			(type default)
		)
		(layer "In1.Cu")
	)
	(gr_arc
		(start 64.54394 -18.11528)
		(mid 64.058927 -17.629886)
		(end 63.57366 -18.115026)
		(stroke
			(width 0.2)
			(type default)
		)
		(layer "In1.Cu")
	)
	(gr_arc
		(start 65.35039 -245.56212)
		(mid 65.835403 -246.047514)
		(end 66.32067 -245.562374)
		(stroke
			(width 0.2)
			(type default)
		)
		(layer "In1.Cu")
	)
	(gr_line
		(start 65.35039 -244.419374)
		(end 65.35039 -245.56212)
		(stroke
			(width 0.2)
			(type default)
		)
		(layer "In1.Cu")
	)
	(gr_arc
		(start 65.35039 -130.56235)
		(mid 65.83553 -131.04749)
		(end 66.32067 -130.56235)
		(stroke
			(width 0.2)
			(type default)
		)
		(layer "In1.Cu")
	)
	(gr_line
		(start 65.35039 -129.41935)
		(end 65.35039 -130.56235)
		(stroke
			(width 0.2)
			(type default)
		)
		(layer "In1.Cu")
	)
	(gr_arc
		(start 65.35039 -15.562326)
		(mid 65.83553 -16.047466)
		(end 66.32067 -15.562326)
		(stroke
			(width 0.2)
			(type default)
		)
		(layer "In1.Cu")
	)
	(gr_line
		(start 65.35039 -14.419326)
		(end 65.35039 -15.562326)
		(stroke
			(width 0.2)
			(type default)
		)
		(layer "In1.Cu")
	)
	(gr_line
		(start 66.32067 -245.562374)
		(end 66.32067 -244.419374)
		(stroke
			(width 0.2)
			(type default)
		)
		(layer "In1.Cu")
	)
	(gr_arc
		(start 66.32067 -244.419374)
		(mid 65.83553 -243.934234)
		(end 65.35039 -244.419374)
		(stroke
			(width 0.2)
			(type default)
		)
		(layer "In1.Cu")
	)
	(gr_line
		(start 66.32067 -130.56235)
		(end 66.32067 -129.419604)
		(stroke
			(width 0.2)
			(type default)
		)
		(layer "In1.Cu")
	)
	(gr_arc
		(start 66.32067 -129.419604)
		(mid 65.835657 -128.93421)
		(end 65.35039 -129.41935)
		(stroke
			(width 0.2)
			(type default)
		)
		(layer "In1.Cu")
	)
	(gr_line
		(start 66.32067 -15.562326)
		(end 66.32067 -14.41958)
		(stroke
			(width 0.2)
			(type default)
		)
		(layer "In1.Cu")
	)
	(gr_arc
		(start 66.32067 -14.41958)
		(mid 65.835657 -13.934186)
		(end 65.35039 -14.419326)
		(stroke
			(width 0.2)
			(type default)
		)
		(layer "In1.Cu")
	)
	(gr_line
		(start 71.300086 -385.99999)
		(end 25.750012 -385.99999)
		(stroke
			(width 1.524)
			(type default)
		)
		(layer "In1.Cu")
	)
	(gr_arc
		(start 71.300086 -385.99999)
		(mid 72.007198 -385.707102)
		(end 72.300084 -384.999992)
		(stroke
			(width 1.524)
			(type default)
		)
		(layer "In1.Cu")
	)
	(gr_line
		(start 72.300084 -381)
		(end 72.300084 -384.999992)
		(stroke
			(width 1.524)
			(type default)
		)
		(layer "In1.Cu")
	)
	(gr_arc
		(start 73.300082 -380.000002)
		(mid 72.592977 -380.292895)
		(end 72.300084 -381)
		(stroke
			(width 1.524)
			(type default)
		)
		(layer "In1.Cu")
	)
	(gr_line
		(start 91.943936 -250.350274)
		(end 91.943936 -247.149874)
		(stroke
			(width 0.2)
			(type default)
		)
		(layer "In1.Cu")
	)
	(gr_line
		(start 91.943936 -247.149874)
		(end 94.306136 -247.149874)
		(stroke
			(width 0.2)
			(type default)
		)
		(layer "In1.Cu")
	)
	(gr_line
		(start 91.943936 -246.540274)
		(end 91.943936 -243.339874)
		(stroke
			(width 0.2)
			(type default)
		)
		(layer "In1.Cu")
	)
	(gr_line
		(start 91.943936 -243.339874)
		(end 94.306136 -243.339874)
		(stroke
			(width 0.2)
			(type default)
		)
		(layer "In1.Cu")
	)
	(gr_line
		(start 91.943936 -135.35025)
		(end 91.943936 -132.14985)
		(stroke
			(width 0.2)
			(type default)
		)
		(layer "In1.Cu")
	)
	(gr_line
		(start 91.943936 -132.14985)
		(end 94.306136 -132.14985)
		(stroke
			(width 0.2)
			(type default)
		)
		(layer "In1.Cu")
	)
	(gr_line
		(start 91.943936 -131.54025)
		(end 91.943936 -128.33985)
		(stroke
			(width 0.2)
			(type default)
		)
		(layer "In1.Cu")
	)
	(gr_line
		(start 91.943936 -128.33985)
		(end 94.306136 -128.33985)
		(stroke
			(width 0.2)
			(type default)
		)
		(layer "In1.Cu")
	)
	(gr_line
		(start 91.943936 -20.350226)
		(end 91.943936 -17.149826)
		(stroke
			(width 0.2)
			(type default)
		)
		(layer "In1.Cu")
	)
	(gr_line
		(start 91.943936 -17.149826)
		(end 94.306136 -17.149826)
		(stroke
			(width 0.2)
			(type default)
		)
		(layer "In1.Cu")
	)
	(gr_line
		(start 91.943936 -16.540226)
		(end 91.943936 -13.339826)
		(stroke
			(width 0.2)
			(type default)
		)
		(layer "In1.Cu")
	)
	(gr_line
		(start 91.943936 -13.339826)
		(end 94.306136 -13.339826)
		(stroke
			(width 0.2)
			(type default)
		)
		(layer "In1.Cu")
	)
	(gr_line
		(start 94.306136 -250.350274)
		(end 91.943936 -250.350274)
		(stroke
			(width 0.2)
			(type default)
		)
		(layer "In1.Cu")
	)
	(gr_line
		(start 94.306136 -247.149874)
		(end 94.306136 -250.350274)
		(stroke
			(width 0.2)
			(type default)
		)
		(layer "In1.Cu")
	)
	(gr_line
		(start 94.306136 -246.540274)
		(end 91.943936 -246.540274)
		(stroke
			(width 0.2)
			(type default)
		)
		(layer "In1.Cu")
	)
	(gr_line
		(start 94.306136 -243.339874)
		(end 94.306136 -246.540274)
		(stroke
			(width 0.2)
			(type default)
		)
		(layer "In1.Cu")
	)
	(gr_line
		(start 94.306136 -135.35025)
		(end 91.943936 -135.35025)
		(stroke
			(width 0.2)
			(type default)
		)
		(layer "In1.Cu")
	)
	(gr_line
		(start 94.306136 -132.14985)
		(end 94.306136 -135.35025)
		(stroke
			(width 0.2)
			(type default)
		)
		(layer "In1.Cu")
	)
	(gr_line
		(start 94.306136 -131.54025)
		(end 91.943936 -131.54025)
		(stroke
			(width 0.2)
			(type default)
		)
		(layer "In1.Cu")
	)
	(gr_line
		(start 94.306136 -128.33985)
		(end 94.306136 -131.54025)
		(stroke
			(width 0.2)
			(type default)
		)
		(layer "In1.Cu")
	)
	(gr_line
		(start 94.306136 -20.350226)
		(end 91.943936 -20.350226)
		(stroke
			(width 0.2)
			(type default)
		)
		(layer "In1.Cu")
	)
	(gr_line
		(start 94.306136 -17.149826)
		(end 94.306136 -20.350226)
		(stroke
			(width 0.2)
			(type default)
		)
		(layer "In1.Cu")
	)
	(gr_line
		(start 94.306136 -16.540226)
		(end 91.943936 -16.540226)
		(stroke
			(width 0.2)
			(type default)
		)
		(layer "In1.Cu")
	)
	(gr_line
		(start 94.306136 -13.339826)
		(end 94.306136 -16.540226)
		(stroke
			(width 0.2)
			(type default)
		)
		(layer "In1.Cu")
	)
	(gr_arc
		(start 95.106236 -245.321074)
		(mid 95.121115 -245.356995)
		(end 95.157036 -245.371874)
		(stroke
			(width 0.2)
			(type default)
		)
		(layer "In1.Cu")
	)
	(gr_line
		(start 95.106236 -245.117874)
		(end 95.106236 -245.321074)
		(stroke
			(width 0.2)
			(type default)
		)
		(layer "In1.Cu")
	)
	(gr_arc
		(start 95.106236 -244.762274)
		(mid 95.121115 -244.798195)
		(end 95.157036 -244.813074)
		(stroke
			(width 0.2)
			(type default)
		)
		(layer "In1.Cu")
	)
	(gr_line
		(start 95.106236 -244.559074)
		(end 95.106236 -244.762274)
		(stroke
			(width 0.2)
			(type default)
		)
		(layer "In1.Cu")
	)
	(gr_arc
		(start 95.106236 -130.32105)
		(mid 95.121115 -130.356971)
		(end 95.157036 -130.37185)
		(stroke
			(width 0.2)
			(type default)
		)
		(layer "In1.Cu")
	)
	(gr_line
		(start 95.106236 -130.11785)
		(end 95.106236 -130.32105)
		(stroke
			(width 0.2)
			(type default)
		)
		(layer "In1.Cu")
	)
	(gr_arc
		(start 95.106236 -129.76225)
		(mid 95.121115 -129.798171)
		(end 95.157036 -129.81305)
		(stroke
			(width 0.2)
			(type default)
		)
		(layer "In1.Cu")
	)
	(gr_line
		(start 95.106236 -129.55905)
		(end 95.106236 -129.76225)
		(stroke
			(width 0.2)
			(type default)
		)
		(layer "In1.Cu")
	)
	(gr_arc
		(start 95.106236 -15.321026)
		(mid 95.121115 -15.356947)
		(end 95.157036 -15.371826)
		(stroke
			(width 0.2)
			(type default)
		)
		(layer "In1.Cu")
	)
	(gr_line
		(start 95.106236 -15.117826)
		(end 95.106236 -15.321026)
		(stroke
			(width 0.2)
			(type default)
		)
		(layer "In1.Cu")
	)
	(gr_arc
		(start 95.106236 -14.762226)
		(mid 95.121115 -14.798147)
		(end 95.157036 -14.813026)
		(stroke
			(width 0.2)
			(type default)
		)
		(layer "In1.Cu")
	)
	(gr_line
		(start 95.106236 -14.559026)
		(end 95.106236 -14.762226)
		(stroke
			(width 0.2)
			(type default)
		)
		(layer "In1.Cu")
	)
	(gr_arc
		(start 95.123762 -249.385074)
		(mid 95.608902 -249.870214)
		(end 96.094042 -249.385074)
		(stroke
			(width 0.2)
			(type default)
		)
		(layer "In1.Cu")
	)
	(gr_line
		(start 95.123762 -248.115074)
		(end 95.123762 -249.385074)
		(stroke
			(width 0.2)
			(type default)
		)
		(layer "In1.Cu")
	)
	(gr_arc
		(start 95.123762 -134.384796)
		(mid 95.608775 -134.87019)
		(end 96.094042 -134.38505)
		(stroke
			(width 0.2)
			(type default)
		)
		(layer "In1.Cu")
	)
	(gr_line
		(start 95.123762 -133.11505)
		(end 95.123762 -134.384796)
		(stroke
			(width 0.2)
			(type default)
		)
		(layer "In1.Cu")
	)
	(gr_arc
		(start 95.123762 -19.385026)
		(mid 95.608902 -19.870166)
		(end 96.094042 -19.385026)
		(stroke
			(width 0.2)
			(type default)
		)
		(layer "In1.Cu")
	)
	(gr_line
		(start 95.123762 -18.115026)
		(end 95.123762 -19.385026)
		(stroke
			(width 0.2)
			(type default)
		)
		(layer "In1.Cu")
	)
	(gr_line
		(start 95.157036 -245.371874)
		(end 95.969836 -245.371874)
		(stroke
			(width 0.2)
			(type default)
		)
		(layer "In1.Cu")
	)
	(gr_arc
		(start 95.157036 -245.067074)
		(mid 95.121115 -245.081953)
		(end 95.106236 -245.117874)
		(stroke
			(width 0.2)
			(type default)
		)
		(layer "In1.Cu")
	)
	(gr_line
		(start 95.157036 -244.813074)
		(end 95.969836 -244.813074)
		(stroke
			(width 0.2)
			(type default)
		)
		(layer "In1.Cu")
	)
	(gr_arc
		(start 95.157036 -244.508274)
		(mid 95.121115 -244.523153)
		(end 95.106236 -244.559074)
		(stroke
			(width 0.2)
			(type default)
		)
		(layer "In1.Cu")
	)
	(gr_line
		(start 95.157036 -130.37185)
		(end 95.969836 -130.37185)
		(stroke
			(width 0.2)
			(type default)
		)
		(layer "In1.Cu")
	)
	(gr_arc
		(start 95.157036 -130.06705)
		(mid 95.121115 -130.081929)
		(end 95.106236 -130.11785)
		(stroke
			(width 0.2)
			(type default)
		)
		(layer "In1.Cu")
	)
	(gr_line
		(start 95.157036 -129.81305)
		(end 95.969836 -129.81305)
		(stroke
			(width 0.2)
			(type default)
		)
		(layer "In1.Cu")
	)
	(gr_arc
		(start 95.157036 -129.50825)
		(mid 95.121115 -129.523129)
		(end 95.106236 -129.55905)
		(stroke
			(width 0.2)
			(type default)
		)
		(layer "In1.Cu")
	)
	(gr_line
		(start 95.157036 -15.371826)
		(end 95.969836 -15.371826)
		(stroke
			(width 0.2)
			(type default)
		)
		(layer "In1.Cu")
	)
	(gr_arc
		(start 95.157036 -15.067026)
		(mid 95.121115 -15.081905)
		(end 95.106236 -15.117826)
		(stroke
			(width 0.2)
			(type default)
		)
		(layer "In1.Cu")
	)
	(gr_line
		(start 95.157036 -14.813026)
		(end 95.969836 -14.813026)
		(stroke
			(width 0.2)
			(type default)
		)
		(layer "In1.Cu")
	)
	(gr_arc
		(start 95.157036 -14.508226)
		(mid 95.121115 -14.523105)
		(end 95.106236 -14.559026)
		(stroke
			(width 0.2)
			(type default)
		)
		(layer "In1.Cu")
	)
	(gr_arc
		(start 95.969836 -245.371874)
		(mid 96.005757 -245.356995)
		(end 96.020636 -245.321074)
		(stroke
			(width 0.2)
			(type default)
		)
		(layer "In1.Cu")
	)
	(gr_line
		(start 95.969836 -245.067074)
		(end 95.157036 -245.067074)
		(stroke
			(width 0.2)
			(type default)
		)
		(layer "In1.Cu")
	)
	(gr_arc
		(start 95.969836 -244.813074)
		(mid 96.005757 -244.798195)
		(end 96.020636 -244.762274)
		(stroke
			(width 0.2)
			(type default)
		)
		(layer "In1.Cu")
	)
	(gr_line
		(start 95.969836 -244.508274)
		(end 95.157036 -244.508274)
		(stroke
			(width 0.2)
			(type default)
		)
		(layer "In1.Cu")
	)
	(gr_arc
		(start 95.969836 -130.37185)
		(mid 96.005757 -130.356971)
		(end 96.020636 -130.32105)
		(stroke
			(width 0.2)
			(type default)
		)
		(layer "In1.Cu")
	)
	(gr_line
		(start 95.969836 -130.06705)
		(end 95.157036 -130.06705)
		(stroke
			(width 0.2)
			(type default)
		)
		(layer "In1.Cu")
	)
	(gr_arc
		(start 95.969836 -129.81305)
		(mid 96.005757 -129.798171)
		(end 96.020636 -129.76225)
		(stroke
			(width 0.2)
			(type default)
		)
		(layer "In1.Cu")
	)
	(gr_line
		(start 95.969836 -129.50825)
		(end 95.157036 -129.50825)
		(stroke
			(width 0.2)
			(type default)
		)
		(layer "In1.Cu")
	)
	(gr_arc
		(start 95.969836 -15.371826)
		(mid 96.005757 -15.356947)
		(end 96.020636 -15.321026)
		(stroke
			(width 0.2)
			(type default)
		)
		(layer "In1.Cu")
	)
	(gr_line
		(start 95.969836 -15.067026)
		(end 95.157036 -15.067026)
		(stroke
			(width 0.2)
			(type default)
		)
		(layer "In1.Cu")
	)
	(gr_arc
		(start 95.969836 -14.813026)
		(mid 96.005757 -14.798147)
		(end 96.020636 -14.762226)
		(stroke
			(width 0.2)
			(type default)
		)
		(layer "In1.Cu")
	)
	(gr_line
		(start 95.969836 -14.508226)
		(end 95.157036 -14.508226)
		(stroke
			(width 0.2)
			(type default)
		)
		(layer "In1.Cu")
	)
	(gr_line
		(start 96.020636 -245.321074)
		(end 96.020636 -245.117874)
		(stroke
			(width 0.2)
			(type default)
		)
		(layer "In1.Cu")
	)
	(gr_arc
		(start 96.020636 -245.117874)
		(mid 96.005757 -245.081953)
		(end 95.969836 -245.067074)
		(stroke
			(width 0.2)
			(type default)
		)
		(layer "In1.Cu")
	)
	(gr_line
		(start 96.020636 -244.762274)
		(end 96.020636 -244.559074)
		(stroke
			(width 0.2)
			(type default)
		)
		(layer "In1.Cu")
	)
	(gr_arc
		(start 96.020636 -244.559074)
		(mid 96.005757 -244.523153)
		(end 95.969836 -244.508274)
		(stroke
			(width 0.2)
			(type default)
		)
		(layer "In1.Cu")
	)
	(gr_line
		(start 96.020636 -130.32105)
		(end 96.020636 -130.11785)
		(stroke
			(width 0.2)
			(type default)
		)
		(layer "In1.Cu")
	)
	(gr_arc
		(start 96.020636 -130.11785)
		(mid 96.005757 -130.081929)
		(end 95.969836 -130.06705)
		(stroke
			(width 0.2)
			(type default)
		)
		(layer "In1.Cu")
	)
	(gr_line
		(start 96.020636 -129.76225)
		(end 96.020636 -129.55905)
		(stroke
			(width 0.2)
			(type default)
		)
		(layer "In1.Cu")
	)
	(gr_arc
		(start 96.020636 -129.55905)
		(mid 96.005757 -129.523129)
		(end 95.969836 -129.50825)
		(stroke
			(width 0.2)
			(type default)
		)
		(layer "In1.Cu")
	)
	(gr_line
		(start 96.020636 -15.321026)
		(end 96.020636 -15.117826)
		(stroke
			(width 0.2)
			(type default)
		)
		(layer "In1.Cu")
	)
	(gr_arc
		(start 96.020636 -15.117826)
		(mid 96.005757 -15.081905)
		(end 95.969836 -15.067026)
		(stroke
			(width 0.2)
			(type default)
		)
		(layer "In1.Cu")
	)
	(gr_line
		(start 96.020636 -14.762226)
		(end 96.020636 -14.559026)
		(stroke
			(width 0.2)
			(type default)
		)
		(layer "In1.Cu")
	)
	(gr_arc
		(start 96.020636 -14.559026)
		(mid 96.005757 -14.523105)
		(end 95.969836 -14.508226)
		(stroke
			(width 0.2)
			(type default)
		)
		(layer "In1.Cu")
	)
	(gr_line
		(start 96.094042 -249.385074)
		(end 96.094042 -248.115328)
		(stroke
			(width 0.2)
			(type default)
		)
		(layer "In1.Cu")
	)
	(gr_arc
		(start 96.094042 -248.115328)
		(mid 95.609029 -247.629934)
		(end 95.123762 -248.115074)
		(stroke
			(width 0.2)
			(type default)
		)
		(layer "In1.Cu")
	)
	(gr_line
		(start 96.094042 -134.38505)
		(end 96.094042 -133.11505)
		(stroke
			(width 0.2)
			(type default)
		)
		(layer "In1.Cu")
	)
	(gr_arc
		(start 96.094042 -133.11505)
		(mid 95.608902 -132.62991)
		(end 95.123762 -133.11505)
		(stroke
			(width 0.2)
			(type default)
		)
		(layer "In1.Cu")
	)
	(gr_line
		(start 96.094042 -19.385026)
		(end 96.094042 -18.11528)
		(stroke
			(width 0.2)
			(type default)
		)
		(layer "In1.Cu")
	)
	(gr_arc
		(start 96.094042 -18.11528)
		(mid 95.609029 -17.629886)
		(end 95.123762 -18.115026)
		(stroke
			(width 0.2)
			(type default)
		)
		(layer "In1.Cu")
	)
	(gr_arc
		(start 96.900492 -245.56212)
		(mid 97.385505 -246.047514)
		(end 97.870772 -245.562374)
		(stroke
			(width 0.2)
			(type default)
		)
		(layer "In1.Cu")
	)
	(gr_line
		(start 96.900492 -244.419374)
		(end 96.900492 -245.56212)
		(stroke
			(width 0.2)
			(type default)
		)
		(layer "In1.Cu")
	)
	(gr_arc
		(start 96.900492 -130.56235)
		(mid 97.385632 -131.04749)
		(end 97.870772 -130.56235)
		(stroke
			(width 0.2)
			(type default)
		)
		(layer "In1.Cu")
	)
	(gr_line
		(start 96.900492 -129.41935)
		(end 96.900492 -130.56235)
		(stroke
			(width 0.2)
			(type default)
		)
		(layer "In1.Cu")
	)
	(gr_arc
		(start 96.900492 -15.562326)
		(mid 97.385632 -16.047466)
		(end 97.870772 -15.562326)
		(stroke
			(width 0.2)
			(type default)
		)
		(layer "In1.Cu")
	)
	(gr_line
		(start 96.900492 -14.419326)
		(end 96.900492 -15.562326)
		(stroke
			(width 0.2)
			(type default)
		)
		(layer "In1.Cu")
	)
	(gr_line
		(start 97.870772 -245.562374)
		(end 97.870772 -244.419374)
		(stroke
			(width 0.2)
			(type default)
		)
		(layer "In1.Cu")
	)
	(gr_arc
		(start 97.870772 -244.419374)
		(mid 97.385632 -243.934234)
		(end 96.900492 -244.419374)
		(stroke
			(width 0.2)
			(type default)
		)
		(layer "In1.Cu")
	)
	(gr_line
		(start 97.870772 -130.56235)
		(end 97.870772 -129.419604)
		(stroke
			(width 0.2)
			(type default)
		)
		(layer "In1.Cu")
	)
	(gr_arc
		(start 97.870772 -129.419604)
		(mid 97.385759 -128.93421)
		(end 96.900492 -129.41935)
		(stroke
			(width 0.2)
			(type default)
		)
		(layer "In1.Cu")
	)
	(gr_line
		(start 97.870772 -15.562326)
		(end 97.870772 -14.41958)
		(stroke
			(width 0.2)
			(type default)
		)
		(layer "In1.Cu")
	)
	(gr_arc
		(start 97.870772 -14.41958)
		(mid 97.385759 -13.934186)
		(end 96.900492 -14.419326)
		(stroke
			(width 0.2)
			(type default)
		)
		(layer "In1.Cu")
	)
	(gr_line
		(start 102.743 -346.202)
		(end 103.632 -347.091)
		(stroke
			(width 0.381)
			(type default)
		)
		(layer "In1.Cu")
	)
	(gr_line
		(start 102.743 -332.613)
		(end 102.743 -346.202)
		(stroke
			(width 0.381)
			(type default)
		)
		(layer "In1.Cu")
	)
	(gr_line
		(start 103.632 -364.269782)
		(end 104.043988 -364.68177)
		(stroke
			(width 0.381)
			(type default)
		)
		(layer "In1.Cu")
	)
	(gr_line
		(start 103.632 -347.091)
		(end 103.632 -364.269782)
		(stroke
			(width 0.381)
			(type default)
		)
		(layer "In1.Cu")
	)
	(gr_line
		(start 104.043988 -364.68177)
		(end 109.290612 -364.68177)
		(stroke
			(width 0.381)
			(type default)
		)
		(layer "In1.Cu")
	)
	(gr_line
		(start 104.146604 -331.209396)
		(end 102.743 -332.613)
		(stroke
			(width 0.381)
			(type default)
		)
		(layer "In1.Cu")
	)
	(gr_line
		(start 109.290612 -364.68177)
		(end 112.207802 -361.76458)
		(stroke
			(width 0.381)
			(type default)
		)
		(layer "In1.Cu")
	)
	(gr_line
		(start 112.207802 -361.76458)
		(end 123.074938 -361.76458)
		(stroke
			(width 0.381)
			(type default)
		)
		(layer "In1.Cu")
	)
	(gr_line
		(start 123.074938 -361.76458)
		(end 126.445518 -358.394)
		(stroke
			(width 0.381)
			(type default)
		)
		(layer "In1.Cu")
	)
	(gr_line
		(start 123.493784 -250.350274)
		(end 123.493784 -247.149874)
		(stroke
			(width 0.2)
			(type default)
		)
		(layer "In1.Cu")
	)
	(gr_line
		(start 123.493784 -247.149874)
		(end 125.855984 -247.149874)
		(stroke
			(width 0.2)
			(type default)
		)
		(layer "In1.Cu")
	)
	(gr_line
		(start 123.493784 -246.540274)
		(end 123.493784 -243.339874)
		(stroke
			(width 0.2)
			(type default)
		)
		(layer "In1.Cu")
	)
	(gr_line
		(start 123.493784 -243.339874)
		(end 125.855984 -243.339874)
		(stroke
			(width 0.2)
			(type default)
		)
		(layer "In1.Cu")
	)
	(gr_line
		(start 123.493784 -135.35025)
		(end 123.493784 -132.14985)
		(stroke
			(width 0.2)
			(type default)
		)
		(layer "In1.Cu")
	)
	(gr_line
		(start 123.493784 -132.14985)
		(end 125.855984 -132.14985)
		(stroke
			(width 0.2)
			(type default)
		)
		(layer "In1.Cu")
	)
	(gr_line
		(start 123.493784 -131.54025)
		(end 123.493784 -128.33985)
		(stroke
			(width 0.2)
			(type default)
		)
		(layer "In1.Cu")
	)
	(gr_line
		(start 123.493784 -128.33985)
		(end 125.855984 -128.33985)
		(stroke
			(width 0.2)
			(type default)
		)
		(layer "In1.Cu")
	)
	(gr_line
		(start 123.493784 -20.350226)
		(end 123.493784 -17.149826)
		(stroke
			(width 0.2)
			(type default)
		)
		(layer "In1.Cu")
	)
	(gr_line
		(start 123.493784 -17.149826)
		(end 125.855984 -17.149826)
		(stroke
			(width 0.2)
			(type default)
		)
		(layer "In1.Cu")
	)
	(gr_line
		(start 123.493784 -16.540226)
		(end 123.493784 -13.339826)
		(stroke
			(width 0.2)
			(type default)
		)
		(layer "In1.Cu")
	)
	(gr_line
		(start 123.493784 -13.339826)
		(end 125.855984 -13.339826)
		(stroke
			(width 0.2)
			(type default)
		)
		(layer "In1.Cu")
	)
	(gr_line
		(start 125.299978 -380.000002)
		(end 73.300082 -380.000002)
		(stroke
			(width 1.524)
			(type default)
		)
		(layer "In1.Cu")
	)
	(gr_line
		(start 125.855984 -250.350274)
		(end 123.493784 -250.350274)
		(stroke
			(width 0.2)
			(type default)
		)
		(layer "In1.Cu")
	)
	(gr_line
		(start 125.855984 -247.149874)
		(end 125.855984 -250.350274)
		(stroke
			(width 0.2)
			(type default)
		)
		(layer "In1.Cu")
	)
	(gr_line
		(start 125.855984 -246.540274)
		(end 123.493784 -246.540274)
		(stroke
			(width 0.2)
			(type default)
		)
		(layer "In1.Cu")
	)
	(gr_line
		(start 125.855984 -243.339874)
		(end 125.855984 -246.540274)
		(stroke
			(width 0.2)
			(type default)
		)
		(layer "In1.Cu")
	)
	(gr_line
		(start 125.855984 -135.35025)
		(end 123.493784 -135.35025)
		(stroke
			(width 0.2)
			(type default)
		)
		(layer "In1.Cu")
	)
	(gr_line
		(start 125.855984 -132.14985)
		(end 125.855984 -135.35025)
		(stroke
			(width 0.2)
			(type default)
		)
		(layer "In1.Cu")
	)
	(gr_line
		(start 125.855984 -131.54025)
		(end 123.493784 -131.54025)
		(stroke
			(width 0.2)
			(type default)
		)
		(layer "In1.Cu")
	)
	(gr_line
		(start 125.855984 -128.33985)
		(end 125.855984 -131.54025)
		(stroke
			(width 0.2)
			(type default)
		)
		(layer "In1.Cu")
	)
	(gr_line
		(start 125.855984 -20.350226)
		(end 123.493784 -20.350226)
		(stroke
			(width 0.2)
			(type default)
		)
		(layer "In1.Cu")
	)
	(gr_line
		(start 125.855984 -17.149826)
		(end 125.855984 -20.350226)
		(stroke
			(width 0.2)
			(type default)
		)
		(layer "In1.Cu")
	)
	(gr_line
		(start 125.855984 -16.540226)
		(end 123.493784 -16.540226)
		(stroke
			(width 0.2)
			(type default)
		)
		(layer "In1.Cu")
	)
	(gr_line
		(start 125.855984 -13.339826)
		(end 125.855984 -16.540226)
		(stroke
			(width 0.2)
			(type default)
		)
		(layer "In1.Cu")
	)
	(gr_line
		(start 126.299976 -384.999992)
		(end 126.299976 -381)
		(stroke
			(width 1.524)
			(type default)
		)
		(layer "In1.Cu")
	)
	(gr_arc
		(start 126.299976 -384.999992)
		(mid 126.592864 -385.707112)
		(end 127.299974 -385.99999)
		(stroke
			(width 1.524)
			(type default)
		)
		(layer "In1.Cu")
	)
	(gr_arc
		(start 126.299976 -381)
		(mid 126.007083 -380.292895)
		(end 125.299978 -380.000002)
		(stroke
			(width 1.524)
			(type default)
		)
		(layer "In1.Cu")
	)
	(gr_line
		(start 126.445518 -358.394)
		(end 160.782 -358.394)
		(stroke
			(width 0.381)
			(type default)
		)
		(layer "In1.Cu")
	)
	(gr_arc
		(start 126.656084 -245.321074)
		(mid 126.670963 -245.356995)
		(end 126.706884 -245.371874)
		(stroke
			(width 0.2)
			(type default)
		)
		(layer "In1.Cu")
	)
	(gr_line
		(start 126.656084 -245.117874)
		(end 126.656084 -245.321074)
		(stroke
			(width 0.2)
			(type default)
		)
		(layer "In1.Cu")
	)
	(gr_arc
		(start 126.656084 -244.762274)
		(mid 126.670963 -244.798195)
		(end 126.706884 -244.813074)
		(stroke
			(width 0.2)
			(type default)
		)
		(layer "In1.Cu")
	)
	(gr_line
		(start 126.656084 -244.559074)
		(end 126.656084 -244.762274)
		(stroke
			(width 0.2)
			(type default)
		)
		(layer "In1.Cu")
	)
	(gr_arc
		(start 126.656084 -130.32105)
		(mid 126.670963 -130.356971)
		(end 126.706884 -130.37185)
		(stroke
			(width 0.2)
			(type default)
		)
		(layer "In1.Cu")
	)
	(gr_line
		(start 126.656084 -130.11785)
		(end 126.656084 -130.32105)
		(stroke
			(width 0.2)
			(type default)
		)
		(layer "In1.Cu")
	)
	(gr_arc
		(start 126.656084 -129.76225)
		(mid 126.670963 -129.798171)
		(end 126.706884 -129.81305)
		(stroke
			(width 0.2)
			(type default)
		)
		(layer "In1.Cu")
	)
	(gr_line
		(start 126.656084 -129.55905)
		(end 126.656084 -129.76225)
		(stroke
			(width 0.2)
			(type default)
		)
		(layer "In1.Cu")
	)
	(gr_arc
		(start 126.656084 -15.321026)
		(mid 126.670963 -15.356947)
		(end 126.706884 -15.371826)
		(stroke
			(width 0.2)
			(type default)
		)
		(layer "In1.Cu")
	)
	(gr_line
		(start 126.656084 -15.117826)
		(end 126.656084 -15.321026)
		(stroke
			(width 0.2)
			(type default)
		)
		(layer "In1.Cu")
	)
	(gr_arc
		(start 126.656084 -14.762226)
		(mid 126.670963 -14.798147)
		(end 126.706884 -14.813026)
		(stroke
			(width 0.2)
			(type default)
		)
		(layer "In1.Cu")
	)
	(gr_line
		(start 126.656084 -14.559026)
		(end 126.656084 -14.762226)
		(stroke
			(width 0.2)
			(type default)
		)
		(layer "In1.Cu")
	)
	(gr_arc
		(start 126.67361 -249.385074)
		(mid 127.15875 -249.870214)
		(end 127.64389 -249.385074)
		(stroke
			(width 0.2)
			(type default)
		)
		(layer "In1.Cu")
	)
	(gr_line
		(start 126.67361 -248.115074)
		(end 126.67361 -249.385074)
		(stroke
			(width 0.2)
			(type default)
		)
		(layer "In1.Cu")
	)
	(gr_arc
		(start 126.67361 -134.384796)
		(mid 127.158623 -134.87019)
		(end 127.64389 -134.38505)
		(stroke
			(width 0.2)
			(type default)
		)
		(layer "In1.Cu")
	)
	(gr_line
		(start 126.67361 -133.11505)
		(end 126.67361 -134.384796)
		(stroke
			(width 0.2)
			(type default)
		)
		(layer "In1.Cu")
	)
	(gr_arc
		(start 126.67361 -19.385026)
		(mid 127.15875 -19.870166)
		(end 127.64389 -19.385026)
		(stroke
			(width 0.2)
			(type default)
		)
		(layer "In1.Cu")
	)
	(gr_line
		(start 126.67361 -18.115026)
		(end 126.67361 -19.385026)
		(stroke
			(width 0.2)
			(type default)
		)
		(layer "In1.Cu")
	)
	(gr_line
		(start 126.706884 -245.371874)
		(end 127.519684 -245.371874)
		(stroke
			(width 0.2)
			(type default)
		)
		(layer "In1.Cu")
	)
	(gr_arc
		(start 126.706884 -245.067074)
		(mid 126.670963 -245.081953)
		(end 126.656084 -245.117874)
		(stroke
			(width 0.2)
			(type default)
		)
		(layer "In1.Cu")
	)
	(gr_line
		(start 126.706884 -244.813074)
		(end 127.519684 -244.813074)
		(stroke
			(width 0.2)
			(type default)
		)
		(layer "In1.Cu")
	)
	(gr_arc
		(start 126.706884 -244.508274)
		(mid 126.670963 -244.523153)
		(end 126.656084 -244.559074)
		(stroke
			(width 0.2)
			(type default)
		)
		(layer "In1.Cu")
	)
	(gr_line
		(start 126.706884 -130.37185)
		(end 127.519684 -130.37185)
		(stroke
			(width 0.2)
			(type default)
		)
		(layer "In1.Cu")
	)
	(gr_arc
		(start 126.706884 -130.06705)
		(mid 126.670963 -130.081929)
		(end 126.656084 -130.11785)
		(stroke
			(width 0.2)
			(type default)
		)
		(layer "In1.Cu")
	)
	(gr_line
		(start 126.706884 -129.81305)
		(end 127.519684 -129.81305)
		(stroke
			(width 0.2)
			(type default)
		)
		(layer "In1.Cu")
	)
	(gr_arc
		(start 126.706884 -129.50825)
		(mid 126.670963 -129.523129)
		(end 126.656084 -129.55905)
		(stroke
			(width 0.2)
			(type default)
		)
		(layer "In1.Cu")
	)
	(gr_line
		(start 126.706884 -15.371826)
		(end 127.519684 -15.371826)
		(stroke
			(width 0.2)
			(type default)
		)
		(layer "In1.Cu")
	)
	(gr_arc
		(start 126.706884 -15.067026)
		(mid 126.670963 -15.081905)
		(end 126.656084 -15.117826)
		(stroke
			(width 0.2)
			(type default)
		)
		(layer "In1.Cu")
	)
	(gr_line
		(start 126.706884 -14.813026)
		(end 127.519684 -14.813026)
		(stroke
			(width 0.2)
			(type default)
		)
		(layer "In1.Cu")
	)
	(gr_arc
		(start 126.706884 -14.508226)
		(mid 126.670963 -14.523105)
		(end 126.656084 -14.559026)
		(stroke
			(width 0.2)
			(type default)
		)
		(layer "In1.Cu")
	)
	(gr_arc
		(start 127.519684 -245.371874)
		(mid 127.555605 -245.356995)
		(end 127.570484 -245.321074)
		(stroke
			(width 0.2)
			(type default)
		)
		(layer "In1.Cu")
	)
	(gr_line
		(start 127.519684 -245.067074)
		(end 126.706884 -245.067074)
		(stroke
			(width 0.2)
			(type default)
		)
		(layer "In1.Cu")
	)
	(gr_arc
		(start 127.519684 -244.813074)
		(mid 127.555605 -244.798195)
		(end 127.570484 -244.762274)
		(stroke
			(width 0.2)
			(type default)
		)
		(layer "In1.Cu")
	)
	(gr_line
		(start 127.519684 -244.508274)
		(end 126.706884 -244.508274)
		(stroke
			(width 0.2)
			(type default)
		)
		(layer "In1.Cu")
	)
	(gr_arc
		(start 127.519684 -130.37185)
		(mid 127.555605 -130.356971)
		(end 127.570484 -130.32105)
		(stroke
			(width 0.2)
			(type default)
		)
		(layer "In1.Cu")
	)
	(gr_line
		(start 127.519684 -130.06705)
		(end 126.706884 -130.06705)
		(stroke
			(width 0.2)
			(type default)
		)
		(layer "In1.Cu")
	)
	(gr_arc
		(start 127.519684 -129.81305)
		(mid 127.555605 -129.798171)
		(end 127.570484 -129.76225)
		(stroke
			(width 0.2)
			(type default)
		)
		(layer "In1.Cu")
	)
	(gr_line
		(start 127.519684 -129.50825)
		(end 126.706884 -129.50825)
		(stroke
			(width 0.2)
			(type default)
		)
		(layer "In1.Cu")
	)
	(gr_arc
		(start 127.519684 -15.371826)
		(mid 127.555605 -15.356947)
		(end 127.570484 -15.321026)
		(stroke
			(width 0.2)
			(type default)
		)
		(layer "In1.Cu")
	)
	(gr_line
		(start 127.519684 -15.067026)
		(end 126.706884 -15.067026)
		(stroke
			(width 0.2)
			(type default)
		)
		(layer "In1.Cu")
	)
	(gr_arc
		(start 127.519684 -14.813026)
		(mid 127.555605 -14.798147)
		(end 127.570484 -14.762226)
		(stroke
			(width 0.2)
			(type default)
		)
		(layer "In1.Cu")
	)
	(gr_line
		(start 127.519684 -14.508226)
		(end 126.706884 -14.508226)
		(stroke
			(width 0.2)
			(type default)
		)
		(layer "In1.Cu")
	)
	(gr_line
		(start 127.570484 -245.321074)
		(end 127.570484 -245.117874)
		(stroke
			(width 0.2)
			(type default)
		)
		(layer "In1.Cu")
	)
	(gr_arc
		(start 127.570484 -245.117874)
		(mid 127.555605 -245.081953)
		(end 127.519684 -245.067074)
		(stroke
			(width 0.2)
			(type default)
		)
		(layer "In1.Cu")
	)
	(gr_line
		(start 127.570484 -244.762274)
		(end 127.570484 -244.559074)
		(stroke
			(width 0.2)
			(type default)
		)
		(layer "In1.Cu")
	)
	(gr_arc
		(start 127.570484 -244.559074)
		(mid 127.555605 -244.523153)
		(end 127.519684 -244.508274)
		(stroke
			(width 0.2)
			(type default)
		)
		(layer "In1.Cu")
	)
	(gr_line
		(start 127.570484 -130.32105)
		(end 127.570484 -130.11785)
		(stroke
			(width 0.2)
			(type default)
		)
		(layer "In1.Cu")
	)
	(gr_arc
		(start 127.570484 -130.11785)
		(mid 127.555605 -130.081929)
		(end 127.519684 -130.06705)
		(stroke
			(width 0.2)
			(type default)
		)
		(layer "In1.Cu")
	)
	(gr_line
		(start 127.570484 -129.76225)
		(end 127.570484 -129.55905)
		(stroke
			(width 0.2)
			(type default)
		)
		(layer "In1.Cu")
	)
	(gr_arc
		(start 127.570484 -129.55905)
		(mid 127.555605 -129.523129)
		(end 127.519684 -129.50825)
		(stroke
			(width 0.2)
			(type default)
		)
		(layer "In1.Cu")
	)
	(gr_line
		(start 127.570484 -15.321026)
		(end 127.570484 -15.117826)
		(stroke
			(width 0.2)
			(type default)
		)
		(layer "In1.Cu")
	)
	(gr_arc
		(start 127.570484 -15.117826)
		(mid 127.555605 -15.081905)
		(end 127.519684 -15.067026)
		(stroke
			(width 0.2)
			(type default)
		)
		(layer "In1.Cu")
	)
	(gr_line
		(start 127.570484 -14.762226)
		(end 127.570484 -14.559026)
		(stroke
			(width 0.2)
			(type default)
		)
		(layer "In1.Cu")
	)
	(gr_arc
		(start 127.570484 -14.559026)
		(mid 127.555605 -14.523105)
		(end 127.519684 -14.508226)
		(stroke
			(width 0.2)
			(type default)
		)
		(layer "In1.Cu")
	)
	(gr_line
		(start 127.64389 -249.385074)
		(end 127.64389 -248.115328)
		(stroke
			(width 0.2)
			(type default)
		)
		(layer "In1.Cu")
	)
	(gr_arc
		(start 127.64389 -248.115328)
		(mid 127.158877 -247.629934)
		(end 126.67361 -248.115074)
		(stroke
			(width 0.2)
			(type default)
		)
		(layer "In1.Cu")
	)
	(gr_line
		(start 127.64389 -134.38505)
		(end 127.64389 -133.11505)
		(stroke
			(width 0.2)
			(type default)
		)
		(layer "In1.Cu")
	)
	(gr_arc
		(start 127.64389 -133.11505)
		(mid 127.15875 -132.62991)
		(end 126.67361 -133.11505)
		(stroke
			(width 0.2)
			(type default)
		)
		(layer "In1.Cu")
	)
	(gr_line
		(start 127.64389 -19.385026)
		(end 127.64389 -18.11528)
		(stroke
			(width 0.2)
			(type default)
		)
		(layer "In1.Cu")
	)
	(gr_arc
		(start 127.64389 -18.11528)
		(mid 127.158877 -17.629886)
		(end 126.67361 -18.115026)
		(stroke
			(width 0.2)
			(type default)
		)
		(layer "In1.Cu")
	)
	(gr_arc
		(start 128.45034 -245.56212)
		(mid 128.935353 -246.047514)
		(end 129.42062 -245.562374)
		(stroke
			(width 0.2)
			(type default)
		)
		(layer "In1.Cu")
	)
	(gr_line
		(start 128.45034 -244.419374)
		(end 128.45034 -245.56212)
		(stroke
			(width 0.2)
			(type default)
		)
		(layer "In1.Cu")
	)
	(gr_arc
		(start 128.45034 -130.56235)
		(mid 128.93548 -131.04749)
		(end 129.42062 -130.56235)
		(stroke
			(width 0.2)
			(type default)
		)
		(layer "In1.Cu")
	)
	(gr_line
		(start 128.45034 -129.41935)
		(end 128.45034 -130.56235)
		(stroke
			(width 0.2)
			(type default)
		)
		(layer "In1.Cu")
	)
	(gr_arc
		(start 128.45034 -15.562326)
		(mid 128.93548 -16.047466)
		(end 129.42062 -15.562326)
		(stroke
			(width 0.2)
			(type default)
		)
		(layer "In1.Cu")
	)
	(gr_line
		(start 128.45034 -14.419326)
		(end 128.45034 -15.562326)
		(stroke
			(width 0.2)
			(type default)
		)
		(layer "In1.Cu")
	)
	(gr_line
		(start 129.42062 -245.562374)
		(end 129.42062 -244.419374)
		(stroke
			(width 0.2)
			(type default)
		)
		(layer "In1.Cu")
	)
	(gr_arc
		(start 129.42062 -244.419374)
		(mid 128.93548 -243.934234)
		(end 128.45034 -244.419374)
		(stroke
			(width 0.2)
			(type default)
		)
		(layer "In1.Cu")
	)
	(gr_line
		(start 129.42062 -130.56235)
		(end 129.42062 -129.419604)
		(stroke
			(width 0.2)
			(type default)
		)
		(layer "In1.Cu")
	)
	(gr_arc
		(start 129.42062 -129.419604)
		(mid 128.935607 -128.93421)
		(end 128.45034 -129.41935)
		(stroke
			(width 0.2)
			(type default)
		)
		(layer "In1.Cu")
	)
	(gr_line
		(start 129.42062 -15.562326)
		(end 129.42062 -14.41958)
		(stroke
			(width 0.2)
			(type default)
		)
		(layer "In1.Cu")
	)
	(gr_arc
		(start 129.42062 -14.41958)
		(mid 128.935607 -13.934186)
		(end 128.45034 -14.419326)
		(stroke
			(width 0.2)
			(type default)
		)
		(layer "In1.Cu")
	)
	(gr_line
		(start 151.263604 -331.209396)
		(end 104.146604 -331.209396)
		(stroke
			(width 0.381)
			(type default)
		)
		(layer "In1.Cu")
	)
	(gr_line
		(start 151.638 -330.835)
		(end 151.263604 -331.209396)
		(stroke
			(width 0.381)
			(type default)
		)
		(layer "In1.Cu")
	)
	(gr_line
		(start 151.638 -327.66)
		(end 151.638 -330.835)
		(stroke
			(width 0.381)
			(type default)
		)
		(layer "In1.Cu")
	)
	(gr_line
		(start 152.273 -327.025)
		(end 151.638 -327.66)
		(stroke
			(width 0.381)
			(type default)
		)
		(layer "In1.Cu")
	)
	(gr_line
		(start 155.043886 -250.350274)
		(end 155.043886 -247.149874)
		(stroke
			(width 0.2)
			(type default)
		)
		(layer "In1.Cu")
	)
	(gr_line
		(start 155.043886 -247.149874)
		(end 157.406086 -247.149874)
		(stroke
			(width 0.2)
			(type default)
		)
		(layer "In1.Cu")
	)
	(gr_line
		(start 155.043886 -246.540274)
		(end 155.043886 -243.339874)
		(stroke
			(width 0.2)
			(type default)
		)
		(layer "In1.Cu")
	)
	(gr_line
		(start 155.043886 -243.339874)
		(end 157.406086 -243.339874)
		(stroke
			(width 0.2)
			(type default)
		)
		(layer "In1.Cu")
	)
	(gr_line
		(start 155.043886 -135.35025)
		(end 155.043886 -132.14985)
		(stroke
			(width 0.2)
			(type default)
		)
		(layer "In1.Cu")
	)
	(gr_line
		(start 155.043886 -132.14985)
		(end 157.406086 -132.14985)
		(stroke
			(width 0.2)
			(type default)
		)
		(layer "In1.Cu")
	)
	(gr_line
		(start 155.043886 -131.54025)
		(end 155.043886 -128.33985)
		(stroke
			(width 0.2)
			(type default)
		)
		(layer "In1.Cu")
	)
	(gr_line
		(start 155.043886 -128.33985)
		(end 157.406086 -128.33985)
		(stroke
			(width 0.2)
			(type default)
		)
		(layer "In1.Cu")
	)
	(gr_line
		(start 155.043886 -20.350226)
		(end 155.043886 -17.149826)
		(stroke
			(width 0.2)
			(type default)
		)
		(layer "In1.Cu")
	)
	(gr_line
		(start 155.043886 -17.149826)
		(end 157.406086 -17.149826)
		(stroke
			(width 0.2)
			(type default)
		)
		(layer "In1.Cu")
	)
	(gr_line
		(start 155.043886 -16.540226)
		(end 155.043886 -13.339826)
		(stroke
			(width 0.2)
			(type default)
		)
		(layer "In1.Cu")
	)
	(gr_line
		(start 155.043886 -13.339826)
		(end 157.406086 -13.339826)
		(stroke
			(width 0.2)
			(type default)
		)
		(layer "In1.Cu")
	)
	(gr_line
		(start 157.353 -327.025)
		(end 152.273 -327.025)
		(stroke
			(width 0.381)
			(type default)
		)
		(layer "In1.Cu")
	)
	(gr_line
		(start 157.406086 -250.350274)
		(end 155.043886 -250.350274)
		(stroke
			(width 0.2)
			(type default)
		)
		(layer "In1.Cu")
	)
	(gr_line
		(start 157.406086 -247.149874)
		(end 157.406086 -250.350274)
		(stroke
			(width 0.2)
			(type default)
		)
		(layer "In1.Cu")
	)
	(gr_line
		(start 157.406086 -246.540274)
		(end 155.043886 -246.540274)
		(stroke
			(width 0.2)
			(type default)
		)
		(layer "In1.Cu")
	)
	(gr_line
		(start 157.406086 -243.339874)
		(end 157.406086 -246.540274)
		(stroke
			(width 0.2)
			(type default)
		)
		(layer "In1.Cu")
	)
	(gr_line
		(start 157.406086 -135.35025)
		(end 155.043886 -135.35025)
		(stroke
			(width 0.2)
			(type default)
		)
		(layer "In1.Cu")
	)
	(gr_line
		(start 157.406086 -132.14985)
		(end 157.406086 -135.35025)
		(stroke
			(width 0.2)
			(type default)
		)
		(layer "In1.Cu")
	)
	(gr_line
		(start 157.406086 -131.54025)
		(end 155.043886 -131.54025)
		(stroke
			(width 0.2)
			(type default)
		)
		(layer "In1.Cu")
	)
	(gr_line
		(start 157.406086 -128.33985)
		(end 157.406086 -131.54025)
		(stroke
			(width 0.2)
			(type default)
		)
		(layer "In1.Cu")
	)
	(gr_line
		(start 157.406086 -20.350226)
		(end 155.043886 -20.350226)
		(stroke
			(width 0.2)
			(type default)
		)
		(layer "In1.Cu")
	)
	(gr_line
		(start 157.406086 -17.149826)
		(end 157.406086 -20.350226)
		(stroke
			(width 0.2)
			(type default)
		)
		(layer "In1.Cu")
	)
	(gr_line
		(start 157.406086 -16.540226)
		(end 155.043886 -16.540226)
		(stroke
			(width 0.2)
			(type default)
		)
		(layer "In1.Cu")
	)
	(gr_line
		(start 157.406086 -13.339826)
		(end 157.406086 -16.540226)
		(stroke
			(width 0.2)
			(type default)
		)
		(layer "In1.Cu")
	)
	(gr_line
		(start 157.607 -328.549)
		(end 157.607 -327.279)
		(stroke
			(width 0.381)
			(type default)
		)
		(layer "In1.Cu")
	)
	(gr_line
		(start 157.607 -327.279)
		(end 157.353 -327.025)
		(stroke
			(width 0.381)
			(type default)
		)
		(layer "In1.Cu")
	)
	(gr_line
		(start 157.988 -328.93)
		(end 157.607 -328.549)
		(stroke
			(width 0.381)
			(type default)
		)
		(layer "In1.Cu")
	)
	(gr_arc
		(start 158.206186 -245.321074)
		(mid 158.221065 -245.356995)
		(end 158.256986 -245.371874)
		(stroke
			(width 0.2)
			(type default)
		)
		(layer "In1.Cu")
	)
	(gr_line
		(start 158.206186 -245.117874)
		(end 158.206186 -245.321074)
		(stroke
			(width 0.2)
			(type default)
		)
		(layer "In1.Cu")
	)
	(gr_arc
		(start 158.206186 -244.762274)
		(mid 158.221065 -244.798195)
		(end 158.256986 -244.813074)
		(stroke
			(width 0.2)
			(type default)
		)
		(layer "In1.Cu")
	)
	(gr_line
		(start 158.206186 -244.559074)
		(end 158.206186 -244.762274)
		(stroke
			(width 0.2)
			(type default)
		)
		(layer "In1.Cu")
	)
	(gr_arc
		(start 158.206186 -130.32105)
		(mid 158.221065 -130.356971)
		(end 158.256986 -130.37185)
		(stroke
			(width 0.2)
			(type default)
		)
		(layer "In1.Cu")
	)
	(gr_line
		(start 158.206186 -130.11785)
		(end 158.206186 -130.32105)
		(stroke
			(width 0.2)
			(type default)
		)
		(layer "In1.Cu")
	)
	(gr_arc
		(start 158.206186 -129.76225)
		(mid 158.221065 -129.798171)
		(end 158.256986 -129.81305)
		(stroke
			(width 0.2)
			(type default)
		)
		(layer "In1.Cu")
	)
	(gr_line
		(start 158.206186 -129.55905)
		(end 158.206186 -129.76225)
		(stroke
			(width 0.2)
			(type default)
		)
		(layer "In1.Cu")
	)
	(gr_arc
		(start 158.206186 -15.321026)
		(mid 158.221065 -15.356947)
		(end 158.256986 -15.371826)
		(stroke
			(width 0.2)
			(type default)
		)
		(layer "In1.Cu")
	)
	(gr_line
		(start 158.206186 -15.117826)
		(end 158.206186 -15.321026)
		(stroke
			(width 0.2)
			(type default)
		)
		(layer "In1.Cu")
	)
	(gr_arc
		(start 158.206186 -14.762226)
		(mid 158.221065 -14.798147)
		(end 158.256986 -14.813026)
		(stroke
			(width 0.2)
			(type default)
		)
		(layer "In1.Cu")
	)
	(gr_line
		(start 158.206186 -14.559026)
		(end 158.206186 -14.762226)
		(stroke
			(width 0.2)
			(type default)
		)
		(layer "In1.Cu")
	)
	(gr_arc
		(start 158.223712 -249.38482)
		(mid 158.708725 -249.870214)
		(end 159.193992 -249.385074)
		(stroke
			(width 0.2)
			(type default)
		)
		(layer "In1.Cu")
	)
	(gr_line
		(start 158.223712 -248.115074)
		(end 158.223712 -249.38482)
		(stroke
			(width 0.2)
			(type default)
		)
		(layer "In1.Cu")
	)
	(gr_arc
		(start 158.223712 -134.384796)
		(mid 158.708725 -134.87019)
		(end 159.193992 -134.38505)
		(stroke
			(width 0.2)
			(type default)
		)
		(layer "In1.Cu")
	)
	(gr_line
		(start 158.223712 -133.11505)
		(end 158.223712 -134.384796)
		(stroke
			(width 0.2)
			(type default)
		)
		(layer "In1.Cu")
	)
	(gr_arc
		(start 158.223712 -19.385026)
		(mid 158.708852 -19.870166)
		(end 159.193992 -19.385026)
		(stroke
			(width 0.2)
			(type default)
		)
		(layer "In1.Cu")
	)
	(gr_line
		(start 158.223712 -18.115026)
		(end 158.223712 -19.385026)
		(stroke
			(width 0.2)
			(type default)
		)
		(layer "In1.Cu")
	)
	(gr_line
		(start 158.256986 -245.371874)
		(end 159.069786 -245.371874)
		(stroke
			(width 0.2)
			(type default)
		)
		(layer "In1.Cu")
	)
	(gr_arc
		(start 158.256986 -245.067074)
		(mid 158.221065 -245.081953)
		(end 158.206186 -245.117874)
		(stroke
			(width 0.2)
			(type default)
		)
		(layer "In1.Cu")
	)
	(gr_line
		(start 158.256986 -244.813074)
		(end 159.069786 -244.813074)
		(stroke
			(width 0.2)
			(type default)
		)
		(layer "In1.Cu")
	)
	(gr_arc
		(start 158.256986 -244.508274)
		(mid 158.221065 -244.523153)
		(end 158.206186 -244.559074)
		(stroke
			(width 0.2)
			(type default)
		)
		(layer "In1.Cu")
	)
	(gr_line
		(start 158.256986 -130.37185)
		(end 159.069786 -130.37185)
		(stroke
			(width 0.2)
			(type default)
		)
		(layer "In1.Cu")
	)
	(gr_arc
		(start 158.256986 -130.06705)
		(mid 158.221065 -130.081929)
		(end 158.206186 -130.11785)
		(stroke
			(width 0.2)
			(type default)
		)
		(layer "In1.Cu")
	)
	(gr_line
		(start 158.256986 -129.81305)
		(end 159.069786 -129.81305)
		(stroke
			(width 0.2)
			(type default)
		)
		(layer "In1.Cu")
	)
	(gr_arc
		(start 158.256986 -129.50825)
		(mid 158.221065 -129.523129)
		(end 158.206186 -129.55905)
		(stroke
			(width 0.2)
			(type default)
		)
		(layer "In1.Cu")
	)
	(gr_line
		(start 158.256986 -15.371826)
		(end 159.069786 -15.371826)
		(stroke
			(width 0.2)
			(type default)
		)
		(layer "In1.Cu")
	)
	(gr_arc
		(start 158.256986 -15.067026)
		(mid 158.221065 -15.081905)
		(end 158.206186 -15.117826)
		(stroke
			(width 0.2)
			(type default)
		)
		(layer "In1.Cu")
	)
	(gr_line
		(start 158.256986 -14.813026)
		(end 159.069786 -14.813026)
		(stroke
			(width 0.2)
			(type default)
		)
		(layer "In1.Cu")
	)
	(gr_arc
		(start 158.256986 -14.508226)
		(mid 158.221065 -14.523105)
		(end 158.206186 -14.559026)
		(stroke
			(width 0.2)
			(type default)
		)
		(layer "In1.Cu")
	)
	(gr_arc
		(start 159.069786 -245.371874)
		(mid 159.105707 -245.356995)
		(end 159.120586 -245.321074)
		(stroke
			(width 0.2)
			(type default)
		)
		(layer "In1.Cu")
	)
	(gr_line
		(start 159.069786 -245.067074)
		(end 158.256986 -245.067074)
		(stroke
			(width 0.2)
			(type default)
		)
		(layer "In1.Cu")
	)
	(gr_arc
		(start 159.069786 -244.813074)
		(mid 159.105707 -244.798195)
		(end 159.120586 -244.762274)
		(stroke
			(width 0.2)
			(type default)
		)
		(layer "In1.Cu")
	)
	(gr_line
		(start 159.069786 -244.508274)
		(end 158.256986 -244.508274)
		(stroke
			(width 0.2)
			(type default)
		)
		(layer "In1.Cu")
	)
	(gr_arc
		(start 159.069786 -130.37185)
		(mid 159.105707 -130.356971)
		(end 159.120586 -130.32105)
		(stroke
			(width 0.2)
			(type default)
		)
		(layer "In1.Cu")
	)
	(gr_line
		(start 159.069786 -130.06705)
		(end 158.256986 -130.06705)
		(stroke
			(width 0.2)
			(type default)
		)
		(layer "In1.Cu")
	)
	(gr_arc
		(start 159.069786 -129.81305)
		(mid 159.105707 -129.798171)
		(end 159.120586 -129.76225)
		(stroke
			(width 0.2)
			(type default)
		)
		(layer "In1.Cu")
	)
	(gr_line
		(start 159.069786 -129.50825)
		(end 158.256986 -129.50825)
		(stroke
			(width 0.2)
			(type default)
		)
		(layer "In1.Cu")
	)
	(gr_arc
		(start 159.069786 -15.371826)
		(mid 159.105707 -15.356947)
		(end 159.120586 -15.321026)
		(stroke
			(width 0.2)
			(type default)
		)
		(layer "In1.Cu")
	)
	(gr_line
		(start 159.069786 -15.067026)
		(end 158.256986 -15.067026)
		(stroke
			(width 0.2)
			(type default)
		)
		(layer "In1.Cu")
	)
	(gr_arc
		(start 159.069786 -14.813026)
		(mid 159.105707 -14.798147)
		(end 159.120586 -14.762226)
		(stroke
			(width 0.2)
			(type default)
		)
		(layer "In1.Cu")
	)
	(gr_line
		(start 159.069786 -14.508226)
		(end 158.256986 -14.508226)
		(stroke
			(width 0.2)
			(type default)
		)
		(layer "In1.Cu")
	)
	(gr_line
		(start 159.120586 -245.321074)
		(end 159.120586 -245.117874)
		(stroke
			(width 0.2)
			(type default)
		)
		(layer "In1.Cu")
	)
	(gr_arc
		(start 159.120586 -245.117874)
		(mid 159.105707 -245.081953)
		(end 159.069786 -245.067074)
		(stroke
			(width 0.2)
			(type default)
		)
		(layer "In1.Cu")
	)
	(gr_line
		(start 159.120586 -244.762274)
		(end 159.120586 -244.559074)
		(stroke
			(width 0.2)
			(type default)
		)
		(layer "In1.Cu")
	)
	(gr_arc
		(start 159.120586 -244.559074)
		(mid 159.105707 -244.523153)
		(end 159.069786 -244.508274)
		(stroke
			(width 0.2)
			(type default)
		)
		(layer "In1.Cu")
	)
	(gr_line
		(start 159.120586 -130.32105)
		(end 159.120586 -130.11785)
		(stroke
			(width 0.2)
			(type default)
		)
		(layer "In1.Cu")
	)
	(gr_arc
		(start 159.120586 -130.11785)
		(mid 159.105707 -130.081929)
		(end 159.069786 -130.06705)
		(stroke
			(width 0.2)
			(type default)
		)
		(layer "In1.Cu")
	)
	(gr_line
		(start 159.120586 -129.76225)
		(end 159.120586 -129.55905)
		(stroke
			(width 0.2)
			(type default)
		)
		(layer "In1.Cu")
	)
	(gr_arc
		(start 159.120586 -129.55905)
		(mid 159.105707 -129.523129)
		(end 159.069786 -129.50825)
		(stroke
			(width 0.2)
			(type default)
		)
		(layer "In1.Cu")
	)
	(gr_line
		(start 159.120586 -15.321026)
		(end 159.120586 -15.117826)
		(stroke
			(width 0.2)
			(type default)
		)
		(layer "In1.Cu")
	)
	(gr_arc
		(start 159.120586 -15.117826)
		(mid 159.105707 -15.081905)
		(end 159.069786 -15.067026)
		(stroke
			(width 0.2)
			(type default)
		)
		(layer "In1.Cu")
	)
	(gr_line
		(start 159.120586 -14.762226)
		(end 159.120586 -14.559026)
		(stroke
			(width 0.2)
			(type default)
		)
		(layer "In1.Cu")
	)
	(gr_arc
		(start 159.120586 -14.559026)
		(mid 159.105707 -14.523105)
		(end 159.069786 -14.508226)
		(stroke
			(width 0.2)
			(type default)
		)
		(layer "In1.Cu")
	)
	(gr_line
		(start 159.193992 -249.385074)
		(end 159.193992 -248.115074)
		(stroke
			(width 0.2)
			(type default)
		)
		(layer "In1.Cu")
	)
	(gr_arc
		(start 159.193992 -248.115074)
		(mid 158.708852 -247.629934)
		(end 158.223712 -248.115074)
		(stroke
			(width 0.2)
			(type default)
		)
		(layer "In1.Cu")
	)
	(gr_line
		(start 159.193992 -134.38505)
		(end 159.193992 -133.11505)
		(stroke
			(width 0.2)
			(type default)
		)
		(layer "In1.Cu")
	)
	(gr_arc
		(start 159.193992 -133.11505)
		(mid 158.708852 -132.62991)
		(end 158.223712 -133.11505)
		(stroke
			(width 0.2)
			(type default)
		)
		(layer "In1.Cu")
	)
	(gr_line
		(start 159.193992 -19.385026)
		(end 159.193992 -18.11528)
		(stroke
			(width 0.2)
			(type default)
		)
		(layer "In1.Cu")
	)
	(gr_arc
		(start 159.193992 -18.11528)
		(mid 158.708979 -17.629886)
		(end 158.223712 -18.115026)
		(stroke
			(width 0.2)
			(type default)
		)
		(layer "In1.Cu")
	)
	(gr_arc
		(start 160.000442 -245.56212)
		(mid 160.485455 -246.047514)
		(end 160.970722 -245.562374)
		(stroke
			(width 0.2)
			(type default)
		)
		(layer "In1.Cu")
	)
	(gr_line
		(start 160.000442 -244.419374)
		(end 160.000442 -245.56212)
		(stroke
			(width 0.2)
			(type default)
		)
		(layer "In1.Cu")
	)
	(gr_arc
		(start 160.000442 -130.56235)
		(mid 160.485582 -131.04749)
		(end 160.970722 -130.56235)
		(stroke
			(width 0.2)
			(type default)
		)
		(layer "In1.Cu")
	)
	(gr_line
		(start 160.000442 -129.41935)
		(end 160.000442 -130.56235)
		(stroke
			(width 0.2)
			(type default)
		)
		(layer "In1.Cu")
	)
	(gr_arc
		(start 160.000442 -15.562326)
		(mid 160.485582 -16.047466)
		(end 160.970722 -15.562326)
		(stroke
			(width 0.2)
			(type default)
		)
		(layer "In1.Cu")
	)
	(gr_line
		(start 160.000442 -14.419326)
		(end 160.000442 -15.562326)
		(stroke
			(width 0.2)
			(type default)
		)
		(layer "In1.Cu")
	)
	(gr_line
		(start 160.782 -358.394)
		(end 160.782 -328.93)
		(stroke
			(width 0.381)
			(type default)
		)
		(layer "In1.Cu")
	)
	(gr_line
		(start 160.782 -328.93)
		(end 157.988 -328.93)
		(stroke
			(width 0.381)
			(type default)
		)
		(layer "In1.Cu")
	)
	(gr_line
		(start 160.970722 -245.562374)
		(end 160.970722 -244.419374)
		(stroke
			(width 0.2)
			(type default)
		)
		(layer "In1.Cu")
	)
	(gr_arc
		(start 160.970722 -244.419374)
		(mid 160.485582 -243.934234)
		(end 160.000442 -244.419374)
		(stroke
			(width 0.2)
			(type default)
		)
		(layer "In1.Cu")
	)
	(gr_line
		(start 160.970722 -130.56235)
		(end 160.970722 -129.419604)
		(stroke
			(width 0.2)
			(type default)
		)
		(layer "In1.Cu")
	)
	(gr_arc
		(start 160.970722 -129.419604)
		(mid 160.485709 -128.93421)
		(end 160.000442 -129.41935)
		(stroke
			(width 0.2)
			(type default)
		)
		(layer "In1.Cu")
	)
	(gr_line
		(start 160.970722 -15.562326)
		(end 160.970722 -14.41958)
		(stroke
			(width 0.2)
			(type default)
		)
		(layer "In1.Cu")
	)
	(gr_arc
		(start 160.970722 -14.41958)
		(mid 160.485709 -13.934186)
		(end 160.000442 -14.419326)
		(stroke
			(width 0.2)
			(type default)
		)
		(layer "In1.Cu")
	)
	(gr_line
		(start 161.262314 -374.637046)
		(end 165.668198 -379.04293)
		(stroke
			(width 0.381)
			(type default)
		)
		(layer "In1.Cu")
	)
	(gr_line
		(start 161.262314 -361.83189)
		(end 161.262314 -374.637046)
		(stroke
			(width 0.381)
			(type default)
		)
		(layer "In1.Cu")
	)
	(gr_line
		(start 161.70656 -361.387644)
		(end 161.262314 -361.83189)
		(stroke
			(width 0.381)
			(type default)
		)
		(layer "In1.Cu")
	)
	(gr_line
		(start 165.668198 -379.04293)
		(end 172.13707 -379.04293)
		(stroke
			(width 0.381)
			(type default)
		)
		(layer "In1.Cu")
	)
	(gr_line
		(start 166.2049 -358.394)
		(end 204.1906 -358.394)
		(stroke
			(width 0.381)
			(type default)
		)
		(layer "In1.Cu")
	)
	(gr_line
		(start 166.2049 -328.93)
		(end 166.2049 -358.394)
		(stroke
			(width 0.381)
			(type default)
		)
		(layer "In1.Cu")
	)
	(gr_line
		(start 166.5859 -328.93)
		(end 166.2049 -328.93)
		(stroke
			(width 0.381)
			(type default)
		)
		(layer "In1.Cu")
	)
	(gr_line
		(start 167.694356 -361.387644)
		(end 161.70656 -361.387644)
		(stroke
			(width 0.381)
			(type default)
		)
		(layer "In1.Cu")
	)
	(gr_line
		(start 169.291 -359.791)
		(end 167.694356 -361.387644)
		(stroke
			(width 0.381)
			(type default)
		)
		(layer "In1.Cu")
	)
	(gr_line
		(start 172.13707 -379.04293)
		(end 175.387 -375.793)
		(stroke
			(width 0.381)
			(type default)
		)
		(layer "In1.Cu")
	)
	(gr_line
		(start 172.850048 -385.99999)
		(end 127.299974 -385.99999)
		(stroke
			(width 1.524)
			(type default)
		)
		(layer "In1.Cu")
	)
	(gr_arc
		(start 172.850048 -385.99999)
		(mid 173.55712 -385.70708)
		(end 173.850046 -384.999992)
		(stroke
			(width 1.524)
			(type default)
		)
		(layer "In1.Cu")
	)
	(gr_line
		(start 173.850046 -383.29997)
		(end 173.850046 -384.999992)
		(stroke
			(width 1.524)
			(type default)
		)
		(layer "In1.Cu")
	)
	(gr_arc
		(start 174.850044 -382.299972)
		(mid 174.142939 -382.592865)
		(end 173.850046 -383.29997)
		(stroke
			(width 1.524)
			(type default)
		)
		(layer "In1.Cu")
	)
	(gr_line
		(start 175.387 -375.793)
		(end 181.864 -375.793)
		(stroke
			(width 0.381)
			(type default)
		)
		(layer "In1.Cu")
	)
	(gr_line
		(start 179.092352 -359.791)
		(end 169.291 -359.791)
		(stroke
			(width 0.381)
			(type default)
		)
		(layer "In1.Cu")
	)
	(gr_line
		(start 181.349904 -382.299972)
		(end 174.850044 -382.299972)
		(stroke
			(width 1.524)
			(type default)
		)
		(layer "In1.Cu")
	)
	(gr_line
		(start 181.864 -375.793)
		(end 184.785 -372.872)
		(stroke
			(width 0.381)
			(type default)
		)
		(layer "In1.Cu")
	)
	(gr_line
		(start 182.349902 -384.999992)
		(end 182.349902 -383.29997)
		(stroke
			(width 1.524)
			(type default)
		)
		(layer "In1.Cu")
	)
	(gr_arc
		(start 182.349902 -384.999992)
		(mid 182.642792 -385.707103)
		(end 183.3499 -385.99999)
		(stroke
			(width 1.524)
			(type default)
		)
		(layer "In1.Cu")
	)
	(gr_arc
		(start 182.349902 -383.29997)
		(mid 182.057009 -382.592865)
		(end 181.349904 -382.299972)
		(stroke
			(width 1.524)
			(type default)
		)
		(layer "In1.Cu")
	)
	(gr_line
		(start 184.785 -372.872)
		(end 184.785 -370.078)
		(stroke
			(width 0.381)
			(type default)
		)
		(layer "In1.Cu")
	)
	(gr_line
		(start 184.785 -370.078)
		(end 186.055 -368.808)
		(stroke
			(width 0.381)
			(type default)
		)
		(layer "In1.Cu")
	)
	(gr_line
		(start 186.055 -368.808)
		(end 186.055 -366.753648)
		(stroke
			(width 0.381)
			(type default)
		)
		(layer "In1.Cu")
	)
	(gr_line
		(start 186.055 -366.753648)
		(end 179.092352 -359.791)
		(stroke
			(width 0.381)
			(type default)
		)
		(layer "In1.Cu")
	)
	(gr_line
		(start 186.593988 -250.350274)
		(end 186.593988 -247.149874)
		(stroke
			(width 0.2)
			(type default)
		)
		(layer "In1.Cu")
	)
	(gr_line
		(start 186.593988 -247.149874)
		(end 188.956188 -247.149874)
		(stroke
			(width 0.2)
			(type default)
		)
		(layer "In1.Cu")
	)
	(gr_line
		(start 186.593988 -246.540274)
		(end 186.593988 -243.339874)
		(stroke
			(width 0.2)
			(type default)
		)
		(layer "In1.Cu")
	)
	(gr_line
		(start 186.593988 -243.339874)
		(end 188.956188 -243.339874)
		(stroke
			(width 0.2)
			(type default)
		)
		(layer "In1.Cu")
	)
	(gr_line
		(start 186.593988 -135.35025)
		(end 186.593988 -132.14985)
		(stroke
			(width 0.2)
			(type default)
		)
		(layer "In1.Cu")
	)
	(gr_line
		(start 186.593988 -132.14985)
		(end 188.956188 -132.14985)
		(stroke
			(width 0.2)
			(type default)
		)
		(layer "In1.Cu")
	)
	(gr_line
		(start 186.593988 -131.54025)
		(end 186.593988 -128.33985)
		(stroke
			(width 0.2)
			(type default)
		)
		(layer "In1.Cu")
	)
	(gr_line
		(start 186.593988 -128.33985)
		(end 188.956188 -128.33985)
		(stroke
			(width 0.2)
			(type default)
		)
		(layer "In1.Cu")
	)
	(gr_line
		(start 186.593988 -20.350226)
		(end 186.593988 -17.149826)
		(stroke
			(width 0.2)
			(type default)
		)
		(layer "In1.Cu")
	)
	(gr_line
		(start 186.593988 -17.149826)
		(end 188.956188 -17.149826)
		(stroke
			(width 0.2)
			(type default)
		)
		(layer "In1.Cu")
	)
	(gr_line
		(start 186.593988 -16.540226)
		(end 186.593988 -13.339826)
		(stroke
			(width 0.2)
			(type default)
		)
		(layer "In1.Cu")
	)
	(gr_line
		(start 186.593988 -13.339826)
		(end 188.956188 -13.339826)
		(stroke
			(width 0.2)
			(type default)
		)
		(layer "In1.Cu")
	)
	(gr_line
		(start 188.956188 -250.350274)
		(end 186.593988 -250.350274)
		(stroke
			(width 0.2)
			(type default)
		)
		(layer "In1.Cu")
	)
	(gr_line
		(start 188.956188 -247.149874)
		(end 188.956188 -250.350274)
		(stroke
			(width 0.2)
			(type default)
		)
		(layer "In1.Cu")
	)
	(gr_line
		(start 188.956188 -246.540274)
		(end 186.593988 -246.540274)
		(stroke
			(width 0.2)
			(type default)
		)
		(layer "In1.Cu")
	)
	(gr_line
		(start 188.956188 -243.339874)
		(end 188.956188 -246.540274)
		(stroke
			(width 0.2)
			(type default)
		)
		(layer "In1.Cu")
	)
	(gr_line
		(start 188.956188 -135.35025)
		(end 186.593988 -135.35025)
		(stroke
			(width 0.2)
			(type default)
		)
		(layer "In1.Cu")
	)
	(gr_line
		(start 188.956188 -132.14985)
		(end 188.956188 -135.35025)
		(stroke
			(width 0.2)
			(type default)
		)
		(layer "In1.Cu")
	)
	(gr_line
		(start 188.956188 -131.54025)
		(end 186.593988 -131.54025)
		(stroke
			(width 0.2)
			(type default)
		)
		(layer "In1.Cu")
	)
	(gr_line
		(start 188.956188 -128.33985)
		(end 188.956188 -131.54025)
		(stroke
			(width 0.2)
			(type default)
		)
		(layer "In1.Cu")
	)
	(gr_line
		(start 188.956188 -20.350226)
		(end 186.593988 -20.350226)
		(stroke
			(width 0.2)
			(type default)
		)
		(layer "In1.Cu")
	)
	(gr_line
		(start 188.956188 -17.149826)
		(end 188.956188 -20.350226)
		(stroke
			(width 0.2)
			(type default)
		)
		(layer "In1.Cu")
	)
	(gr_line
		(start 188.956188 -16.540226)
		(end 186.593988 -16.540226)
		(stroke
			(width 0.2)
			(type default)
		)
		(layer "In1.Cu")
	)
	(gr_line
		(start 188.956188 -13.339826)
		(end 188.956188 -16.540226)
		(stroke
			(width 0.2)
			(type default)
		)
		(layer "In1.Cu")
	)
	(gr_arc
		(start 189.756288 -245.321074)
		(mid 189.771167 -245.356995)
		(end 189.807088 -245.371874)
		(stroke
			(width 0.2)
			(type default)
		)
		(layer "In1.Cu")
	)
	(gr_line
		(start 189.756288 -245.117874)
		(end 189.756288 -245.321074)
		(stroke
			(width 0.2)
			(type default)
		)
		(layer "In1.Cu")
	)
	(gr_arc
		(start 189.756288 -244.762274)
		(mid 189.771167 -244.798195)
		(end 189.807088 -244.813074)
		(stroke
			(width 0.2)
			(type default)
		)
		(layer "In1.Cu")
	)
	(gr_line
		(start 189.756288 -244.559074)
		(end 189.756288 -244.762274)
		(stroke
			(width 0.2)
			(type default)
		)
		(layer "In1.Cu")
	)
	(gr_arc
		(start 189.756288 -130.32105)
		(mid 189.771167 -130.356971)
		(end 189.807088 -130.37185)
		(stroke
			(width 0.2)
			(type default)
		)
		(layer "In1.Cu")
	)
	(gr_line
		(start 189.756288 -130.11785)
		(end 189.756288 -130.32105)
		(stroke
			(width 0.2)
			(type default)
		)
		(layer "In1.Cu")
	)
	(gr_arc
		(start 189.756288 -129.76225)
		(mid 189.771167 -129.798171)
		(end 189.807088 -129.81305)
		(stroke
			(width 0.2)
			(type default)
		)
		(layer "In1.Cu")
	)
	(gr_line
		(start 189.756288 -129.55905)
		(end 189.756288 -129.76225)
		(stroke
			(width 0.2)
			(type default)
		)
		(layer "In1.Cu")
	)
	(gr_arc
		(start 189.756288 -15.321026)
		(mid 189.771167 -15.356947)
		(end 189.807088 -15.371826)
		(stroke
			(width 0.2)
			(type default)
		)
		(layer "In1.Cu")
	)
	(gr_line
		(start 189.756288 -15.117826)
		(end 189.756288 -15.321026)
		(stroke
			(width 0.2)
			(type default)
		)
		(layer "In1.Cu")
	)
	(gr_arc
		(start 189.756288 -14.762226)
		(mid 189.771167 -14.798147)
		(end 189.807088 -14.813026)
		(stroke
			(width 0.2)
			(type default)
		)
		(layer "In1.Cu")
	)
	(gr_line
		(start 189.756288 -14.559026)
		(end 189.756288 -14.762226)
		(stroke
			(width 0.2)
			(type default)
		)
		(layer "In1.Cu")
	)
	(gr_arc
		(start 189.773814 -249.385074)
		(mid 190.258954 -249.870214)
		(end 190.744094 -249.385074)
		(stroke
			(width 0.2)
			(type default)
		)
		(layer "In1.Cu")
	)
	(gr_line
		(start 189.773814 -248.115074)
		(end 189.773814 -249.385074)
		(stroke
			(width 0.2)
			(type default)
		)
		(layer "In1.Cu")
	)
	(gr_arc
		(start 189.773814 -134.38505)
		(mid 190.258954 -134.87019)
		(end 190.744094 -134.38505)
		(stroke
			(width 0.2)
			(type default)
		)
		(layer "In1.Cu")
	)
	(gr_line
		(start 189.773814 -133.11505)
		(end 189.773814 -134.38505)
		(stroke
			(width 0.2)
			(type default)
		)
		(layer "In1.Cu")
	)
	(gr_arc
		(start 189.773814 -19.385026)
		(mid 190.258954 -19.870166)
		(end 190.744094 -19.385026)
		(stroke
			(width 0.2)
			(type default)
		)
		(layer "In1.Cu")
	)
	(gr_line
		(start 189.773814 -18.115026)
		(end 189.773814 -19.385026)
		(stroke
			(width 0.2)
			(type default)
		)
		(layer "In1.Cu")
	)
	(gr_line
		(start 189.807088 -245.371874)
		(end 190.619888 -245.371874)
		(stroke
			(width 0.2)
			(type default)
		)
		(layer "In1.Cu")
	)
	(gr_arc
		(start 189.807088 -245.067074)
		(mid 189.771167 -245.081953)
		(end 189.756288 -245.117874)
		(stroke
			(width 0.2)
			(type default)
		)
		(layer "In1.Cu")
	)
	(gr_line
		(start 189.807088 -244.813074)
		(end 190.619888 -244.813074)
		(stroke
			(width 0.2)
			(type default)
		)
		(layer "In1.Cu")
	)
	(gr_arc
		(start 189.807088 -244.508274)
		(mid 189.771167 -244.523153)
		(end 189.756288 -244.559074)
		(stroke
			(width 0.2)
			(type default)
		)
		(layer "In1.Cu")
	)
	(gr_line
		(start 189.807088 -130.37185)
		(end 190.619888 -130.37185)
		(stroke
			(width 0.2)
			(type default)
		)
		(layer "In1.Cu")
	)
	(gr_arc
		(start 189.807088 -130.06705)
		(mid 189.771167 -130.081929)
		(end 189.756288 -130.11785)
		(stroke
			(width 0.2)
			(type default)
		)
		(layer "In1.Cu")
	)
	(gr_line
		(start 189.807088 -129.81305)
		(end 190.619888 -129.81305)
		(stroke
			(width 0.2)
			(type default)
		)
		(layer "In1.Cu")
	)
	(gr_arc
		(start 189.807088 -129.50825)
		(mid 189.771167 -129.523129)
		(end 189.756288 -129.55905)
		(stroke
			(width 0.2)
			(type default)
		)
		(layer "In1.Cu")
	)
	(gr_line
		(start 189.807088 -15.371826)
		(end 190.619888 -15.371826)
		(stroke
			(width 0.2)
			(type default)
		)
		(layer "In1.Cu")
	)
	(gr_arc
		(start 189.807088 -15.067026)
		(mid 189.771167 -15.081905)
		(end 189.756288 -15.117826)
		(stroke
			(width 0.2)
			(type default)
		)
		(layer "In1.Cu")
	)
	(gr_line
		(start 189.807088 -14.813026)
		(end 190.619888 -14.813026)
		(stroke
			(width 0.2)
			(type default)
		)
		(layer "In1.Cu")
	)
	(gr_arc
		(start 189.807088 -14.508226)
		(mid 189.771167 -14.523105)
		(end 189.756288 -14.559026)
		(stroke
			(width 0.2)
			(type default)
		)
		(layer "In1.Cu")
	)
	(gr_arc
		(start 190.619888 -245.371874)
		(mid 190.655809 -245.356995)
		(end 190.670688 -245.321074)
		(stroke
			(width 0.2)
			(type default)
		)
		(layer "In1.Cu")
	)
	(gr_line
		(start 190.619888 -245.067074)
		(end 189.807088 -245.067074)
		(stroke
			(width 0.2)
			(type default)
		)
		(layer "In1.Cu")
	)
	(gr_arc
		(start 190.619888 -244.813074)
		(mid 190.655809 -244.798195)
		(end 190.670688 -244.762274)
		(stroke
			(width 0.2)
			(type default)
		)
		(layer "In1.Cu")
	)
	(gr_line
		(start 190.619888 -244.508274)
		(end 189.807088 -244.508274)
		(stroke
			(width 0.2)
			(type default)
		)
		(layer "In1.Cu")
	)
	(gr_arc
		(start 190.619888 -130.37185)
		(mid 190.655809 -130.356971)
		(end 190.670688 -130.32105)
		(stroke
			(width 0.2)
			(type default)
		)
		(layer "In1.Cu")
	)
	(gr_line
		(start 190.619888 -130.06705)
		(end 189.807088 -130.06705)
		(stroke
			(width 0.2)
			(type default)
		)
		(layer "In1.Cu")
	)
	(gr_arc
		(start 190.619888 -129.81305)
		(mid 190.655809 -129.798171)
		(end 190.670688 -129.76225)
		(stroke
			(width 0.2)
			(type default)
		)
		(layer "In1.Cu")
	)
	(gr_line
		(start 190.619888 -129.50825)
		(end 189.807088 -129.50825)
		(stroke
			(width 0.2)
			(type default)
		)
		(layer "In1.Cu")
	)
	(gr_arc
		(start 190.619888 -15.371826)
		(mid 190.655809 -15.356947)
		(end 190.670688 -15.321026)
		(stroke
			(width 0.2)
			(type default)
		)
		(layer "In1.Cu")
	)
	(gr_line
		(start 190.619888 -15.067026)
		(end 189.807088 -15.067026)
		(stroke
			(width 0.2)
			(type default)
		)
		(layer "In1.Cu")
	)
	(gr_arc
		(start 190.619888 -14.813026)
		(mid 190.655809 -14.798147)
		(end 190.670688 -14.762226)
		(stroke
			(width 0.2)
			(type default)
		)
		(layer "In1.Cu")
	)
	(gr_line
		(start 190.619888 -14.508226)
		(end 189.807088 -14.508226)
		(stroke
			(width 0.2)
			(type default)
		)
		(layer "In1.Cu")
	)
	(gr_line
		(start 190.670688 -245.321074)
		(end 190.670688 -245.117874)
		(stroke
			(width 0.2)
			(type default)
		)
		(layer "In1.Cu")
	)
	(gr_arc
		(start 190.670688 -245.117874)
		(mid 190.655809 -245.081953)
		(end 190.619888 -245.067074)
		(stroke
			(width 0.2)
			(type default)
		)
		(layer "In1.Cu")
	)
	(gr_line
		(start 190.670688 -244.762274)
		(end 190.670688 -244.559074)
		(stroke
			(width 0.2)
			(type default)
		)
		(layer "In1.Cu")
	)
	(gr_arc
		(start 190.670688 -244.559074)
		(mid 190.655809 -244.523153)
		(end 190.619888 -244.508274)
		(stroke
			(width 0.2)
			(type default)
		)
		(layer "In1.Cu")
	)
	(gr_line
		(start 190.670688 -130.32105)
		(end 190.670688 -130.11785)
		(stroke
			(width 0.2)
			(type default)
		)
		(layer "In1.Cu")
	)
	(gr_arc
		(start 190.670688 -130.11785)
		(mid 190.655809 -130.081929)
		(end 190.619888 -130.06705)
		(stroke
			(width 0.2)
			(type default)
		)
		(layer "In1.Cu")
	)
	(gr_line
		(start 190.670688 -129.76225)
		(end 190.670688 -129.55905)
		(stroke
			(width 0.2)
			(type default)
		)
		(layer "In1.Cu")
	)
	(gr_arc
		(start 190.670688 -129.55905)
		(mid 190.655809 -129.523129)
		(end 190.619888 -129.50825)
		(stroke
			(width 0.2)
			(type default)
		)
		(layer "In1.Cu")
	)
	(gr_line
		(start 190.670688 -15.321026)
		(end 190.670688 -15.117826)
		(stroke
			(width 0.2)
			(type default)
		)
		(layer "In1.Cu")
	)
	(gr_arc
		(start 190.670688 -15.117826)
		(mid 190.655809 -15.081905)
		(end 190.619888 -15.067026)
		(stroke
			(width 0.2)
			(type default)
		)
		(layer "In1.Cu")
	)
	(gr_line
		(start 190.670688 -14.762226)
		(end 190.670688 -14.559026)
		(stroke
			(width 0.2)
			(type default)
		)
		(layer "In1.Cu")
	)
	(gr_arc
		(start 190.670688 -14.559026)
		(mid 190.655809 -14.523105)
		(end 190.619888 -14.508226)
		(stroke
			(width 0.2)
			(type default)
		)
		(layer "In1.Cu")
	)
	(gr_line
		(start 190.744094 -249.385074)
		(end 190.744094 -248.115328)
		(stroke
			(width 0.2)
			(type default)
		)
		(layer "In1.Cu")
	)
	(gr_arc
		(start 190.744094 -248.115328)
		(mid 190.259081 -247.629934)
		(end 189.773814 -248.115074)
		(stroke
			(width 0.2)
			(type default)
		)
		(layer "In1.Cu")
	)
	(gr_line
		(start 190.744094 -134.38505)
		(end 190.744094 -133.115304)
		(stroke
			(width 0.2)
			(type default)
		)
		(layer "In1.Cu")
	)
	(gr_arc
		(start 190.744094 -133.115304)
		(mid 190.259081 -132.62991)
		(end 189.773814 -133.11505)
		(stroke
			(width 0.2)
			(type default)
		)
		(layer "In1.Cu")
	)
	(gr_line
		(start 190.744094 -19.385026)
		(end 190.744094 -18.11528)
		(stroke
			(width 0.2)
			(type default)
		)
		(layer "In1.Cu")
	)
	(gr_arc
		(start 190.744094 -18.11528)
		(mid 190.259081 -17.629886)
		(end 189.773814 -18.115026)
		(stroke
			(width 0.2)
			(type default)
		)
		(layer "In1.Cu")
	)
	(gr_arc
		(start 191.550544 -245.56212)
		(mid 192.035557 -246.047514)
		(end 192.520824 -245.562374)
		(stroke
			(width 0.2)
			(type default)
		)
		(layer "In1.Cu")
	)
	(gr_line
		(start 191.550544 -244.419374)
		(end 191.550544 -245.56212)
		(stroke
			(width 0.2)
			(type default)
		)
		(layer "In1.Cu")
	)
	(gr_arc
		(start 191.550544 -130.56235)
		(mid 192.035684 -131.04749)
		(end 192.520824 -130.56235)
		(stroke
			(width 0.2)
			(type default)
		)
		(layer "In1.Cu")
	)
	(gr_line
		(start 191.550544 -129.41935)
		(end 191.550544 -130.56235)
		(stroke
			(width 0.2)
			(type default)
		)
		(layer "In1.Cu")
	)
	(gr_arc
		(start 191.550544 -15.562326)
		(mid 192.035684 -16.047466)
		(end 192.520824 -15.562326)
		(stroke
			(width 0.2)
			(type default)
		)
		(layer "In1.Cu")
	)
	(gr_line
		(start 191.550544 -14.419326)
		(end 191.550544 -15.562326)
		(stroke
			(width 0.2)
			(type default)
		)
		(layer "In1.Cu")
	)
	(gr_line
		(start 192.520824 -245.562374)
		(end 192.520824 -244.419374)
		(stroke
			(width 0.2)
			(type default)
		)
		(layer "In1.Cu")
	)
	(gr_arc
		(start 192.520824 -244.419374)
		(mid 192.035684 -243.934234)
		(end 191.550544 -244.419374)
		(stroke
			(width 0.2)
			(type default)
		)
		(layer "In1.Cu")
	)
	(gr_line
		(start 192.520824 -130.56235)
		(end 192.520824 -129.419604)
		(stroke
			(width 0.2)
			(type default)
		)
		(layer "In1.Cu")
	)
	(gr_arc
		(start 192.520824 -129.419604)
		(mid 192.035811 -128.93421)
		(end 191.550544 -129.41935)
		(stroke
			(width 0.2)
			(type default)
		)
		(layer "In1.Cu")
	)
	(gr_line
		(start 192.520824 -15.562326)
		(end 192.520824 -14.41958)
		(stroke
			(width 0.2)
			(type default)
		)
		(layer "In1.Cu")
	)
	(gr_arc
		(start 192.520824 -14.41958)
		(mid 192.035811 -13.934186)
		(end 191.550544 -14.419326)
		(stroke
			(width 0.2)
			(type default)
		)
		(layer "In1.Cu")
	)
	(gr_line
		(start 197.000114 -385.99999)
		(end 183.3499 -385.99999)
		(stroke
			(width 1.524)
			(type default)
		)
		(layer "In1.Cu")
	)
	(gr_arc
		(start 197.000114 -385.99999)
		(mid 197.707207 -385.707092)
		(end 198.000112 -384.999992)
		(stroke
			(width 1.524)
			(type default)
		)
		(layer "In1.Cu")
	)
	(gr_line
		(start 198.000112 -381)
		(end 198.000112 -384.999992)
		(stroke
			(width 1.524)
			(type default)
		)
		(layer "In1.Cu")
	)
	(gr_arc
		(start 199.00011 -380.000002)
		(mid 198.293005 -380.292895)
		(end 198.000112 -381)
		(stroke
			(width 1.524)
			(type default)
		)
		(layer "In1.Cu")
	)
	(gr_arc
		(start 199.00011 -47.200058)
		(mid 199.293003 -47.907163)
		(end 200.000108 -48.200056)
		(stroke
			(width 1.524)
			(type default)
		)
		(layer "In1.Cu")
	)
	(gr_arc
		(start 199.00011 -0.999998)
		(mid 198.707217 -0.29289)
		(end 198.000112 0)
		(stroke
			(width 1.524)
			(type default)
		)
		(layer "In1.Cu")
	)
	(gr_line
		(start 199.00011 -0.999998)
		(end 199.00011 -47.200058)
		(stroke
			(width 1.524)
			(type default)
		)
		(layer "In1.Cu")
	)
	(gr_line
		(start 200.000108 -48.200056)
		(end 206.000096 -48.200056)
		(stroke
			(width 1.524)
			(type default)
		)
		(layer "In1.Cu")
	)
	(gr_line
		(start 204.1906 -358.394)
		(end 204.6351 -357.9495)
		(stroke
			(width 0.381)
			(type default)
		)
		(layer "In1.Cu")
	)
	(gr_line
		(start 204.2287 -328.93)
		(end 166.5859 -328.93)
		(stroke
			(width 0.381)
			(type default)
		)
		(layer "In1.Cu")
	)
	(gr_line
		(start 204.6351 -357.9495)
		(end 204.6351 -329.3364)
		(stroke
			(width 0.381)
			(type default)
		)
		(layer "In1.Cu")
	)
	(gr_line
		(start 204.6351 -329.3364)
		(end 204.2287 -328.93)
		(stroke
			(width 0.381)
			(type default)
		)
		(layer "In1.Cu")
	)
	(gr_arc
		(start 207.000094 -61.999876)
		(mid 207.292987 -62.706981)
		(end 208.000092 -62.999874)
		(stroke
			(width 1.524)
			(type default)
		)
		(layer "In1.Cu")
	)
	(gr_arc
		(start 207.000094 -49.200054)
		(mid 206.707185 -48.49298)
		(end 206.000096 -48.200056)
		(stroke
			(width 1.524)
			(type default)
		)
		(layer "In1.Cu")
	)
	(gr_line
		(start 207.000094 -49.200054)
		(end 207.000094 -61.999876)
		(stroke
			(width 1.524)
			(type default)
		)
		(layer "In1.Cu")
	)
	(gr_line
		(start 208.000092 -62.999874)
		(end 267.999972 -62.999874)
		(stroke
			(width 1.524)
			(type default)
		)
		(layer "In1.Cu")
	)
	(gr_arc
		(start 209.451448 -78.999842)
		(mid 210.000088 -79.548482)
		(end 210.548728 -78.999842)
		(stroke
			(width 0.2)
			(type default)
		)
		(layer "In1.Cu")
	)
	(gr_line
		(start 209.451448 -77.600048)
		(end 209.451448 -78.999842)
		(stroke
			(width 0.2)
			(type default)
		)
		(layer "In1.Cu")
	)
	(gr_arc
		(start 209.451448 -75.399646)
		(mid 209.999961 -75.94854)
		(end 210.548728 -75.3999)
		(stroke
			(width 0.2)
			(type default)
		)
		(layer "In1.Cu")
	)
	(gr_line
		(start 209.451448 -73.999852)
		(end 209.451448 -75.399646)
		(stroke
			(width 0.2)
			(type default)
		)
		(layer "In1.Cu")
	)
	(gr_arc
		(start 209.451448 -71.799704)
		(mid 209.999961 -72.348598)
		(end 210.548728 -71.799958)
		(stroke
			(width 0.2)
			(type default)
		)
		(layer "In1.Cu")
	)
	(gr_line
		(start 209.451448 -70.39991)
		(end 209.451448 -71.799704)
		(stroke
			(width 0.2)
			(type default)
		)
		(layer "In1.Cu")
	)
	(gr_line
		(start 210.548728 -78.999842)
		(end 210.548728 -77.600302)
		(stroke
			(width 0.2)
			(type default)
		)
		(layer "In1.Cu")
	)
	(gr_arc
		(start 210.548728 -77.600302)
		(mid 210.000215 -77.051408)
		(end 209.451448 -77.600048)
		(stroke
			(width 0.2)
			(type default)
		)
		(layer "In1.Cu")
	)
	(gr_line
		(start 210.548728 -75.3999)
		(end 210.548728 -73.999852)
		(stroke
			(width 0.2)
			(type default)
		)
		(layer "In1.Cu")
	)
	(gr_arc
		(start 210.548728 -73.999852)
		(mid 210.000088 -73.451212)
		(end 209.451448 -73.999852)
		(stroke
			(width 0.2)
			(type default)
		)
		(layer "In1.Cu")
	)
	(gr_line
		(start 210.548728 -71.799958)
		(end 210.548728 -70.39991)
		(stroke
			(width 0.2)
			(type default)
		)
		(layer "In1.Cu")
	)
	(gr_arc
		(start 210.548728 -70.39991)
		(mid 210.000088 -69.85127)
		(end 209.451448 -70.39991)
		(stroke
			(width 0.2)
			(type default)
		)
		(layer "In1.Cu")
	)
	(gr_arc
		(start 211.251546 -77.799692)
		(mid 211.800059 -78.348586)
		(end 212.348826 -77.799946)
		(stroke
			(width 0.2)
			(type default)
		)
		(layer "In1.Cu")
	)
	(gr_line
		(start 211.251546 -76.399898)
		(end 211.251546 -77.799692)
		(stroke
			(width 0.2)
			(type default)
		)
		(layer "In1.Cu")
	)
	(gr_arc
		(start 211.251546 -66.999612)
		(mid 211.800059 -67.548506)
		(end 212.348826 -66.999866)
		(stroke
			(width 0.2)
			(type default)
		)
		(layer "In1.Cu")
	)
	(gr_line
		(start 211.251546 -65.600072)
		(end 211.251546 -66.999612)
		(stroke
			(width 0.2)
			(type default)
		)
		(layer "In1.Cu")
	)
	(gr_line
		(start 212.348826 -77.799946)
		(end 212.348826 -76.399898)
		(stroke
			(width 0.2)
			(type default)
		)
		(layer "In1.Cu")
	)
	(gr_arc
		(start 212.348826 -76.399898)
		(mid 211.800186 -75.851258)
		(end 211.251546 -76.399898)
		(stroke
			(width 0.2)
			(type default)
		)
		(layer "In1.Cu")
	)
	(gr_line
		(start 212.348826 -66.999866)
		(end 212.348826 -65.600072)
		(stroke
			(width 0.2)
			(type default)
		)
		(layer "In1.Cu")
	)
	(gr_arc
		(start 212.348826 -65.600072)
		(mid 211.800186 -65.051432)
		(end 211.251546 -65.600072)
		(stroke
			(width 0.2)
			(type default)
		)
		(layer "In1.Cu")
	)
	(gr_arc
		(start 213.05139 -78.999842)
		(mid 213.60003 -79.548482)
		(end 214.14867 -78.999842)
		(stroke
			(width 0.2)
			(type default)
		)
		(layer "In1.Cu")
	)
	(gr_line
		(start 213.05139 -77.600048)
		(end 213.05139 -78.999842)
		(stroke
			(width 0.2)
			(type default)
		)
		(layer "In1.Cu")
	)
	(gr_arc
		(start 213.05139 -71.799704)
		(mid 213.599903 -72.348598)
		(end 214.14867 -71.799958)
		(stroke
			(width 0.2)
			(type default)
		)
		(layer "In1.Cu")
	)
	(gr_line
		(start 213.05139 -70.39991)
		(end 213.05139 -71.799704)
		(stroke
			(width 0.2)
			(type default)
		)
		(layer "In1.Cu")
	)
	(gr_line
		(start 214.14867 -78.999842)
		(end 214.14867 -77.600302)
		(stroke
			(width 0.2)
			(type default)
		)
		(layer "In1.Cu")
	)
	(gr_arc
		(start 214.14867 -77.600302)
		(mid 213.600157 -77.051408)
		(end 213.05139 -77.600048)
		(stroke
			(width 0.2)
			(type default)
		)
		(layer "In1.Cu")
	)
	(gr_line
		(start 214.14867 -71.799958)
		(end 214.14867 -70.39991)
		(stroke
			(width 0.2)
			(type default)
		)
		(layer "In1.Cu")
	)
	(gr_arc
		(start 214.14867 -70.39991)
		(mid 213.60003 -69.85127)
		(end 213.05139 -70.39991)
		(stroke
			(width 0.2)
			(type default)
		)
		(layer "In1.Cu")
	)
	(gr_arc
		(start 214.851488 -77.799692)
		(mid 215.400001 -78.348586)
		(end 215.948768 -77.799946)
		(stroke
			(width 0.2)
			(type default)
		)
		(layer "In1.Cu")
	)
	(gr_line
		(start 214.851488 -76.399898)
		(end 214.851488 -77.799692)
		(stroke
			(width 0.2)
			(type default)
		)
		(layer "In1.Cu")
	)
	(gr_arc
		(start 214.851488 -66.999612)
		(mid 215.400001 -67.548506)
		(end 215.948768 -66.999866)
		(stroke
			(width 0.2)
			(type default)
		)
		(layer "In1.Cu")
	)
	(gr_line
		(start 214.851488 -65.600072)
		(end 214.851488 -66.999612)
		(stroke
			(width 0.2)
			(type default)
		)
		(layer "In1.Cu")
	)
	(gr_line
		(start 215.948768 -77.799946)
		(end 215.948768 -76.399898)
		(stroke
			(width 0.2)
			(type default)
		)
		(layer "In1.Cu")
	)
	(gr_arc
		(start 215.948768 -76.399898)
		(mid 215.400128 -75.851258)
		(end 214.851488 -76.399898)
		(stroke
			(width 0.2)
			(type default)
		)
		(layer "In1.Cu")
	)
	(gr_line
		(start 215.948768 -66.999866)
		(end 215.948768 -65.600072)
		(stroke
			(width 0.2)
			(type default)
		)
		(layer "In1.Cu")
	)
	(gr_arc
		(start 215.948768 -65.600072)
		(mid 215.400128 -65.051432)
		(end 214.851488 -65.600072)
		(stroke
			(width 0.2)
			(type default)
		)
		(layer "In1.Cu")
	)
	(gr_arc
		(start 216.651332 -78.999842)
		(mid 217.199972 -79.548482)
		(end 217.748612 -78.999842)
		(stroke
			(width 0.2)
			(type default)
		)
		(layer "In1.Cu")
	)
	(gr_line
		(start 216.651332 -77.600048)
		(end 216.651332 -78.999842)
		(stroke
			(width 0.2)
			(type default)
		)
		(layer "In1.Cu")
	)
	(gr_arc
		(start 216.651332 -71.799704)
		(mid 217.199845 -72.348598)
		(end 217.748612 -71.799958)
		(stroke
			(width 0.2)
			(type default)
		)
		(layer "In1.Cu")
	)
	(gr_line
		(start 216.651332 -70.39991)
		(end 216.651332 -71.799704)
		(stroke
			(width 0.2)
			(type default)
		)
		(layer "In1.Cu")
	)
	(gr_line
		(start 217.748612 -78.999842)
		(end 217.748612 -77.600302)
		(stroke
			(width 0.2)
			(type default)
		)
		(layer "In1.Cu")
	)
	(gr_arc
		(start 217.748612 -77.600302)
		(mid 217.200099 -77.051408)
		(end 216.651332 -77.600048)
		(stroke
			(width 0.2)
			(type default)
		)
		(layer "In1.Cu")
	)
	(gr_line
		(start 217.748612 -71.799958)
		(end 217.748612 -70.39991)
		(stroke
			(width 0.2)
			(type default)
		)
		(layer "In1.Cu")
	)
	(gr_arc
		(start 217.748612 -70.39991)
		(mid 217.199972 -69.85127)
		(end 216.651332 -70.39991)
		(stroke
			(width 0.2)
			(type default)
		)
		(layer "In1.Cu")
	)
	(gr_arc
		(start 218.45143 -77.799692)
		(mid 218.999943 -78.348586)
		(end 219.54871 -77.799946)
		(stroke
			(width 0.2)
			(type default)
		)
		(layer "In1.Cu")
	)
	(gr_line
		(start 218.45143 -76.399898)
		(end 218.45143 -77.799692)
		(stroke
			(width 0.2)
			(type default)
		)
		(layer "In1.Cu")
	)
	(gr_arc
		(start 218.45143 -66.999612)
		(mid 218.999943 -67.548506)
		(end 219.54871 -66.999866)
		(stroke
			(width 0.2)
			(type default)
		)
		(layer "In1.Cu")
	)
	(gr_line
		(start 218.45143 -65.600072)
		(end 218.45143 -66.999612)
		(stroke
			(width 0.2)
			(type default)
		)
		(layer "In1.Cu")
	)
	(gr_line
		(start 219.54871 -77.799946)
		(end 219.54871 -76.399898)
		(stroke
			(width 0.2)
			(type default)
		)
		(layer "In1.Cu")
	)
	(gr_arc
		(start 219.54871 -76.399898)
		(mid 219.00007 -75.851258)
		(end 218.45143 -76.399898)
		(stroke
			(width 0.2)
			(type default)
		)
		(layer "In1.Cu")
	)
	(gr_line
		(start 219.54871 -66.999866)
		(end 219.54871 -65.600072)
		(stroke
			(width 0.2)
			(type default)
		)
		(layer "In1.Cu")
	)
	(gr_arc
		(start 219.54871 -65.600072)
		(mid 219.00007 -65.051432)
		(end 218.45143 -65.600072)
		(stroke
			(width 0.2)
			(type default)
		)
		(layer "In1.Cu")
	)
	(gr_arc
		(start 220.251528 -78.999842)
		(mid 220.800168 -79.548482)
		(end 221.348808 -78.999842)
		(stroke
			(width 0.2)
			(type default)
		)
		(layer "In1.Cu")
	)
	(gr_line
		(start 220.251528 -77.600048)
		(end 220.251528 -78.999842)
		(stroke
			(width 0.2)
			(type default)
		)
		(layer "In1.Cu")
	)
	(gr_arc
		(start 220.251528 -71.799704)
		(mid 220.800041 -72.348598)
		(end 221.348808 -71.799958)
		(stroke
			(width 0.2)
			(type default)
		)
		(layer "In1.Cu")
	)
	(gr_line
		(start 220.251528 -70.39991)
		(end 220.251528 -71.799704)
		(stroke
			(width 0.2)
			(type default)
		)
		(layer "In1.Cu")
	)
	(gr_line
		(start 221.348808 -78.999842)
		(end 221.348808 -77.600302)
		(stroke
			(width 0.2)
			(type default)
		)
		(layer "In1.Cu")
	)
	(gr_arc
		(start 221.348808 -77.600302)
		(mid 220.800295 -77.051408)
		(end 220.251528 -77.600048)
		(stroke
			(width 0.2)
			(type default)
		)
		(layer "In1.Cu")
	)
	(gr_line
		(start 221.348808 -71.799958)
		(end 221.348808 -70.39991)
		(stroke
			(width 0.2)
			(type default)
		)
		(layer "In1.Cu")
	)
	(gr_arc
		(start 221.348808 -70.39991)
		(mid 220.800168 -69.85127)
		(end 220.251528 -70.39991)
		(stroke
			(width 0.2)
			(type default)
		)
		(layer "In1.Cu")
	)
	(gr_arc
		(start 222.051372 -77.799692)
		(mid 222.599885 -78.348586)
		(end 223.148652 -77.799946)
		(stroke
			(width 0.2)
			(type default)
		)
		(layer "In1.Cu")
	)
	(gr_line
		(start 222.051372 -76.399898)
		(end 222.051372 -77.799692)
		(stroke
			(width 0.2)
			(type default)
		)
		(layer "In1.Cu")
	)
	(gr_arc
		(start 222.051372 -66.999866)
		(mid 222.600012 -67.548506)
		(end 223.148652 -66.999866)
		(stroke
			(width 0.2)
			(type default)
		)
		(layer "In1.Cu")
	)
	(gr_line
		(start 222.051372 -65.600072)
		(end 222.051372 -66.999866)
		(stroke
			(width 0.2)
			(type default)
		)
		(layer "In1.Cu")
	)
	(gr_line
		(start 223.148652 -77.799946)
		(end 223.148652 -76.399898)
		(stroke
			(width 0.2)
			(type default)
		)
		(layer "In1.Cu")
	)
	(gr_arc
		(start 223.148652 -76.399898)
		(mid 222.600012 -75.851258)
		(end 222.051372 -76.399898)
		(stroke
			(width 0.2)
			(type default)
		)
		(layer "In1.Cu")
	)
	(gr_line
		(start 223.148652 -66.999866)
		(end 223.148652 -65.600326)
		(stroke
			(width 0.2)
			(type default)
		)
		(layer "In1.Cu")
	)
	(gr_arc
		(start 223.148652 -65.600326)
		(mid 222.600139 -65.051432)
		(end 222.051372 -65.600072)
		(stroke
			(width 0.2)
			(type default)
		)
		(layer "In1.Cu")
	)
	(gr_line
		(start 238.905288 -369.41887)
		(end 240.142522 -370.656104)
		(stroke
			(width 0.381)
			(type default)
		)
		(layer "In1.Cu")
	)
	(gr_line
		(start 238.905288 -369.210082)
		(end 238.905288 -369.41887)
		(stroke
			(width 0.381)
			(type default)
		)
		(layer "In1.Cu")
	)
	(gr_line
		(start 238.905288 -359.001822)
		(end 238.905288 -369.210082)
		(stroke
			(width 0.381)
			(type default)
		)
		(layer "In1.Cu")
	)
	(gr_line
		(start 239.724692 -358.182418)
		(end 238.905288 -359.001822)
		(stroke
			(width 0.381)
			(type default)
		)
		(layer "In1.Cu")
	)
	(gr_line
		(start 240.142522 -370.656104)
		(end 246.41429 -370.656104)
		(stroke
			(width 0.381)
			(type default)
		)
		(layer "In1.Cu")
	)
	(gr_line
		(start 246.41429 -370.656104)
		(end 251.701554 -375.943368)
		(stroke
			(width 0.381)
			(type default)
		)
		(layer "In1.Cu")
	)
	(gr_line
		(start 246.418608 -358.182418)
		(end 239.724692 -358.182418)
		(stroke
			(width 0.381)
			(type default)
		)
		(layer "In1.Cu")
	)
	(gr_line
		(start 247.850914 -356.750112)
		(end 246.418608 -358.182418)
		(stroke
			(width 0.381)
			(type default)
		)
		(layer "In1.Cu")
	)
	(gr_line
		(start 251.000006 -380.000002)
		(end 199.00011 -380.000002)
		(stroke
			(width 1.524)
			(type default)
		)
		(layer "In1.Cu")
	)
	(gr_line
		(start 251.701554 -375.943368)
		(end 258.243324 -375.943368)
		(stroke
			(width 0.381)
			(type default)
		)
		(layer "In1.Cu")
	)
	(gr_line
		(start 252.000004 -384.999992)
		(end 252.000004 -381)
		(stroke
			(width 1.524)
			(type default)
		)
		(layer "In1.Cu")
	)
	(gr_arc
		(start 252.000004 -384.999992)
		(mid 252.292894 -385.707102)
		(end 253.000002 -385.99999)
		(stroke
			(width 1.524)
			(type default)
		)
		(layer "In1.Cu")
	)
	(gr_arc
		(start 252.000004 -381)
		(mid 251.707111 -380.292895)
		(end 251.000006 -380.000002)
		(stroke
			(width 1.524)
			(type default)
		)
		(layer "In1.Cu")
	)
	(gr_line
		(start 258.243324 -375.943368)
		(end 260.229096 -373.957596)
		(stroke
			(width 0.381)
			(type default)
		)
		(layer "In1.Cu")
	)
	(gr_line
		(start 260.229096 -373.957596)
		(end 260.229096 -371.73662)
		(stroke
			(width 0.381)
			(type default)
		)
		(layer "In1.Cu")
	)
	(gr_line
		(start 260.229096 -371.73662)
		(end 261.004304 -370.961412)
		(stroke
			(width 0.381)
			(type default)
		)
		(layer "In1.Cu")
	)
	(gr_line
		(start 261.004304 -370.961412)
		(end 265.830812 -370.961412)
		(stroke
			(width 0.381)
			(type default)
		)
		(layer "In1.Cu")
	)
	(gr_line
		(start 265.830812 -370.961412)
		(end 268.469872 -368.322352)
		(stroke
			(width 0.381)
			(type default)
		)
		(layer "In1.Cu")
	)
	(gr_line
		(start 267.8811 -356.750112)
		(end 247.850914 -356.750112)
		(stroke
			(width 0.381)
			(type default)
		)
		(layer "In1.Cu")
	)
	(gr_arc
		(start 267.999972 -62.999874)
		(mid 268.707077 -62.706981)
		(end 268.99997 -61.999876)
		(stroke
			(width 1.524)
			(type default)
		)
		(layer "In1.Cu")
	)
	(gr_line
		(start 268.469872 -368.322352)
		(end 268.469872 -357.338884)
		(stroke
			(width 0.381)
			(type default)
		)
		(layer "In1.Cu")
	)
	(gr_line
		(start 268.469872 -357.338884)
		(end 267.8811 -356.750112)
		(stroke
			(width 0.381)
			(type default)
		)
		(layer "In1.Cu")
	)
	(gr_line
		(start 268.99997 -61.999876)
		(end 268.99997 -49.200054)
		(stroke
			(width 1.524)
			(type default)
		)
		(layer "In1.Cu")
	)
	(gr_line
		(start 269.035784 -385.99999)
		(end 253.000002 -385.99999)
		(stroke
			(width 1.524)
			(type default)
		)
		(layer "In1.Cu")
	)
	(gr_arc
		(start 269.035784 -385.99999)
		(mid 269.41848 -385.923895)
		(end 269.74292 -385.707128)
		(stroke
			(width 1.524)
			(type default)
		)
		(layer "In1.Cu")
	)
	(gr_arc
		(start 269.999968 -48.200056)
		(mid 269.292867 -48.492957)
		(end 268.99997 -49.200054)
		(stroke
			(width 1.524)
			(type default)
		)
		(layer "In1.Cu")
	)
	(gr_line
		(start 269.999968 -48.200056)
		(end 309.999888 -48.200056)
		(stroke
			(width 1.524)
			(type default)
		)
		(layer "In1.Cu")
	)
	(gr_line
		(start 272.15719 -383.292858)
		(end 269.74292 -385.707128)
		(stroke
			(width 1.524)
			(type default)
		)
		(layer "In1.Cu")
	)
	(gr_arc
		(start 272.15719 -383.292858)
		(mid 272.373925 -382.968408)
		(end 272.450052 -382.585722)
		(stroke
			(width 1.524)
			(type default)
		)
		(layer "In1.Cu")
	)
	(gr_line
		(start 272.450052 -361.00004)
		(end 272.450052 -382.585722)
		(stroke
			(width 1.524)
			(type default)
		)
		(layer "In1.Cu")
	)
	(gr_arc
		(start 273.45005 -360.000042)
		(mid 272.742945 -360.292935)
		(end 272.450052 -361.00004)
		(stroke
			(width 1.524)
			(type default)
		)
		(layer "In1.Cu")
	)
	(gr_line
		(start 275.75002 -360.000042)
		(end 273.45005 -360.000042)
		(stroke
			(width 1.524)
			(type default)
		)
		(layer "In1.Cu")
	)
	(gr_line
		(start 276.750018 -382.585722)
		(end 276.750018 -361.00004)
		(stroke
			(width 1.524)
			(type default)
		)
		(layer "In1.Cu")
	)
	(gr_arc
		(start 276.750018 -382.585722)
		(mid 276.826093 -382.96843)
		(end 277.04288 -383.292858)
		(stroke
			(width 1.524)
			(type default)
		)
		(layer "In1.Cu")
	)
	(gr_arc
		(start 276.750018 -361.00004)
		(mid 276.457125 -360.292935)
		(end 275.75002 -360.000042)
		(stroke
			(width 1.524)
			(type default)
		)
		(layer "In1.Cu")
	)
	(gr_line
		(start 278.23668 -237.44301)
		(end 279.636728 -237.44301)
		(stroke
			(width 0.2)
			(type default)
		)
		(layer "In1.Cu")
	)
	(gr_arc
		(start 278.23668 -236.34573)
		(mid 277.68804 -236.89437)
		(end 278.23668 -237.44301)
		(stroke
			(width 0.2)
			(type default)
		)
		(layer "In1.Cu")
	)
	(gr_line
		(start 278.23668 -233.843068)
		(end 279.636728 -233.843068)
		(stroke
			(width 0.2)
			(type default)
		)
		(layer "In1.Cu")
	)
	(gr_arc
		(start 278.23668 -232.745788)
		(mid 277.68804 -233.294428)
		(end 278.23668 -233.843068)
		(stroke
			(width 0.2)
			(type default)
		)
		(layer "In1.Cu")
	)
	(gr_line
		(start 278.23668 -230.243126)
		(end 279.636728 -230.243126)
		(stroke
			(width 0.2)
			(type default)
		)
		(layer "In1.Cu")
	)
	(gr_arc
		(start 278.23668 -229.145846)
		(mid 277.68804 -229.694486)
		(end 278.23668 -230.243126)
		(stroke
			(width 0.2)
			(type default)
		)
		(layer "In1.Cu")
	)
	(gr_line
		(start 278.23668 -226.643184)
		(end 279.636728 -226.643184)
		(stroke
			(width 0.2)
			(type default)
		)
		(layer "In1.Cu")
	)
	(gr_arc
		(start 278.23668 -225.545904)
		(mid 277.68804 -226.094544)
		(end 278.23668 -226.643184)
		(stroke
			(width 0.2)
			(type default)
		)
		(layer "In1.Cu")
	)
	(gr_line
		(start 278.23668 -223.042988)
		(end 279.636728 -223.042988)
		(stroke
			(width 0.2)
			(type default)
		)
		(layer "In1.Cu")
	)
	(gr_arc
		(start 278.23668 -221.945708)
		(mid 277.68804 -222.494348)
		(end 278.23668 -223.042988)
		(stroke
			(width 0.2)
			(type default)
		)
		(layer "In1.Cu")
	)
	(gr_line
		(start 278.23668 -219.443046)
		(end 279.636728 -219.443046)
		(stroke
			(width 0.2)
			(type default)
		)
		(layer "In1.Cu")
	)
	(gr_arc
		(start 278.23668 -218.345766)
		(mid 277.68804 -218.894406)
		(end 278.23668 -219.443046)
		(stroke
			(width 0.2)
			(type default)
		)
		(layer "In1.Cu")
	)
	(gr_line
		(start 278.23668 -215.843104)
		(end 279.636728 -215.843104)
		(stroke
			(width 0.2)
			(type default)
		)
		(layer "In1.Cu")
	)
	(gr_arc
		(start 278.23668 -214.745824)
		(mid 277.68804 -215.294464)
		(end 278.23668 -215.843104)
		(stroke
			(width 0.2)
			(type default)
		)
		(layer "In1.Cu")
	)
	(gr_line
		(start 278.23668 -212.243162)
		(end 279.636728 -212.243162)
		(stroke
			(width 0.2)
			(type default)
		)
		(layer "In1.Cu")
	)
	(gr_arc
		(start 278.23668 -211.145882)
		(mid 277.68804 -211.694522)
		(end 278.23668 -212.243162)
		(stroke
			(width 0.2)
			(type default)
		)
		(layer "In1.Cu")
	)
	(gr_line
		(start 278.23668 -208.64322)
		(end 279.636728 -208.64322)
		(stroke
			(width 0.2)
			(type default)
		)
		(layer "In1.Cu")
	)
	(gr_arc
		(start 278.23668 -207.54594)
		(mid 277.68804 -208.09458)
		(end 278.23668 -208.64322)
		(stroke
			(width 0.2)
			(type default)
		)
		(layer "In1.Cu")
	)
	(gr_line
		(start 278.23668 -205.043024)
		(end 279.636728 -205.043024)
		(stroke
			(width 0.2)
			(type default)
		)
		(layer "In1.Cu")
	)
	(gr_arc
		(start 278.23668 -203.945744)
		(mid 277.68804 -204.494384)
		(end 278.23668 -205.043024)
		(stroke
			(width 0.2)
			(type default)
		)
		(layer "In1.Cu")
	)
	(gr_line
		(start 278.23668 -201.443082)
		(end 279.636728 -201.443082)
		(stroke
			(width 0.2)
			(type default)
		)
		(layer "In1.Cu")
	)
	(gr_arc
		(start 278.23668 -200.345802)
		(mid 277.68804 -200.894442)
		(end 278.23668 -201.443082)
		(stroke
			(width 0.2)
			(type default)
		)
		(layer "In1.Cu")
	)
	(gr_line
		(start 278.23668 -197.84314)
		(end 279.636728 -197.84314)
		(stroke
			(width 0.2)
			(type default)
		)
		(layer "In1.Cu")
	)
	(gr_arc
		(start 278.23668 -196.74586)
		(mid 277.68804 -197.2945)
		(end 278.23668 -197.84314)
		(stroke
			(width 0.2)
			(type default)
		)
		(layer "In1.Cu")
	)
	(gr_line
		(start 278.23668 -194.243198)
		(end 279.636728 -194.243198)
		(stroke
			(width 0.2)
			(type default)
		)
		(layer "In1.Cu")
	)
	(gr_arc
		(start 278.23668 -193.145918)
		(mid 277.68804 -193.694558)
		(end 278.23668 -194.243198)
		(stroke
			(width 0.2)
			(type default)
		)
		(layer "In1.Cu")
	)
	(gr_line
		(start 278.23668 -190.643002)
		(end 279.636728 -190.643002)
		(stroke
			(width 0.2)
			(type default)
		)
		(layer "In1.Cu")
	)
	(gr_arc
		(start 278.23668 -189.545722)
		(mid 277.68804 -190.094362)
		(end 278.23668 -190.643002)
		(stroke
			(width 0.2)
			(type default)
		)
		(layer "In1.Cu")
	)
	(gr_line
		(start 278.23668 -187.04306)
		(end 279.636728 -187.04306)
		(stroke
			(width 0.2)
			(type default)
		)
		(layer "In1.Cu")
	)
	(gr_arc
		(start 278.23668 -185.94578)
		(mid 277.68804 -186.49442)
		(end 278.23668 -187.04306)
		(stroke
			(width 0.2)
			(type default)
		)
		(layer "In1.Cu")
	)
	(gr_line
		(start 278.23668 -183.443118)
		(end 279.636728 -183.443118)
		(stroke
			(width 0.2)
			(type default)
		)
		(layer "In1.Cu")
	)
	(gr_arc
		(start 278.23668 -182.345838)
		(mid 277.68804 -182.894478)
		(end 278.23668 -183.443118)
		(stroke
			(width 0.2)
			(type default)
		)
		(layer "In1.Cu")
	)
	(gr_line
		(start 278.23668 -179.843176)
		(end 279.636728 -179.843176)
		(stroke
			(width 0.2)
			(type default)
		)
		(layer "In1.Cu")
	)
	(gr_arc
		(start 278.23668 -178.745896)
		(mid 277.68804 -179.294536)
		(end 278.23668 -179.843176)
		(stroke
			(width 0.2)
			(type default)
		)
		(layer "In1.Cu")
	)
	(gr_line
		(start 278.23668 -176.243234)
		(end 279.636728 -176.243234)
		(stroke
			(width 0.2)
			(type default)
		)
		(layer "In1.Cu")
	)
	(gr_arc
		(start 278.23668 -175.145954)
		(mid 277.68804 -175.694594)
		(end 278.23668 -176.243234)
		(stroke
			(width 0.2)
			(type default)
		)
		(layer "In1.Cu")
	)
	(gr_line
		(start 278.23668 -143.442944)
		(end 279.636728 -143.442944)
		(stroke
			(width 0.2)
			(type default)
		)
		(layer "In1.Cu")
	)
	(gr_arc
		(start 278.23668 -142.345664)
		(mid 277.68804 -142.894304)
		(end 278.23668 -143.442944)
		(stroke
			(width 0.2)
			(type default)
		)
		(layer "In1.Cu")
	)
	(gr_line
		(start 278.23668 -139.843002)
		(end 279.636728 -139.843002)
		(stroke
			(width 0.2)
			(type default)
		)
		(layer "In1.Cu")
	)
	(gr_arc
		(start 278.23668 -138.745722)
		(mid 277.68804 -139.294362)
		(end 278.23668 -139.843002)
		(stroke
			(width 0.2)
			(type default)
		)
		(layer "In1.Cu")
	)
	(gr_line
		(start 278.23668 -136.24306)
		(end 279.636728 -136.24306)
		(stroke
			(width 0.2)
			(type default)
		)
		(layer "In1.Cu")
	)
	(gr_arc
		(start 278.23668 -135.14578)
		(mid 277.68804 -135.69442)
		(end 278.23668 -136.24306)
		(stroke
			(width 0.2)
			(type default)
		)
		(layer "In1.Cu")
	)
	(gr_line
		(start 278.23668 -132.643118)
		(end 279.636728 -132.643118)
		(stroke
			(width 0.2)
			(type default)
		)
		(layer "In1.Cu")
	)
	(gr_arc
		(start 278.23668 -131.545838)
		(mid 277.68804 -132.094478)
		(end 278.23668 -132.643118)
		(stroke
			(width 0.2)
			(type default)
		)
		(layer "In1.Cu")
	)
	(gr_line
		(start 279.236678 -239.243108)
		(end 280.636726 -239.243108)
		(stroke
			(width 0.2)
			(type default)
		)
		(layer "In1.Cu")
	)
	(gr_arc
		(start 279.236678 -238.145828)
		(mid 278.688038 -238.694468)
		(end 279.236678 -239.243108)
		(stroke
			(width 0.2)
			(type default)
		)
		(layer "In1.Cu")
	)
	(gr_line
		(start 279.236678 -235.643166)
		(end 280.636726 -235.643166)
		(stroke
			(width 0.2)
			(type default)
		)
		(layer "In1.Cu")
	)
	(gr_arc
		(start 279.236678 -234.545886)
		(mid 278.688038 -235.094526)
		(end 279.236678 -235.643166)
		(stroke
			(width 0.2)
			(type default)
		)
		(layer "In1.Cu")
	)
	(gr_line
		(start 279.236678 -232.043224)
		(end 280.636726 -232.043224)
		(stroke
			(width 0.2)
			(type default)
		)
		(layer "In1.Cu")
	)
	(gr_arc
		(start 279.236678 -230.945944)
		(mid 278.688038 -231.494584)
		(end 279.236678 -232.043224)
		(stroke
			(width 0.2)
			(type default)
		)
		(layer "In1.Cu")
	)
	(gr_line
		(start 279.236678 -228.443028)
		(end 280.636726 -228.443028)
		(stroke
			(width 0.2)
			(type default)
		)
		(layer "In1.Cu")
	)
	(gr_arc
		(start 279.236678 -227.345748)
		(mid 278.688038 -227.894388)
		(end 279.236678 -228.443028)
		(stroke
			(width 0.2)
			(type default)
		)
		(layer "In1.Cu")
	)
	(gr_line
		(start 279.236678 -224.843086)
		(end 280.636726 -224.843086)
		(stroke
			(width 0.2)
			(type default)
		)
		(layer "In1.Cu")
	)
	(gr_arc
		(start 279.236678 -223.745806)
		(mid 278.688038 -224.294446)
		(end 279.236678 -224.843086)
		(stroke
			(width 0.2)
			(type default)
		)
		(layer "In1.Cu")
	)
	(gr_line
		(start 279.236678 -221.243144)
		(end 280.636726 -221.243144)
		(stroke
			(width 0.2)
			(type default)
		)
		(layer "In1.Cu")
	)
	(gr_arc
		(start 279.236678 -220.145864)
		(mid 278.688038 -220.694504)
		(end 279.236678 -221.243144)
		(stroke
			(width 0.2)
			(type default)
		)
		(layer "In1.Cu")
	)
	(gr_line
		(start 279.236678 -217.643202)
		(end 280.636726 -217.643202)
		(stroke
			(width 0.2)
			(type default)
		)
		(layer "In1.Cu")
	)
	(gr_arc
		(start 279.236678 -216.545922)
		(mid 278.688038 -217.094562)
		(end 279.236678 -217.643202)
		(stroke
			(width 0.2)
			(type default)
		)
		(layer "In1.Cu")
	)
	(gr_line
		(start 279.236678 -214.043006)
		(end 280.636726 -214.043006)
		(stroke
			(width 0.2)
			(type default)
		)
		(layer "In1.Cu")
	)
	(gr_arc
		(start 279.236678 -212.945726)
		(mid 278.688038 -213.494366)
		(end 279.236678 -214.043006)
		(stroke
			(width 0.2)
			(type default)
		)
		(layer "In1.Cu")
	)
	(gr_line
		(start 279.236678 -210.443064)
		(end 280.636726 -210.443064)
		(stroke
			(width 0.2)
			(type default)
		)
		(layer "In1.Cu")
	)
	(gr_arc
		(start 279.236678 -209.345784)
		(mid 278.688038 -209.894424)
		(end 279.236678 -210.443064)
		(stroke
			(width 0.2)
			(type default)
		)
		(layer "In1.Cu")
	)
	(gr_line
		(start 279.236678 -206.843122)
		(end 280.636726 -206.843122)
		(stroke
			(width 0.2)
			(type default)
		)
		(layer "In1.Cu")
	)
	(gr_arc
		(start 279.236678 -205.745842)
		(mid 278.688038 -206.294482)
		(end 279.236678 -206.843122)
		(stroke
			(width 0.2)
			(type default)
		)
		(layer "In1.Cu")
	)
	(gr_line
		(start 279.236678 -203.24318)
		(end 280.636726 -203.24318)
		(stroke
			(width 0.2)
			(type default)
		)
		(layer "In1.Cu")
	)
	(gr_arc
		(start 279.236678 -202.1459)
		(mid 278.688038 -202.69454)
		(end 279.236678 -203.24318)
		(stroke
			(width 0.2)
			(type default)
		)
		(layer "In1.Cu")
	)
	(gr_line
		(start 279.236678 -199.642984)
		(end 280.636726 -199.642984)
		(stroke
			(width 0.2)
			(type default)
		)
		(layer "In1.Cu")
	)
	(gr_arc
		(start 279.236678 -198.545704)
		(mid 278.688038 -199.094344)
		(end 279.236678 -199.642984)
		(stroke
			(width 0.2)
			(type default)
		)
		(layer "In1.Cu")
	)
	(gr_line
		(start 279.236678 -196.043042)
		(end 280.636726 -196.043042)
		(stroke
			(width 0.2)
			(type default)
		)
		(layer "In1.Cu")
	)
	(gr_arc
		(start 279.236678 -194.945762)
		(mid 278.688038 -195.494402)
		(end 279.236678 -196.043042)
		(stroke
			(width 0.2)
			(type default)
		)
		(layer "In1.Cu")
	)
	(gr_line
		(start 279.236678 -192.4431)
		(end 280.636726 -192.4431)
		(stroke
			(width 0.2)
			(type default)
		)
		(layer "In1.Cu")
	)
	(gr_arc
		(start 279.236678 -191.34582)
		(mid 278.688038 -191.89446)
		(end 279.236678 -192.4431)
		(stroke
			(width 0.2)
			(type default)
		)
		(layer "In1.Cu")
	)
	(gr_line
		(start 279.236678 -188.843158)
		(end 280.636726 -188.843158)
		(stroke
			(width 0.2)
			(type default)
		)
		(layer "In1.Cu")
	)
	(gr_arc
		(start 279.236678 -187.745878)
		(mid 278.688038 -188.294518)
		(end 279.236678 -188.843158)
		(stroke
			(width 0.2)
			(type default)
		)
		(layer "In1.Cu")
	)
	(gr_line
		(start 279.236678 -185.243216)
		(end 280.636726 -185.243216)
		(stroke
			(width 0.2)
			(type default)
		)
		(layer "In1.Cu")
	)
	(gr_arc
		(start 279.236678 -184.145936)
		(mid 278.688038 -184.694576)
		(end 279.236678 -185.243216)
		(stroke
			(width 0.2)
			(type default)
		)
		(layer "In1.Cu")
	)
	(gr_line
		(start 279.236678 -181.64302)
		(end 280.636726 -181.64302)
		(stroke
			(width 0.2)
			(type default)
		)
		(layer "In1.Cu")
	)
	(gr_arc
		(start 279.236678 -180.54574)
		(mid 278.688038 -181.09438)
		(end 279.236678 -181.64302)
		(stroke
			(width 0.2)
			(type default)
		)
		(layer "In1.Cu")
	)
	(gr_line
		(start 279.236678 -178.043078)
		(end 280.636726 -178.043078)
		(stroke
			(width 0.2)
			(type default)
		)
		(layer "In1.Cu")
	)
	(gr_arc
		(start 279.236678 -176.945798)
		(mid 278.688038 -177.494438)
		(end 279.236678 -178.043078)
		(stroke
			(width 0.2)
			(type default)
		)
		(layer "In1.Cu")
	)
	(gr_line
		(start 279.236678 -145.243042)
		(end 280.636726 -145.243042)
		(stroke
			(width 0.2)
			(type default)
		)
		(layer "In1.Cu")
	)
	(gr_arc
		(start 279.236678 -144.145762)
		(mid 278.688038 -144.694402)
		(end 279.236678 -145.243042)
		(stroke
			(width 0.2)
			(type default)
		)
		(layer "In1.Cu")
	)
	(gr_line
		(start 279.236678 -141.6431)
		(end 280.636726 -141.6431)
		(stroke
			(width 0.2)
			(type default)
		)
		(layer "In1.Cu")
	)
	(gr_arc
		(start 279.236678 -140.54582)
		(mid 278.688038 -141.09446)
		(end 279.236678 -141.6431)
		(stroke
			(width 0.2)
			(type default)
		)
		(layer "In1.Cu")
	)
	(gr_line
		(start 279.236678 -138.045698)
		(end 280.636726 -138.045698)
		(stroke
			(width 0.2)
			(type default)
		)
		(layer "In1.Cu")
	)
	(gr_arc
		(start 279.236678 -136.943338)
		(mid 278.685498 -137.494518)
		(end 279.236678 -138.045698)
		(stroke
			(width 0.2)
			(type default)
		)
		(layer "In1.Cu")
	)
	(gr_line
		(start 279.236678 -134.442962)
		(end 280.636726 -134.442962)
		(stroke
			(width 0.2)
			(type default)
		)
		(layer "In1.Cu")
	)
	(gr_arc
		(start 279.236678 -133.345682)
		(mid 278.688038 -133.894322)
		(end 279.236678 -134.442962)
		(stroke
			(width 0.2)
			(type default)
		)
		(layer "In1.Cu")
	)
	(gr_line
		(start 279.236932 -136.943338)
		(end 279.236678 -136.943338)
		(stroke
			(width 0.2)
			(type default)
		)
		(layer "In1.Cu")
	)
	(gr_line
		(start 279.45715 -385.707128)
		(end 277.04288 -383.292858)
		(stroke
			(width 1.524)
			(type default)
		)
		(layer "In1.Cu")
	)
	(gr_arc
		(start 279.45715 -385.707128)
		(mid 279.781602 -385.923853)
		(end 280.164286 -385.99999)
		(stroke
			(width 1.524)
			(type default)
		)
		(layer "In1.Cu")
	)
	(gr_arc
		(start 279.636728 -237.44301)
		(mid 280.185368 -236.89437)
		(end 279.636728 -236.34573)
		(stroke
			(width 0.2)
			(type default)
		)
		(layer "In1.Cu")
	)
	(gr_line
		(start 279.636728 -236.34573)
		(end 278.23668 -236.34573)
		(stroke
			(width 0.2)
			(type default)
		)
		(layer "In1.Cu")
	)
	(gr_arc
		(start 279.636728 -233.843068)
		(mid 280.185368 -233.294428)
		(end 279.636728 -232.745788)
		(stroke
			(width 0.2)
			(type default)
		)
		(layer "In1.Cu")
	)
	(gr_line
		(start 279.636728 -232.745788)
		(end 278.23668 -232.745788)
		(stroke
			(width 0.2)
			(type default)
		)
		(layer "In1.Cu")
	)
	(gr_arc
		(start 279.636728 -230.243126)
		(mid 280.185368 -229.694486)
		(end 279.636728 -229.145846)
		(stroke
			(width 0.2)
			(type default)
		)
		(layer "In1.Cu")
	)
	(gr_line
		(start 279.636728 -229.145846)
		(end 278.23668 -229.145846)
		(stroke
			(width 0.2)
			(type default)
		)
		(layer "In1.Cu")
	)
	(gr_arc
		(start 279.636728 -226.643184)
		(mid 280.185368 -226.094544)
		(end 279.636728 -225.545904)
		(stroke
			(width 0.2)
			(type default)
		)
		(layer "In1.Cu")
	)
	(gr_line
		(start 279.636728 -225.545904)
		(end 278.23668 -225.545904)
		(stroke
			(width 0.2)
			(type default)
		)
		(layer "In1.Cu")
	)
	(gr_arc
		(start 279.636728 -223.042988)
		(mid 280.185368 -222.494348)
		(end 279.636728 -221.945708)
		(stroke
			(width 0.2)
			(type default)
		)
		(layer "In1.Cu")
	)
	(gr_line
		(start 279.636728 -221.945708)
		(end 278.23668 -221.945708)
		(stroke
			(width 0.2)
			(type default)
		)
		(layer "In1.Cu")
	)
	(gr_arc
		(start 279.636728 -219.443046)
		(mid 280.185368 -218.894406)
		(end 279.636728 -218.345766)
		(stroke
			(width 0.2)
			(type default)
		)
		(layer "In1.Cu")
	)
	(gr_line
		(start 279.636728 -218.345766)
		(end 278.23668 -218.345766)
		(stroke
			(width 0.2)
			(type default)
		)
		(layer "In1.Cu")
	)
	(gr_arc
		(start 279.636728 -215.843104)
		(mid 280.185368 -215.294464)
		(end 279.636728 -214.745824)
		(stroke
			(width 0.2)
			(type default)
		)
		(layer "In1.Cu")
	)
	(gr_line
		(start 279.636728 -214.745824)
		(end 278.23668 -214.745824)
		(stroke
			(width 0.2)
			(type default)
		)
		(layer "In1.Cu")
	)
	(gr_arc
		(start 279.636728 -212.243162)
		(mid 280.185368 -211.694522)
		(end 279.636728 -211.145882)
		(stroke
			(width 0.2)
			(type default)
		)
		(layer "In1.Cu")
	)
	(gr_line
		(start 279.636728 -211.145882)
		(end 278.23668 -211.145882)
		(stroke
			(width 0.2)
			(type default)
		)
		(layer "In1.Cu")
	)
	(gr_arc
		(start 279.636728 -208.64322)
		(mid 280.185368 -208.09458)
		(end 279.636728 -207.54594)
		(stroke
			(width 0.2)
			(type default)
		)
		(layer "In1.Cu")
	)
	(gr_line
		(start 279.636728 -207.54594)
		(end 278.23668 -207.54594)
		(stroke
			(width 0.2)
			(type default)
		)
		(layer "In1.Cu")
	)
	(gr_arc
		(start 279.636728 -205.043024)
		(mid 280.185368 -204.494384)
		(end 279.636728 -203.945744)
		(stroke
			(width 0.2)
			(type default)
		)
		(layer "In1.Cu")
	)
	(gr_line
		(start 279.636728 -203.945744)
		(end 278.23668 -203.945744)
		(stroke
			(width 0.2)
			(type default)
		)
		(layer "In1.Cu")
	)
	(gr_arc
		(start 279.636728 -201.443082)
		(mid 280.185368 -200.894442)
		(end 279.636728 -200.345802)
		(stroke
			(width 0.2)
			(type default)
		)
		(layer "In1.Cu")
	)
	(gr_line
		(start 279.636728 -200.345802)
		(end 278.23668 -200.345802)
		(stroke
			(width 0.2)
			(type default)
		)
		(layer "In1.Cu")
	)
	(gr_arc
		(start 279.636728 -197.84314)
		(mid 280.185368 -197.2945)
		(end 279.636728 -196.74586)
		(stroke
			(width 0.2)
			(type default)
		)
		(layer "In1.Cu")
	)
	(gr_line
		(start 279.636728 -196.74586)
		(end 278.23668 -196.74586)
		(stroke
			(width 0.2)
			(type default)
		)
		(layer "In1.Cu")
	)
	(gr_arc
		(start 279.636728 -194.243198)
		(mid 280.185368 -193.694558)
		(end 279.636728 -193.145918)
		(stroke
			(width 0.2)
			(type default)
		)
		(layer "In1.Cu")
	)
	(gr_line
		(start 279.636728 -193.145918)
		(end 278.23668 -193.145918)
		(stroke
			(width 0.2)
			(type default)
		)
		(layer "In1.Cu")
	)
	(gr_arc
		(start 279.636728 -190.643002)
		(mid 280.185368 -190.094362)
		(end 279.636728 -189.545722)
		(stroke
			(width 0.2)
			(type default)
		)
		(layer "In1.Cu")
	)
	(gr_line
		(start 279.636728 -189.545722)
		(end 278.23668 -189.545722)
		(stroke
			(width 0.2)
			(type default)
		)
		(layer "In1.Cu")
	)
	(gr_arc
		(start 279.636728 -187.04306)
		(mid 280.185368 -186.49442)
		(end 279.636728 -185.94578)
		(stroke
			(width 0.2)
			(type default)
		)
		(layer "In1.Cu")
	)
	(gr_line
		(start 279.636728 -185.94578)
		(end 278.23668 -185.94578)
		(stroke
			(width 0.2)
			(type default)
		)
		(layer "In1.Cu")
	)
	(gr_arc
		(start 279.636728 -183.443118)
		(mid 280.185368 -182.894478)
		(end 279.636728 -182.345838)
		(stroke
			(width 0.2)
			(type default)
		)
		(layer "In1.Cu")
	)
	(gr_line
		(start 279.636728 -182.345838)
		(end 278.23668 -182.345838)
		(stroke
			(width 0.2)
			(type default)
		)
		(layer "In1.Cu")
	)
	(gr_arc
		(start 279.636728 -179.843176)
		(mid 280.185368 -179.294536)
		(end 279.636728 -178.745896)
		(stroke
			(width 0.2)
			(type default)
		)
		(layer "In1.Cu")
	)
	(gr_line
		(start 279.636728 -178.745896)
		(end 278.23668 -178.745896)
		(stroke
			(width 0.2)
			(type default)
		)
		(layer "In1.Cu")
	)
	(gr_arc
		(start 279.636728 -176.243234)
		(mid 280.185368 -175.694594)
		(end 279.636728 -175.145954)
		(stroke
			(width 0.2)
			(type default)
		)
		(layer "In1.Cu")
	)
	(gr_line
		(start 279.636728 -175.145954)
		(end 278.23668 -175.145954)
		(stroke
			(width 0.2)
			(type default)
		)
		(layer "In1.Cu")
	)
	(gr_arc
		(start 279.636728 -143.442944)
		(mid 280.185368 -142.894304)
		(end 279.636728 -142.345664)
		(stroke
			(width 0.2)
			(type default)
		)
		(layer "In1.Cu")
	)
	(gr_line
		(start 279.636728 -142.345664)
		(end 278.23668 -142.345664)
		(stroke
			(width 0.2)
			(type default)
		)
		(layer "In1.Cu")
	)
	(gr_arc
		(start 279.636728 -139.843002)
		(mid 280.185368 -139.294362)
		(end 279.636728 -138.745722)
		(stroke
			(width 0.2)
			(type default)
		)
		(layer "In1.Cu")
	)
	(gr_line
		(start 279.636728 -138.745722)
		(end 278.23668 -138.745722)
		(stroke
			(width 0.2)
			(type default)
		)
		(layer "In1.Cu")
	)
	(gr_arc
		(start 279.636728 -136.24306)
		(mid 280.185368 -135.69442)
		(end 279.636728 -135.14578)
		(stroke
			(width 0.2)
			(type default)
		)
		(layer "In1.Cu")
	)
	(gr_line
		(start 279.636728 -135.14578)
		(end 278.23668 -135.14578)
		(stroke
			(width 0.2)
			(type default)
		)
		(layer "In1.Cu")
	)
	(gr_arc
		(start 279.636728 -132.643118)
		(mid 280.185368 -132.094478)
		(end 279.636728 -131.545838)
		(stroke
			(width 0.2)
			(type default)
		)
		(layer "In1.Cu")
	)
	(gr_line
		(start 279.636728 -131.545838)
		(end 278.23668 -131.545838)
		(stroke
			(width 0.2)
			(type default)
		)
		(layer "In1.Cu")
	)
	(gr_arc
		(start 280.636726 -239.243108)
		(mid 281.185366 -238.694468)
		(end 280.636726 -238.145828)
		(stroke
			(width 0.2)
			(type default)
		)
		(layer "In1.Cu")
	)
	(gr_line
		(start 280.636726 -238.145828)
		(end 279.236678 -238.145828)
		(stroke
			(width 0.2)
			(type default)
		)
		(layer "In1.Cu")
	)
	(gr_arc
		(start 280.636726 -235.643166)
		(mid 281.185366 -235.094526)
		(end 280.636726 -234.545886)
		(stroke
			(width 0.2)
			(type default)
		)
		(layer "In1.Cu")
	)
	(gr_line
		(start 280.636726 -234.545886)
		(end 279.236678 -234.545886)
		(stroke
			(width 0.2)
			(type default)
		)
		(layer "In1.Cu")
	)
	(gr_arc
		(start 280.636726 -232.043224)
		(mid 281.185366 -231.494584)
		(end 280.636726 -230.945944)
		(stroke
			(width 0.2)
			(type default)
		)
		(layer "In1.Cu")
	)
	(gr_line
		(start 280.636726 -230.945944)
		(end 279.236678 -230.945944)
		(stroke
			(width 0.2)
			(type default)
		)
		(layer "In1.Cu")
	)
	(gr_arc
		(start 280.636726 -228.443028)
		(mid 281.185366 -227.894388)
		(end 280.636726 -227.345748)
		(stroke
			(width 0.2)
			(type default)
		)
		(layer "In1.Cu")
	)
	(gr_line
		(start 280.636726 -227.345748)
		(end 279.236678 -227.345748)
		(stroke
			(width 0.2)
			(type default)
		)
		(layer "In1.Cu")
	)
	(gr_arc
		(start 280.636726 -224.843086)
		(mid 281.185366 -224.294446)
		(end 280.636726 -223.745806)
		(stroke
			(width 0.2)
			(type default)
		)
		(layer "In1.Cu")
	)
	(gr_line
		(start 280.636726 -223.745806)
		(end 279.236678 -223.745806)
		(stroke
			(width 0.2)
			(type default)
		)
		(layer "In1.Cu")
	)
	(gr_arc
		(start 280.636726 -221.243144)
		(mid 281.185366 -220.694504)
		(end 280.636726 -220.145864)
		(stroke
			(width 0.2)
			(type default)
		)
		(layer "In1.Cu")
	)
	(gr_line
		(start 280.636726 -220.145864)
		(end 279.236678 -220.145864)
		(stroke
			(width 0.2)
			(type default)
		)
		(layer "In1.Cu")
	)
	(gr_arc
		(start 280.636726 -217.643202)
		(mid 281.185366 -217.094562)
		(end 280.636726 -216.545922)
		(stroke
			(width 0.2)
			(type default)
		)
		(layer "In1.Cu")
	)
	(gr_line
		(start 280.636726 -216.545922)
		(end 279.236678 -216.545922)
		(stroke
			(width 0.2)
			(type default)
		)
		(layer "In1.Cu")
	)
	(gr_arc
		(start 280.636726 -214.043006)
		(mid 281.185366 -213.494366)
		(end 280.636726 -212.945726)
		(stroke
			(width 0.2)
			(type default)
		)
		(layer "In1.Cu")
	)
	(gr_line
		(start 280.636726 -212.945726)
		(end 279.236678 -212.945726)
		(stroke
			(width 0.2)
			(type default)
		)
		(layer "In1.Cu")
	)
	(gr_arc
		(start 280.636726 -210.443064)
		(mid 281.185366 -209.894424)
		(end 280.636726 -209.345784)
		(stroke
			(width 0.2)
			(type default)
		)
		(layer "In1.Cu")
	)
	(gr_line
		(start 280.636726 -209.345784)
		(end 279.236678 -209.345784)
		(stroke
			(width 0.2)
			(type default)
		)
		(layer "In1.Cu")
	)
	(gr_arc
		(start 280.636726 -206.843122)
		(mid 281.185366 -206.294482)
		(end 280.636726 -205.745842)
		(stroke
			(width 0.2)
			(type default)
		)
		(layer "In1.Cu")
	)
	(gr_line
		(start 280.636726 -205.745842)
		(end 279.236678 -205.745842)
		(stroke
			(width 0.2)
			(type default)
		)
		(layer "In1.Cu")
	)
	(gr_arc
		(start 280.636726 -203.24318)
		(mid 281.185366 -202.69454)
		(end 280.636726 -202.1459)
		(stroke
			(width 0.2)
			(type default)
		)
		(layer "In1.Cu")
	)
	(gr_line
		(start 280.636726 -202.1459)
		(end 279.236678 -202.1459)
		(stroke
			(width 0.2)
			(type default)
		)
		(layer "In1.Cu")
	)
	(gr_arc
		(start 280.636726 -199.642984)
		(mid 281.185366 -199.094344)
		(end 280.636726 -198.545704)
		(stroke
			(width 0.2)
			(type default)
		)
		(layer "In1.Cu")
	)
	(gr_line
		(start 280.636726 -198.545704)
		(end 279.236678 -198.545704)
		(stroke
			(width 0.2)
			(type default)
		)
		(layer "In1.Cu")
	)
	(gr_arc
		(start 280.636726 -196.043042)
		(mid 281.185366 -195.494402)
		(end 280.636726 -194.945762)
		(stroke
			(width 0.2)
			(type default)
		)
		(layer "In1.Cu")
	)
	(gr_line
		(start 280.636726 -194.945762)
		(end 279.236678 -194.945762)
		(stroke
			(width 0.2)
			(type default)
		)
		(layer "In1.Cu")
	)
	(gr_arc
		(start 280.636726 -192.4431)
		(mid 281.185366 -191.89446)
		(end 280.636726 -191.34582)
		(stroke
			(width 0.2)
			(type default)
		)
		(layer "In1.Cu")
	)
	(gr_line
		(start 280.636726 -191.34582)
		(end 279.236678 -191.34582)
		(stroke
			(width 0.2)
			(type default)
		)
		(layer "In1.Cu")
	)
	(gr_arc
		(start 280.636726 -188.843158)
		(mid 281.185366 -188.294518)
		(end 280.636726 -187.745878)
		(stroke
			(width 0.2)
			(type default)
		)
		(layer "In1.Cu")
	)
	(gr_line
		(start 280.636726 -187.745878)
		(end 279.236678 -187.745878)
		(stroke
			(width 0.2)
			(type default)
		)
		(layer "In1.Cu")
	)
	(gr_arc
		(start 280.636726 -185.243216)
		(mid 281.185366 -184.694576)
		(end 280.636726 -184.145936)
		(stroke
			(width 0.2)
			(type default)
		)
		(layer "In1.Cu")
	)
	(gr_line
		(start 280.636726 -184.145936)
		(end 279.236678 -184.145936)
		(stroke
			(width 0.2)
			(type default)
		)
		(layer "In1.Cu")
	)
	(gr_arc
		(start 280.636726 -181.64302)
		(mid 281.185366 -181.09438)
		(end 280.636726 -180.54574)
		(stroke
			(width 0.2)
			(type default)
		)
		(layer "In1.Cu")
	)
	(gr_line
		(start 280.636726 -180.54574)
		(end 279.236678 -180.54574)
		(stroke
			(width 0.2)
			(type default)
		)
		(layer "In1.Cu")
	)
	(gr_arc
		(start 280.636726 -178.043078)
		(mid 281.185366 -177.494438)
		(end 280.636726 -176.945798)
		(stroke
			(width 0.2)
			(type default)
		)
		(layer "In1.Cu")
	)
	(gr_line
		(start 280.636726 -176.945798)
		(end 279.236678 -176.945798)
		(stroke
			(width 0.2)
			(type default)
		)
		(layer "In1.Cu")
	)
	(gr_arc
		(start 280.636726 -145.243042)
		(mid 281.185366 -144.694402)
		(end 280.636726 -144.145762)
		(stroke
			(width 0.2)
			(type default)
		)
		(layer "In1.Cu")
	)
	(gr_line
		(start 280.636726 -144.145762)
		(end 279.236678 -144.145762)
		(stroke
			(width 0.2)
			(type default)
		)
		(layer "In1.Cu")
	)
	(gr_arc
		(start 280.636726 -141.6431)
		(mid 281.185366 -141.09446)
		(end 280.636726 -140.54582)
		(stroke
			(width 0.2)
			(type default)
		)
		(layer "In1.Cu")
	)
	(gr_line
		(start 280.636726 -140.54582)
		(end 279.236678 -140.54582)
		(stroke
			(width 0.2)
			(type default)
		)
		(layer "In1.Cu")
	)
	(gr_arc
		(start 280.636726 -138.045698)
		(mid 281.187906 -137.494518)
		(end 280.636726 -136.943338)
		(stroke
			(width 0.2)
			(type default)
		)
		(layer "In1.Cu")
	)
	(gr_line
		(start 280.636726 -136.943338)
		(end 279.236932 -136.943338)
		(stroke
			(width 0.2)
			(type default)
		)
		(layer "In1.Cu")
	)
	(gr_arc
		(start 280.636726 -134.442962)
		(mid 281.185366 -133.894322)
		(end 280.636726 -133.345682)
		(stroke
			(width 0.2)
			(type default)
		)
		(layer "In1.Cu")
	)
	(gr_line
		(start 280.636726 -133.345682)
		(end 279.236678 -133.345682)
		(stroke
			(width 0.2)
			(type default)
		)
		(layer "In1.Cu")
	)
	(gr_line
		(start 282.83662 -145.243042)
		(end 284.236668 -145.243042)
		(stroke
			(width 0.2)
			(type default)
		)
		(layer "In1.Cu")
	)
	(gr_arc
		(start 282.83662 -144.145762)
		(mid 282.28798 -144.694402)
		(end 282.83662 -145.243042)
		(stroke
			(width 0.2)
			(type default)
		)
		(layer "In1.Cu")
	)
	(gr_arc
		(start 284.236668 -145.243042)
		(mid 284.785308 -144.694402)
		(end 284.236668 -144.145762)
		(stroke
			(width 0.2)
			(type default)
		)
		(layer "In1.Cu")
	)
	(gr_line
		(start 284.236668 -144.145762)
		(end 282.83662 -144.145762)
		(stroke
			(width 0.2)
			(type default)
		)
		(layer "In1.Cu")
	)
	(gr_line
		(start 285.436564 -237.44301)
		(end 286.836612 -237.44301)
		(stroke
			(width 0.2)
			(type default)
		)
		(layer "In1.Cu")
	)
	(gr_arc
		(start 285.436564 -236.34573)
		(mid 284.887924 -236.89437)
		(end 285.436564 -237.44301)
		(stroke
			(width 0.2)
			(type default)
		)
		(layer "In1.Cu")
	)
	(gr_line
		(start 285.436564 -233.843068)
		(end 286.836612 -233.843068)
		(stroke
			(width 0.2)
			(type default)
		)
		(layer "In1.Cu")
	)
	(gr_arc
		(start 285.436564 -232.745788)
		(mid 284.887924 -233.294428)
		(end 285.436564 -233.843068)
		(stroke
			(width 0.2)
			(type default)
		)
		(layer "In1.Cu")
	)
	(gr_line
		(start 285.436564 -230.243126)
		(end 286.836612 -230.243126)
		(stroke
			(width 0.2)
			(type default)
		)
		(layer "In1.Cu")
	)
	(gr_arc
		(start 285.436564 -229.145846)
		(mid 284.887924 -229.694486)
		(end 285.436564 -230.243126)
		(stroke
			(width 0.2)
			(type default)
		)
		(layer "In1.Cu")
	)
	(gr_line
		(start 285.436564 -226.643184)
		(end 286.836612 -226.643184)
		(stroke
			(width 0.2)
			(type default)
		)
		(layer "In1.Cu")
	)
	(gr_arc
		(start 285.436564 -225.545904)
		(mid 284.887924 -226.094544)
		(end 285.436564 -226.643184)
		(stroke
			(width 0.2)
			(type default)
		)
		(layer "In1.Cu")
	)
	(gr_line
		(start 285.436564 -223.042988)
		(end 286.836612 -223.042988)
		(stroke
			(width 0.2)
			(type default)
		)
		(layer "In1.Cu")
	)
	(gr_arc
		(start 285.436564 -221.945708)
		(mid 284.887924 -222.494348)
		(end 285.436564 -223.042988)
		(stroke
			(width 0.2)
			(type default)
		)
		(layer "In1.Cu")
	)
	(gr_line
		(start 285.436564 -219.443046)
		(end 286.836612 -219.443046)
		(stroke
			(width 0.2)
			(type default)
		)
		(layer "In1.Cu")
	)
	(gr_arc
		(start 285.436564 -218.345766)
		(mid 284.887924 -218.894406)
		(end 285.436564 -219.443046)
		(stroke
			(width 0.2)
			(type default)
		)
		(layer "In1.Cu")
	)
	(gr_line
		(start 285.436564 -215.843104)
		(end 286.836612 -215.843104)
		(stroke
			(width 0.2)
			(type default)
		)
		(layer "In1.Cu")
	)
	(gr_arc
		(start 285.436564 -214.745824)
		(mid 284.887924 -215.294464)
		(end 285.436564 -215.843104)
		(stroke
			(width 0.2)
			(type default)
		)
		(layer "In1.Cu")
	)
	(gr_line
		(start 285.436564 -212.243162)
		(end 286.836612 -212.243162)
		(stroke
			(width 0.2)
			(type default)
		)
		(layer "In1.Cu")
	)
	(gr_arc
		(start 285.436564 -211.145882)
		(mid 284.887924 -211.694522)
		(end 285.436564 -212.243162)
		(stroke
			(width 0.2)
			(type default)
		)
		(layer "In1.Cu")
	)
	(gr_line
		(start 285.436564 -208.64322)
		(end 286.836612 -208.64322)
		(stroke
			(width 0.2)
			(type default)
		)
		(layer "In1.Cu")
	)
	(gr_arc
		(start 285.436564 -207.54594)
		(mid 284.887924 -208.09458)
		(end 285.436564 -208.64322)
		(stroke
			(width 0.2)
			(type default)
		)
		(layer "In1.Cu")
	)
	(gr_line
		(start 285.436564 -205.043024)
		(end 286.836612 -205.043024)
		(stroke
			(width 0.2)
			(type default)
		)
		(layer "In1.Cu")
	)
	(gr_arc
		(start 285.436564 -203.945744)
		(mid 284.887924 -204.494384)
		(end 285.436564 -205.043024)
		(stroke
			(width 0.2)
			(type default)
		)
		(layer "In1.Cu")
	)
	(gr_line
		(start 285.436564 -201.443082)
		(end 286.836612 -201.443082)
		(stroke
			(width 0.2)
			(type default)
		)
		(layer "In1.Cu")
	)
	(gr_arc
		(start 285.436564 -200.345802)
		(mid 284.887924 -200.894442)
		(end 285.436564 -201.443082)
		(stroke
			(width 0.2)
			(type default)
		)
		(layer "In1.Cu")
	)
	(gr_line
		(start 285.436564 -197.84314)
		(end 286.836612 -197.84314)
		(stroke
			(width 0.2)
			(type default)
		)
		(layer "In1.Cu")
	)
	(gr_arc
		(start 285.436564 -196.74586)
		(mid 284.887924 -197.2945)
		(end 285.436564 -197.84314)
		(stroke
			(width 0.2)
			(type default)
		)
		(layer "In1.Cu")
	)
	(gr_line
		(start 285.436564 -194.243198)
		(end 286.836612 -194.243198)
		(stroke
			(width 0.2)
			(type default)
		)
		(layer "In1.Cu")
	)
	(gr_arc
		(start 285.436564 -193.145918)
		(mid 284.887924 -193.694558)
		(end 285.436564 -194.243198)
		(stroke
			(width 0.2)
			(type default)
		)
		(layer "In1.Cu")
	)
	(gr_line
		(start 285.436564 -190.643002)
		(end 286.836612 -190.643002)
		(stroke
			(width 0.2)
			(type default)
		)
		(layer "In1.Cu")
	)
	(gr_arc
		(start 285.436564 -189.545722)
		(mid 284.887924 -190.094362)
		(end 285.436564 -190.643002)
		(stroke
			(width 0.2)
			(type default)
		)
		(layer "In1.Cu")
	)
	(gr_line
		(start 285.436564 -187.04306)
		(end 286.836612 -187.04306)
		(stroke
			(width 0.2)
			(type default)
		)
		(layer "In1.Cu")
	)
	(gr_arc
		(start 285.436564 -185.94578)
		(mid 284.887924 -186.49442)
		(end 285.436564 -187.04306)
		(stroke
			(width 0.2)
			(type default)
		)
		(layer "In1.Cu")
	)
	(gr_line
		(start 285.436564 -183.443118)
		(end 286.836612 -183.443118)
		(stroke
			(width 0.2)
			(type default)
		)
		(layer "In1.Cu")
	)
	(gr_arc
		(start 285.436564 -182.345838)
		(mid 284.887924 -182.894478)
		(end 285.436564 -183.443118)
		(stroke
			(width 0.2)
			(type default)
		)
		(layer "In1.Cu")
	)
	(gr_line
		(start 285.436564 -179.843176)
		(end 286.836612 -179.843176)
		(stroke
			(width 0.2)
			(type default)
		)
		(layer "In1.Cu")
	)
	(gr_arc
		(start 285.436564 -178.745896)
		(mid 284.887924 -179.294536)
		(end 285.436564 -179.843176)
		(stroke
			(width 0.2)
			(type default)
		)
		(layer "In1.Cu")
	)
	(gr_line
		(start 285.436564 -176.243234)
		(end 286.836612 -176.243234)
		(stroke
			(width 0.2)
			(type default)
		)
		(layer "In1.Cu")
	)
	(gr_arc
		(start 285.436564 -175.145954)
		(mid 284.887924 -175.694594)
		(end 285.436564 -176.243234)
		(stroke
			(width 0.2)
			(type default)
		)
		(layer "In1.Cu")
	)
	(gr_line
		(start 285.436564 -143.442944)
		(end 286.836612 -143.442944)
		(stroke
			(width 0.2)
			(type default)
		)
		(layer "In1.Cu")
	)
	(gr_arc
		(start 285.436564 -142.345664)
		(mid 284.887924 -142.894304)
		(end 285.436564 -143.442944)
		(stroke
			(width 0.2)
			(type default)
		)
		(layer "In1.Cu")
	)
	(gr_line
		(start 285.436564 -139.843002)
		(end 286.836612 -139.843002)
		(stroke
			(width 0.2)
			(type default)
		)
		(layer "In1.Cu")
	)
	(gr_arc
		(start 285.436564 -138.745722)
		(mid 284.887924 -139.294362)
		(end 285.436564 -139.843002)
		(stroke
			(width 0.2)
			(type default)
		)
		(layer "In1.Cu")
	)
	(gr_line
		(start 285.436564 -136.24306)
		(end 286.836612 -136.24306)
		(stroke
			(width 0.2)
			(type default)
		)
		(layer "In1.Cu")
	)
	(gr_arc
		(start 285.436564 -135.14578)
		(mid 284.887924 -135.69442)
		(end 285.436564 -136.24306)
		(stroke
			(width 0.2)
			(type default)
		)
		(layer "In1.Cu")
	)
	(gr_line
		(start 285.436564 -132.643118)
		(end 286.836612 -132.643118)
		(stroke
			(width 0.2)
			(type default)
		)
		(layer "In1.Cu")
	)
	(gr_arc
		(start 285.436564 -131.545838)
		(mid 284.887924 -132.094478)
		(end 285.436564 -132.643118)
		(stroke
			(width 0.2)
			(type default)
		)
		(layer "In1.Cu")
	)
	(gr_line
		(start 286.436562 -239.243108)
		(end 287.83661 -239.243108)
		(stroke
			(width 0.2)
			(type default)
		)
		(layer "In1.Cu")
	)
	(gr_arc
		(start 286.436562 -238.145828)
		(mid 285.887922 -238.694468)
		(end 286.436562 -239.243108)
		(stroke
			(width 0.2)
			(type default)
		)
		(layer "In1.Cu")
	)
	(gr_line
		(start 286.436562 -235.643166)
		(end 287.83661 -235.643166)
		(stroke
			(width 0.2)
			(type default)
		)
		(layer "In1.Cu")
	)
	(gr_arc
		(start 286.436562 -234.545886)
		(mid 285.887922 -235.094526)
		(end 286.436562 -235.643166)
		(stroke
			(width 0.2)
			(type default)
		)
		(layer "In1.Cu")
	)
	(gr_line
		(start 286.436562 -232.043224)
		(end 287.83661 -232.043224)
		(stroke
			(width 0.2)
			(type default)
		)
		(layer "In1.Cu")
	)
	(gr_arc
		(start 286.436562 -230.945944)
		(mid 285.887922 -231.494584)
		(end 286.436562 -232.043224)
		(stroke
			(width 0.2)
			(type default)
		)
		(layer "In1.Cu")
	)
	(gr_line
		(start 286.436562 -228.443028)
		(end 287.83661 -228.443028)
		(stroke
			(width 0.2)
			(type default)
		)
		(layer "In1.Cu")
	)
	(gr_arc
		(start 286.436562 -227.345748)
		(mid 285.887922 -227.894388)
		(end 286.436562 -228.443028)
		(stroke
			(width 0.2)
			(type default)
		)
		(layer "In1.Cu")
	)
	(gr_line
		(start 286.436562 -224.906586)
		(end 287.83661 -224.906586)
		(stroke
			(width 0.2)
			(type default)
		)
		(layer "In1.Cu")
	)
	(gr_arc
		(start 286.436562 -223.682306)
		(mid 285.824422 -224.294446)
		(end 286.436562 -224.906586)
		(stroke
			(width 0.2)
			(type default)
		)
		(layer "In1.Cu")
	)
	(gr_line
		(start 286.436562 -221.243144)
		(end 287.83661 -221.243144)
		(stroke
			(width 0.2)
			(type default)
		)
		(layer "In1.Cu")
	)
	(gr_arc
		(start 286.436562 -220.145864)
		(mid 285.887922 -220.694504)
		(end 286.436562 -221.243144)
		(stroke
			(width 0.2)
			(type default)
		)
		(layer "In1.Cu")
	)
	(gr_line
		(start 286.436562 -217.643202)
		(end 287.83661 -217.643202)
		(stroke
			(width 0.2)
			(type default)
		)
		(layer "In1.Cu")
	)
	(gr_arc
		(start 286.436562 -216.545922)
		(mid 285.887922 -217.094562)
		(end 286.436562 -217.643202)
		(stroke
			(width 0.2)
			(type default)
		)
		(layer "In1.Cu")
	)
	(gr_line
		(start 286.436562 -214.043006)
		(end 287.83661 -214.043006)
		(stroke
			(width 0.2)
			(type default)
		)
		(layer "In1.Cu")
	)
	(gr_arc
		(start 286.436562 -212.945726)
		(mid 285.887922 -213.494366)
		(end 286.436562 -214.043006)
		(stroke
			(width 0.2)
			(type default)
		)
		(layer "In1.Cu")
	)
	(gr_line
		(start 286.436562 -210.443064)
		(end 287.83661 -210.443064)
		(stroke
			(width 0.2)
			(type default)
		)
		(layer "In1.Cu")
	)
	(gr_arc
		(start 286.436562 -209.345784)
		(mid 285.887922 -209.894424)
		(end 286.436562 -210.443064)
		(stroke
			(width 0.2)
			(type default)
		)
		(layer "In1.Cu")
	)
	(gr_line
		(start 286.436562 -206.843122)
		(end 287.83661 -206.843122)
		(stroke
			(width 0.2)
			(type default)
		)
		(layer "In1.Cu")
	)
	(gr_arc
		(start 286.436562 -205.745842)
		(mid 285.887922 -206.294482)
		(end 286.436562 -206.843122)
		(stroke
			(width 0.2)
			(type default)
		)
		(layer "In1.Cu")
	)
	(gr_line
		(start 286.436562 -203.24318)
		(end 287.83661 -203.24318)
		(stroke
			(width 0.2)
			(type default)
		)
		(layer "In1.Cu")
	)
	(gr_arc
		(start 286.436562 -202.1459)
		(mid 285.887922 -202.69454)
		(end 286.436562 -203.24318)
		(stroke
			(width 0.2)
			(type default)
		)
		(layer "In1.Cu")
	)
	(gr_line
		(start 286.436562 -199.642984)
		(end 287.83661 -199.642984)
		(stroke
			(width 0.2)
			(type default)
		)
		(layer "In1.Cu")
	)
	(gr_arc
		(start 286.436562 -198.545704)
		(mid 285.887922 -199.094344)
		(end 286.436562 -199.642984)
		(stroke
			(width 0.2)
			(type default)
		)
		(layer "In1.Cu")
	)
	(gr_line
		(start 286.436562 -196.043042)
		(end 287.83661 -196.043042)
		(stroke
			(width 0.2)
			(type default)
		)
		(layer "In1.Cu")
	)
	(gr_arc
		(start 286.436562 -194.945762)
		(mid 285.887922 -195.494402)
		(end 286.436562 -196.043042)
		(stroke
			(width 0.2)
			(type default)
		)
		(layer "In1.Cu")
	)
	(gr_line
		(start 286.436562 -192.4431)
		(end 287.83661 -192.4431)
		(stroke
			(width 0.2)
			(type default)
		)
		(layer "In1.Cu")
	)
	(gr_arc
		(start 286.436562 -191.34582)
		(mid 285.887922 -191.89446)
		(end 286.436562 -192.4431)
		(stroke
			(width 0.2)
			(type default)
		)
		(layer "In1.Cu")
	)
	(gr_line
		(start 286.436562 -188.843158)
		(end 287.83661 -188.843158)
		(stroke
			(width 0.2)
			(type default)
		)
		(layer "In1.Cu")
	)
	(gr_arc
		(start 286.436562 -187.745878)
		(mid 285.887922 -188.294518)
		(end 286.436562 -188.843158)
		(stroke
			(width 0.2)
			(type default)
		)
		(layer "In1.Cu")
	)
	(gr_line
		(start 286.436562 -185.243216)
		(end 287.83661 -185.243216)
		(stroke
			(width 0.2)
			(type default)
		)
		(layer "In1.Cu")
	)
	(gr_arc
		(start 286.436562 -184.145936)
		(mid 285.887922 -184.694576)
		(end 286.436562 -185.243216)
		(stroke
			(width 0.2)
			(type default)
		)
		(layer "In1.Cu")
	)
	(gr_line
		(start 286.436562 -181.64302)
		(end 287.83661 -181.64302)
		(stroke
			(width 0.2)
			(type default)
		)
		(layer "In1.Cu")
	)
	(gr_arc
		(start 286.436562 -180.54574)
		(mid 285.887922 -181.09438)
		(end 286.436562 -181.64302)
		(stroke
			(width 0.2)
			(type default)
		)
		(layer "In1.Cu")
	)
	(gr_line
		(start 286.436562 -178.043078)
		(end 287.83661 -178.043078)
		(stroke
			(width 0.2)
			(type default)
		)
		(layer "In1.Cu")
	)
	(gr_arc
		(start 286.436562 -176.945798)
		(mid 285.887922 -177.494438)
		(end 286.436562 -178.043078)
		(stroke
			(width 0.2)
			(type default)
		)
		(layer "In1.Cu")
	)
	(gr_line
		(start 286.436562 -145.243042)
		(end 287.83661 -145.243042)
		(stroke
			(width 0.2)
			(type default)
		)
		(layer "In1.Cu")
	)
	(gr_arc
		(start 286.436562 -144.145762)
		(mid 285.887922 -144.694402)
		(end 286.436562 -145.243042)
		(stroke
			(width 0.2)
			(type default)
		)
		(layer "In1.Cu")
	)
	(gr_line
		(start 286.436562 -141.6431)
		(end 287.83661 -141.6431)
		(stroke
			(width 0.2)
			(type default)
		)
		(layer "In1.Cu")
	)
	(gr_arc
		(start 286.436562 -140.54582)
		(mid 285.887922 -141.09446)
		(end 286.436562 -141.6431)
		(stroke
			(width 0.2)
			(type default)
		)
		(layer "In1.Cu")
	)
	(gr_line
		(start 286.436562 -138.043158)
		(end 287.83661 -138.043158)
		(stroke
			(width 0.2)
			(type default)
		)
		(layer "In1.Cu")
	)
	(gr_arc
		(start 286.436562 -136.945878)
		(mid 285.887922 -137.494518)
		(end 286.436562 -138.043158)
		(stroke
			(width 0.2)
			(type default)
		)
		(layer "In1.Cu")
	)
	(gr_line
		(start 286.436562 -134.442962)
		(end 287.83661 -134.442962)
		(stroke
			(width 0.2)
			(type default)
		)
		(layer "In1.Cu")
	)
	(gr_arc
		(start 286.436562 -133.345682)
		(mid 285.887922 -133.894322)
		(end 286.436562 -134.442962)
		(stroke
			(width 0.2)
			(type default)
		)
		(layer "In1.Cu")
	)
	(gr_line
		(start 286.436816 -223.682306)
		(end 286.436562 -223.682306)
		(stroke
			(width 0.2)
			(type default)
		)
		(layer "In1.Cu")
	)
	(gr_arc
		(start 286.836612 -237.44301)
		(mid 287.385252 -236.89437)
		(end 286.836612 -236.34573)
		(stroke
			(width 0.2)
			(type default)
		)
		(layer "In1.Cu")
	)
	(gr_line
		(start 286.836612 -236.34573)
		(end 285.436564 -236.34573)
		(stroke
			(width 0.2)
			(type default)
		)
		(layer "In1.Cu")
	)
	(gr_arc
		(start 286.836612 -233.843068)
		(mid 287.385252 -233.294428)
		(end 286.836612 -232.745788)
		(stroke
			(width 0.2)
			(type default)
		)
		(layer "In1.Cu")
	)
	(gr_line
		(start 286.836612 -232.745788)
		(end 285.436564 -232.745788)
		(stroke
			(width 0.2)
			(type default)
		)
		(layer "In1.Cu")
	)
	(gr_arc
		(start 286.836612 -230.243126)
		(mid 287.385252 -229.694486)
		(end 286.836612 -229.145846)
		(stroke
			(width 0.2)
			(type default)
		)
		(layer "In1.Cu")
	)
	(gr_line
		(start 286.836612 -229.145846)
		(end 285.436564 -229.145846)
		(stroke
			(width 0.2)
			(type default)
		)
		(layer "In1.Cu")
	)
	(gr_arc
		(start 286.836612 -226.643184)
		(mid 287.385252 -226.094544)
		(end 286.836612 -225.545904)
		(stroke
			(width 0.2)
			(type default)
		)
		(layer "In1.Cu")
	)
	(gr_line
		(start 286.836612 -225.545904)
		(end 285.436564 -225.545904)
		(stroke
			(width 0.2)
			(type default)
		)
		(layer "In1.Cu")
	)
	(gr_arc
		(start 286.836612 -223.042988)
		(mid 287.385252 -222.494348)
		(end 286.836612 -221.945708)
		(stroke
			(width 0.2)
			(type default)
		)
		(layer "In1.Cu")
	)
	(gr_line
		(start 286.836612 -221.945708)
		(end 285.436564 -221.945708)
		(stroke
			(width 0.2)
			(type default)
		)
		(layer "In1.Cu")
	)
	(gr_arc
		(start 286.836612 -219.443046)
		(mid 287.385252 -218.894406)
		(end 286.836612 -218.345766)
		(stroke
			(width 0.2)
			(type default)
		)
		(layer "In1.Cu")
	)
	(gr_line
		(start 286.836612 -218.345766)
		(end 285.436564 -218.345766)
		(stroke
			(width 0.2)
			(type default)
		)
		(layer "In1.Cu")
	)
	(gr_arc
		(start 286.836612 -215.843104)
		(mid 287.385252 -215.294464)
		(end 286.836612 -214.745824)
		(stroke
			(width 0.2)
			(type default)
		)
		(layer "In1.Cu")
	)
	(gr_line
		(start 286.836612 -214.745824)
		(end 285.436564 -214.745824)
		(stroke
			(width 0.2)
			(type default)
		)
		(layer "In1.Cu")
	)
	(gr_arc
		(start 286.836612 -212.243162)
		(mid 287.385252 -211.694522)
		(end 286.836612 -211.145882)
		(stroke
			(width 0.2)
			(type default)
		)
		(layer "In1.Cu")
	)
	(gr_line
		(start 286.836612 -211.145882)
		(end 285.436564 -211.145882)
		(stroke
			(width 0.2)
			(type default)
		)
		(layer "In1.Cu")
	)
	(gr_arc
		(start 286.836612 -208.64322)
		(mid 287.385252 -208.09458)
		(end 286.836612 -207.54594)
		(stroke
			(width 0.2)
			(type default)
		)
		(layer "In1.Cu")
	)
	(gr_line
		(start 286.836612 -207.54594)
		(end 285.436564 -207.54594)
		(stroke
			(width 0.2)
			(type default)
		)
		(layer "In1.Cu")
	)
	(gr_arc
		(start 286.836612 -205.043024)
		(mid 287.385252 -204.494384)
		(end 286.836612 -203.945744)
		(stroke
			(width 0.2)
			(type default)
		)
		(layer "In1.Cu")
	)
	(gr_line
		(start 286.836612 -203.945744)
		(end 285.436564 -203.945744)
		(stroke
			(width 0.2)
			(type default)
		)
		(layer "In1.Cu")
	)
	(gr_arc
		(start 286.836612 -201.443082)
		(mid 287.385252 -200.894442)
		(end 286.836612 -200.345802)
		(stroke
			(width 0.2)
			(type default)
		)
		(layer "In1.Cu")
	)
	(gr_line
		(start 286.836612 -200.345802)
		(end 285.436564 -200.345802)
		(stroke
			(width 0.2)
			(type default)
		)
		(layer "In1.Cu")
	)
	(gr_arc
		(start 286.836612 -197.84314)
		(mid 287.385252 -197.2945)
		(end 286.836612 -196.74586)
		(stroke
			(width 0.2)
			(type default)
		)
		(layer "In1.Cu")
	)
	(gr_line
		(start 286.836612 -196.74586)
		(end 285.436564 -196.74586)
		(stroke
			(width 0.2)
			(type default)
		)
		(layer "In1.Cu")
	)
	(gr_arc
		(start 286.836612 -194.243198)
		(mid 287.385252 -193.694558)
		(end 286.836612 -193.145918)
		(stroke
			(width 0.2)
			(type default)
		)
		(layer "In1.Cu")
	)
	(gr_line
		(start 286.836612 -193.145918)
		(end 285.436564 -193.145918)
		(stroke
			(width 0.2)
			(type default)
		)
		(layer "In1.Cu")
	)
	(gr_arc
		(start 286.836612 -190.643002)
		(mid 287.385252 -190.094362)
		(end 286.836612 -189.545722)
		(stroke
			(width 0.2)
			(type default)
		)
		(layer "In1.Cu")
	)
	(gr_line
		(start 286.836612 -189.545722)
		(end 285.436564 -189.545722)
		(stroke
			(width 0.2)
			(type default)
		)
		(layer "In1.Cu")
	)
	(gr_arc
		(start 286.836612 -187.04306)
		(mid 287.385252 -186.49442)
		(end 286.836612 -185.94578)
		(stroke
			(width 0.2)
			(type default)
		)
		(layer "In1.Cu")
	)
	(gr_line
		(start 286.836612 -185.94578)
		(end 285.436564 -185.94578)
		(stroke
			(width 0.2)
			(type default)
		)
		(layer "In1.Cu")
	)
	(gr_arc
		(start 286.836612 -183.443118)
		(mid 287.385252 -182.894478)
		(end 286.836612 -182.345838)
		(stroke
			(width 0.2)
			(type default)
		)
		(layer "In1.Cu")
	)
	(gr_line
		(start 286.836612 -182.345838)
		(end 285.436564 -182.345838)
		(stroke
			(width 0.2)
			(type default)
		)
		(layer "In1.Cu")
	)
	(gr_arc
		(start 286.836612 -179.843176)
		(mid 287.385252 -179.294536)
		(end 286.836612 -178.745896)
		(stroke
			(width 0.2)
			(type default)
		)
		(layer "In1.Cu")
	)
	(gr_line
		(start 286.836612 -178.745896)
		(end 285.436564 -178.745896)
		(stroke
			(width 0.2)
			(type default)
		)
		(layer "In1.Cu")
	)
	(gr_arc
		(start 286.836612 -176.243234)
		(mid 287.385252 -175.694594)
		(end 286.836612 -175.145954)
		(stroke
			(width 0.2)
			(type default)
		)
		(layer "In1.Cu")
	)
	(gr_line
		(start 286.836612 -175.145954)
		(end 285.436564 -175.145954)
		(stroke
			(width 0.2)
			(type default)
		)
		(layer "In1.Cu")
	)
	(gr_arc
		(start 286.836612 -143.442944)
		(mid 287.385252 -142.894304)
		(end 286.836612 -142.345664)
		(stroke
			(width 0.2)
			(type default)
		)
		(layer "In1.Cu")
	)
	(gr_line
		(start 286.836612 -142.345664)
		(end 285.436564 -142.345664)
		(stroke
			(width 0.2)
			(type default)
		)
		(layer "In1.Cu")
	)
	(gr_arc
		(start 286.836612 -139.843002)
		(mid 287.385252 -139.294362)
		(end 286.836612 -138.745722)
		(stroke
			(width 0.2)
			(type default)
		)
		(layer "In1.Cu")
	)
	(gr_line
		(start 286.836612 -138.745722)
		(end 285.436564 -138.745722)
		(stroke
			(width 0.2)
			(type default)
		)
		(layer "In1.Cu")
	)
	(gr_arc
		(start 286.836612 -136.24306)
		(mid 287.385252 -135.69442)
		(end 286.836612 -135.14578)
		(stroke
			(width 0.2)
			(type default)
		)
		(layer "In1.Cu")
	)
	(gr_line
		(start 286.836612 -135.14578)
		(end 285.436564 -135.14578)
		(stroke
			(width 0.2)
			(type default)
		)
		(layer "In1.Cu")
	)
	(gr_arc
		(start 286.836612 -132.643118)
		(mid 287.385252 -132.094478)
		(end 286.836612 -131.545838)
		(stroke
			(width 0.2)
			(type default)
		)
		(layer "In1.Cu")
	)
	(gr_line
		(start 286.836612 -131.545838)
		(end 285.436564 -131.545838)
		(stroke
			(width 0.2)
			(type default)
		)
		(layer "In1.Cu")
	)
	(gr_arc
		(start 287.83661 -239.243108)
		(mid 288.38525 -238.694468)
		(end 287.83661 -238.145828)
		(stroke
			(width 0.2)
			(type default)
		)
		(layer "In1.Cu")
	)
	(gr_line
		(start 287.83661 -238.145828)
		(end 286.436562 -238.145828)
		(stroke
			(width 0.2)
			(type default)
		)
		(layer "In1.Cu")
	)
	(gr_arc
		(start 287.83661 -235.643166)
		(mid 288.38525 -235.094526)
		(end 287.83661 -234.545886)
		(stroke
			(width 0.2)
			(type default)
		)
		(layer "In1.Cu")
	)
	(gr_line
		(start 287.83661 -234.545886)
		(end 286.436562 -234.545886)
		(stroke
			(width 0.2)
			(type default)
		)
		(layer "In1.Cu")
	)
	(gr_arc
		(start 287.83661 -232.043224)
		(mid 288.38525 -231.494584)
		(end 287.83661 -230.945944)
		(stroke
			(width 0.2)
			(type default)
		)
		(layer "In1.Cu")
	)
	(gr_line
		(start 287.83661 -230.945944)
		(end 286.436562 -230.945944)
		(stroke
			(width 0.2)
			(type default)
		)
		(layer "In1.Cu")
	)
	(gr_arc
		(start 287.83661 -228.443028)
		(mid 288.38525 -227.894388)
		(end 287.83661 -227.345748)
		(stroke
			(width 0.2)
			(type default)
		)
		(layer "In1.Cu")
	)
	(gr_line
		(start 287.83661 -227.345748)
		(end 286.436562 -227.345748)
		(stroke
			(width 0.2)
			(type default)
		)
		(layer "In1.Cu")
	)
	(gr_arc
		(start 287.83661 -224.906586)
		(mid 288.44875 -224.294446)
		(end 287.83661 -223.682306)
		(stroke
			(width 0.2)
			(type default)
		)
		(layer "In1.Cu")
	)
	(gr_line
		(start 287.83661 -223.682306)
		(end 286.436816 -223.682306)
		(stroke
			(width 0.2)
			(type default)
		)
		(layer "In1.Cu")
	)
	(gr_arc
		(start 287.83661 -221.243144)
		(mid 288.38525 -220.694504)
		(end 287.83661 -220.145864)
		(stroke
			(width 0.2)
			(type default)
		)
		(layer "In1.Cu")
	)
	(gr_line
		(start 287.83661 -220.145864)
		(end 286.436562 -220.145864)
		(stroke
			(width 0.2)
			(type default)
		)
		(layer "In1.Cu")
	)
	(gr_arc
		(start 287.83661 -217.643202)
		(mid 288.38525 -217.094562)
		(end 287.83661 -216.545922)
		(stroke
			(width 0.2)
			(type default)
		)
		(layer "In1.Cu")
	)
	(gr_line
		(start 287.83661 -216.545922)
		(end 286.436562 -216.545922)
		(stroke
			(width 0.2)
			(type default)
		)
		(layer "In1.Cu")
	)
	(gr_arc
		(start 287.83661 -214.043006)
		(mid 288.38525 -213.494366)
		(end 287.83661 -212.945726)
		(stroke
			(width 0.2)
			(type default)
		)
		(layer "In1.Cu")
	)
	(gr_line
		(start 287.83661 -212.945726)
		(end 286.436562 -212.945726)
		(stroke
			(width 0.2)
			(type default)
		)
		(layer "In1.Cu")
	)
	(gr_arc
		(start 287.83661 -210.443064)
		(mid 288.38525 -209.894424)
		(end 287.83661 -209.345784)
		(stroke
			(width 0.2)
			(type default)
		)
		(layer "In1.Cu")
	)
	(gr_line
		(start 287.83661 -209.345784)
		(end 286.436562 -209.345784)
		(stroke
			(width 0.2)
			(type default)
		)
		(layer "In1.Cu")
	)
	(gr_arc
		(start 287.83661 -206.843122)
		(mid 288.38525 -206.294482)
		(end 287.83661 -205.745842)
		(stroke
			(width 0.2)
			(type default)
		)
		(layer "In1.Cu")
	)
	(gr_line
		(start 287.83661 -205.745842)
		(end 286.436562 -205.745842)
		(stroke
			(width 0.2)
			(type default)
		)
		(layer "In1.Cu")
	)
	(gr_arc
		(start 287.83661 -203.24318)
		(mid 288.38525 -202.69454)
		(end 287.83661 -202.1459)
		(stroke
			(width 0.2)
			(type default)
		)
		(layer "In1.Cu")
	)
	(gr_line
		(start 287.83661 -202.1459)
		(end 286.436562 -202.1459)
		(stroke
			(width 0.2)
			(type default)
		)
		(layer "In1.Cu")
	)
	(gr_arc
		(start 287.83661 -199.642984)
		(mid 288.38525 -199.094344)
		(end 287.83661 -198.545704)
		(stroke
			(width 0.2)
			(type default)
		)
		(layer "In1.Cu")
	)
	(gr_line
		(start 287.83661 -198.545704)
		(end 286.436562 -198.545704)
		(stroke
			(width 0.2)
			(type default)
		)
		(layer "In1.Cu")
	)
	(gr_arc
		(start 287.83661 -196.043042)
		(mid 288.38525 -195.494402)
		(end 287.83661 -194.945762)
		(stroke
			(width 0.2)
			(type default)
		)
		(layer "In1.Cu")
	)
	(gr_line
		(start 287.83661 -194.945762)
		(end 286.436562 -194.945762)
		(stroke
			(width 0.2)
			(type default)
		)
		(layer "In1.Cu")
	)
	(gr_arc
		(start 287.83661 -192.4431)
		(mid 288.38525 -191.89446)
		(end 287.83661 -191.34582)
		(stroke
			(width 0.2)
			(type default)
		)
		(layer "In1.Cu")
	)
	(gr_line
		(start 287.83661 -191.34582)
		(end 286.436562 -191.34582)
		(stroke
			(width 0.2)
			(type default)
		)
		(layer "In1.Cu")
	)
	(gr_arc
		(start 287.83661 -188.843158)
		(mid 288.38525 -188.294518)
		(end 287.83661 -187.745878)
		(stroke
			(width 0.2)
			(type default)
		)
		(layer "In1.Cu")
	)
	(gr_line
		(start 287.83661 -187.745878)
		(end 286.436562 -187.745878)
		(stroke
			(width 0.2)
			(type default)
		)
		(layer "In1.Cu")
	)
	(gr_arc
		(start 287.83661 -185.243216)
		(mid 288.38525 -184.694576)
		(end 287.83661 -184.145936)
		(stroke
			(width 0.2)
			(type default)
		)
		(layer "In1.Cu")
	)
	(gr_line
		(start 287.83661 -184.145936)
		(end 286.436562 -184.145936)
		(stroke
			(width 0.2)
			(type default)
		)
		(layer "In1.Cu")
	)
	(gr_arc
		(start 287.83661 -181.64302)
		(mid 288.38525 -181.09438)
		(end 287.83661 -180.54574)
		(stroke
			(width 0.2)
			(type default)
		)
		(layer "In1.Cu")
	)
	(gr_line
		(start 287.83661 -180.54574)
		(end 286.436562 -180.54574)
		(stroke
			(width 0.2)
			(type default)
		)
		(layer "In1.Cu")
	)
	(gr_arc
		(start 287.83661 -178.043078)
		(mid 288.38525 -177.494438)
		(end 287.83661 -176.945798)
		(stroke
			(width 0.2)
			(type default)
		)
		(layer "In1.Cu")
	)
	(gr_line
		(start 287.83661 -176.945798)
		(end 286.436562 -176.945798)
		(stroke
			(width 0.2)
			(type default)
		)
		(layer "In1.Cu")
	)
	(gr_arc
		(start 287.83661 -145.243042)
		(mid 288.38525 -144.694402)
		(end 287.83661 -144.145762)
		(stroke
			(width 0.2)
			(type default)
		)
		(layer "In1.Cu")
	)
	(gr_line
		(start 287.83661 -144.145762)
		(end 286.436562 -144.145762)
		(stroke
			(width 0.2)
			(type default)
		)
		(layer "In1.Cu")
	)
	(gr_arc
		(start 287.83661 -141.6431)
		(mid 288.38525 -141.09446)
		(end 287.83661 -140.54582)
		(stroke
			(width 0.2)
			(type default)
		)
		(layer "In1.Cu")
	)
	(gr_line
		(start 287.83661 -140.54582)
		(end 286.436562 -140.54582)
		(stroke
			(width 0.2)
			(type default)
		)
		(layer "In1.Cu")
	)
	(gr_arc
		(start 287.83661 -138.043158)
		(mid 288.38525 -137.494518)
		(end 287.83661 -136.945878)
		(stroke
			(width 0.2)
			(type default)
		)
		(layer "In1.Cu")
	)
	(gr_line
		(start 287.83661 -136.945878)
		(end 286.436562 -136.945878)
		(stroke
			(width 0.2)
			(type default)
		)
		(layer "In1.Cu")
	)
	(gr_arc
		(start 287.83661 -134.442962)
		(mid 288.38525 -133.894322)
		(end 287.83661 -133.345682)
		(stroke
			(width 0.2)
			(type default)
		)
		(layer "In1.Cu")
	)
	(gr_line
		(start 287.83661 -133.345682)
		(end 286.436562 -133.345682)
		(stroke
			(width 0.2)
			(type default)
		)
		(layer "In1.Cu")
	)
	(gr_line
		(start 306.649882 -385.99999)
		(end 280.164286 -385.99999)
		(stroke
			(width 1.524)
			(type default)
		)
		(layer "In1.Cu")
	)
	(gr_arc
		(start 306.649882 -385.99999)
		(mid 307.356996 -385.707103)
		(end 307.64988 -384.999992)
		(stroke
			(width 1.524)
			(type default)
		)
		(layer "In1.Cu")
	)
	(gr_line
		(start 307.64988 -383.29997)
		(end 307.64988 -384.999992)
		(stroke
			(width 1.524)
			(type default)
		)
		(layer "In1.Cu")
	)
	(gr_arc
		(start 308.649878 -382.299972)
		(mid 307.942773 -382.592865)
		(end 307.64988 -383.29997)
		(stroke
			(width 1.524)
			(type default)
		)
		(layer "In1.Cu")
	)
	(gr_arc
		(start 309.999888 -48.200056)
		(mid 310.706993 -47.907163)
		(end 310.999886 -47.200058)
		(stroke
			(width 1.524)
			(type default)
		)
		(layer "In1.Cu")
	)
	(gr_line
		(start 310.999886 -47.200058)
		(end 310.999886 -0.999998)
		(stroke
			(width 1.524)
			(type default)
		)
		(layer "In1.Cu")
	)
	(gr_arc
		(start 311.999884 0)
		(mid 311.292788 -0.292898)
		(end 310.999886 -0.999998)
		(stroke
			(width 1.524)
			(type default)
		)
		(layer "In1.Cu")
	)
	(gr_line
		(start 311.999884 0)
		(end 490.450124 0)
		(stroke
			(width 1.524)
			(type default)
		)
		(layer "In1.Cu")
	)
	(gr_line
		(start 315.149992 -382.299972)
		(end 308.649878 -382.299972)
		(stroke
			(width 1.524)
			(type default)
		)
		(layer "In1.Cu")
	)
	(gr_line
		(start 316.14999 -384.999992)
		(end 316.14999 -383.29997)
		(stroke
			(width 1.524)
			(type default)
		)
		(layer "In1.Cu")
	)
	(gr_arc
		(start 316.14999 -384.999992)
		(mid 316.442879 -385.707107)
		(end 317.149988 -385.99999)
		(stroke
			(width 1.524)
			(type default)
		)
		(layer "In1.Cu")
	)
	(gr_arc
		(start 316.14999 -383.29997)
		(mid 315.857097 -382.592865)
		(end 315.149992 -382.299972)
		(stroke
			(width 1.524)
			(type default)
		)
		(layer "In1.Cu")
	)
	(gr_arc
		(start 318.91732 -245.45544)
		(mid 319.402333 -245.940834)
		(end 319.8876 -245.455694)
		(stroke
			(width 0.2)
			(type default)
		)
		(layer "In1.Cu")
	)
	(gr_line
		(start 318.91732 -244.312694)
		(end 318.91732 -245.45544)
		(stroke
			(width 0.2)
			(type default)
		)
		(layer "In1.Cu")
	)
	(gr_line
		(start 319.2145 -129.112264)
		(end 320.3575 -129.112264)
		(stroke
			(width 0.2)
			(type default)
		)
		(layer "In1.Cu")
	)
	(gr_line
		(start 319.2145 -14.11224)
		(end 320.3575 -14.11224)
		(stroke
			(width 0.2)
			(type default)
		)
		(layer "In1.Cu")
	)
	(gr_arc
		(start 319.214754 -128.141984)
		(mid 318.72936 -128.626997)
		(end 319.2145 -129.112264)
		(stroke
			(width 0.2)
			(type default)
		)
		(layer "In1.Cu")
	)
	(gr_arc
		(start 319.214754 -13.14196)
		(mid 318.72936 -13.626973)
		(end 319.2145 -14.11224)
		(stroke
			(width 0.2)
			(type default)
		)
		(layer "In1.Cu")
	)
	(gr_line
		(start 319.8876 -245.455694)
		(end 319.8876 -244.312694)
		(stroke
			(width 0.2)
			(type default)
		)
		(layer "In1.Cu")
	)
	(gr_arc
		(start 319.8876 -244.312694)
		(mid 319.40246 -243.827554)
		(end 318.91732 -244.312694)
		(stroke
			(width 0.2)
			(type default)
		)
		(layer "In1.Cu")
	)
	(gr_arc
		(start 320.3575 -129.112264)
		(mid 320.84264 -128.627124)
		(end 320.3575 -128.141984)
		(stroke
			(width 0.2)
			(type default)
		)
		(layer "In1.Cu")
	)
	(gr_line
		(start 320.3575 -128.141984)
		(end 319.214754 -128.141984)
		(stroke
			(width 0.2)
			(type default)
		)
		(layer "In1.Cu")
	)
	(gr_arc
		(start 320.3575 -14.11224)
		(mid 320.84264 -13.6271)
		(end 320.3575 -13.14196)
		(stroke
			(width 0.2)
			(type default)
		)
		(layer "In1.Cu")
	)
	(gr_line
		(start 320.3575 -13.14196)
		(end 319.214754 -13.14196)
		(stroke
			(width 0.2)
			(type default)
		)
		(layer "In1.Cu")
	)
	(gr_arc
		(start 321.177412 -245.321074)
		(mid 321.192291 -245.356995)
		(end 321.228212 -245.371874)
		(stroke
			(width 0.2)
			(type default)
		)
		(layer "In1.Cu")
	)
	(gr_line
		(start 321.177412 -245.117874)
		(end 321.177412 -245.321074)
		(stroke
			(width 0.2)
			(type default)
		)
		(layer "In1.Cu")
	)
	(gr_arc
		(start 321.177412 -244.762274)
		(mid 321.192291 -244.798195)
		(end 321.228212 -244.813074)
		(stroke
			(width 0.2)
			(type default)
		)
		(layer "In1.Cu")
	)
	(gr_line
		(start 321.177412 -244.559074)
		(end 321.177412 -244.762274)
		(stroke
			(width 0.2)
			(type default)
		)
		(layer "In1.Cu")
	)
	(gr_arc
		(start 321.177412 -130.32105)
		(mid 321.192291 -130.356971)
		(end 321.228212 -130.37185)
		(stroke
			(width 0.2)
			(type default)
		)
		(layer "In1.Cu")
	)
	(gr_line
		(start 321.177412 -130.11785)
		(end 321.177412 -130.32105)
		(stroke
			(width 0.2)
			(type default)
		)
		(layer "In1.Cu")
	)
	(gr_arc
		(start 321.177412 -129.76225)
		(mid 321.192291 -129.798171)
		(end 321.228212 -129.81305)
		(stroke
			(width 0.2)
			(type default)
		)
		(layer "In1.Cu")
	)
	(gr_line
		(start 321.177412 -129.55905)
		(end 321.177412 -129.76225)
		(stroke
			(width 0.2)
			(type default)
		)
		(layer "In1.Cu")
	)
	(gr_arc
		(start 321.177412 -15.321026)
		(mid 321.192291 -15.356947)
		(end 321.228212 -15.371826)
		(stroke
			(width 0.2)
			(type default)
		)
		(layer "In1.Cu")
	)
	(gr_line
		(start 321.177412 -15.117826)
		(end 321.177412 -15.321026)
		(stroke
			(width 0.2)
			(type default)
		)
		(layer "In1.Cu")
	)
	(gr_arc
		(start 321.177412 -14.762226)
		(mid 321.192291 -14.798147)
		(end 321.228212 -14.813026)
		(stroke
			(width 0.2)
			(type default)
		)
		(layer "In1.Cu")
	)
	(gr_line
		(start 321.177412 -14.559026)
		(end 321.177412 -14.762226)
		(stroke
			(width 0.2)
			(type default)
		)
		(layer "In1.Cu")
	)
	(gr_line
		(start 321.228212 -245.371874)
		(end 322.041012 -245.371874)
		(stroke
			(width 0.2)
			(type default)
		)
		(layer "In1.Cu")
	)
	(gr_arc
		(start 321.228212 -245.067074)
		(mid 321.192291 -245.081953)
		(end 321.177412 -245.117874)
		(stroke
			(width 0.2)
			(type default)
		)
		(layer "In1.Cu")
	)
	(gr_line
		(start 321.228212 -244.813074)
		(end 322.041012 -244.813074)
		(stroke
			(width 0.2)
			(type default)
		)
		(layer "In1.Cu")
	)
	(gr_arc
		(start 321.228212 -244.508274)
		(mid 321.192291 -244.523153)
		(end 321.177412 -244.559074)
		(stroke
			(width 0.2)
			(type default)
		)
		(layer "In1.Cu")
	)
	(gr_line
		(start 321.228212 -130.37185)
		(end 322.041012 -130.37185)
		(stroke
			(width 0.2)
			(type default)
		)
		(layer "In1.Cu")
	)
	(gr_arc
		(start 321.228212 -130.06705)
		(mid 321.192291 -130.081929)
		(end 321.177412 -130.11785)
		(stroke
			(width 0.2)
			(type default)
		)
		(layer "In1.Cu")
	)
	(gr_line
		(start 321.228212 -129.81305)
		(end 322.041012 -129.81305)
		(stroke
			(width 0.2)
			(type default)
		)
		(layer "In1.Cu")
	)
	(gr_arc
		(start 321.228212 -129.50825)
		(mid 321.192291 -129.523129)
		(end 321.177412 -129.55905)
		(stroke
			(width 0.2)
			(type default)
		)
		(layer "In1.Cu")
	)
	(gr_line
		(start 321.228212 -15.371826)
		(end 322.041012 -15.371826)
		(stroke
			(width 0.2)
			(type default)
		)
		(layer "In1.Cu")
	)
	(gr_arc
		(start 321.228212 -15.067026)
		(mid 321.192291 -15.081905)
		(end 321.177412 -15.117826)
		(stroke
			(width 0.2)
			(type default)
		)
		(layer "In1.Cu")
	)
	(gr_line
		(start 321.228212 -14.813026)
		(end 322.041012 -14.813026)
		(stroke
			(width 0.2)
			(type default)
		)
		(layer "In1.Cu")
	)
	(gr_arc
		(start 321.228212 -14.508226)
		(mid 321.192291 -14.523105)
		(end 321.177412 -14.559026)
		(stroke
			(width 0.2)
			(type default)
		)
		(layer "In1.Cu")
	)
	(gr_arc
		(start 322.041012 -245.371874)
		(mid 322.076933 -245.356995)
		(end 322.091812 -245.321074)
		(stroke
			(width 0.2)
			(type default)
		)
		(layer "In1.Cu")
	)
	(gr_line
		(start 322.041012 -245.067074)
		(end 321.228212 -245.067074)
		(stroke
			(width 0.2)
			(type default)
		)
		(layer "In1.Cu")
	)
	(gr_arc
		(start 322.041012 -244.813074)
		(mid 322.076933 -244.798195)
		(end 322.091812 -244.762274)
		(stroke
			(width 0.2)
			(type default)
		)
		(layer "In1.Cu")
	)
	(gr_line
		(start 322.041012 -244.508274)
		(end 321.228212 -244.508274)
		(stroke
			(width 0.2)
			(type default)
		)
		(layer "In1.Cu")
	)
	(gr_arc
		(start 322.041012 -130.37185)
		(mid 322.076933 -130.356971)
		(end 322.091812 -130.32105)
		(stroke
			(width 0.2)
			(type default)
		)
		(layer "In1.Cu")
	)
	(gr_line
		(start 322.041012 -130.06705)
		(end 321.228212 -130.06705)
		(stroke
			(width 0.2)
			(type default)
		)
		(layer "In1.Cu")
	)
	(gr_arc
		(start 322.041012 -129.81305)
		(mid 322.076933 -129.798171)
		(end 322.091812 -129.76225)
		(stroke
			(width 0.2)
			(type default)
		)
		(layer "In1.Cu")
	)
	(gr_line
		(start 322.041012 -129.50825)
		(end 321.228212 -129.50825)
		(stroke
			(width 0.2)
			(type default)
		)
		(layer "In1.Cu")
	)
	(gr_arc
		(start 322.041012 -15.371826)
		(mid 322.076933 -15.356947)
		(end 322.091812 -15.321026)
		(stroke
			(width 0.2)
			(type default)
		)
		(layer "In1.Cu")
	)
	(gr_line
		(start 322.041012 -15.067026)
		(end 321.228212 -15.067026)
		(stroke
			(width 0.2)
			(type default)
		)
		(layer "In1.Cu")
	)
	(gr_arc
		(start 322.041012 -14.813026)
		(mid 322.076933 -14.798147)
		(end 322.091812 -14.762226)
		(stroke
			(width 0.2)
			(type default)
		)
		(layer "In1.Cu")
	)
	(gr_line
		(start 322.041012 -14.508226)
		(end 321.228212 -14.508226)
		(stroke
			(width 0.2)
			(type default)
		)
		(layer "In1.Cu")
	)
	(gr_line
		(start 322.091812 -245.321074)
		(end 322.091812 -245.117874)
		(stroke
			(width 0.2)
			(type default)
		)
		(layer "In1.Cu")
	)
	(gr_arc
		(start 322.091812 -245.117874)
		(mid 322.076933 -245.081953)
		(end 322.041012 -245.067074)
		(stroke
			(width 0.2)
			(type default)
		)
		(layer "In1.Cu")
	)
	(gr_line
		(start 322.091812 -244.762274)
		(end 322.091812 -244.559074)
		(stroke
			(width 0.2)
			(type default)
		)
		(layer "In1.Cu")
	)
	(gr_arc
		(start 322.091812 -244.559074)
		(mid 322.076933 -244.523153)
		(end 322.041012 -244.508274)
		(stroke
			(width 0.2)
			(type default)
		)
		(layer "In1.Cu")
	)
	(gr_line
		(start 322.091812 -130.32105)
		(end 322.091812 -130.11785)
		(stroke
			(width 0.2)
			(type default)
		)
		(layer "In1.Cu")
	)
	(gr_arc
		(start 322.091812 -130.11785)
		(mid 322.076933 -130.081929)
		(end 322.041012 -130.06705)
		(stroke
			(width 0.2)
			(type default)
		)
		(layer "In1.Cu")
	)
	(gr_line
		(start 322.091812 -129.76225)
		(end 322.091812 -129.55905)
		(stroke
			(width 0.2)
			(type default)
		)
		(layer "In1.Cu")
	)
	(gr_arc
		(start 322.091812 -129.55905)
		(mid 322.076933 -129.523129)
		(end 322.041012 -129.50825)
		(stroke
			(width 0.2)
			(type default)
		)
		(layer "In1.Cu")
	)
	(gr_line
		(start 322.091812 -15.321026)
		(end 322.091812 -15.117826)
		(stroke
			(width 0.2)
			(type default)
		)
		(layer "In1.Cu")
	)
	(gr_arc
		(start 322.091812 -15.117826)
		(mid 322.076933 -15.081905)
		(end 322.041012 -15.067026)
		(stroke
			(width 0.2)
			(type default)
		)
		(layer "In1.Cu")
	)
	(gr_line
		(start 322.091812 -14.762226)
		(end 322.091812 -14.559026)
		(stroke
			(width 0.2)
			(type default)
		)
		(layer "In1.Cu")
	)
	(gr_arc
		(start 322.091812 -14.559026)
		(mid 322.076933 -14.523105)
		(end 322.041012 -14.508226)
		(stroke
			(width 0.2)
			(type default)
		)
		(layer "In1.Cu")
	)
	(gr_line
		(start 322.6816 -132.922264)
		(end 323.951346 -132.922264)
		(stroke
			(width 0.2)
			(type default)
		)
		(layer "In1.Cu")
	)
	(gr_arc
		(start 322.6816 -131.951984)
		(mid 322.19646 -132.437124)
		(end 322.6816 -132.922264)
		(stroke
			(width 0.2)
			(type default)
		)
		(layer "In1.Cu")
	)
	(gr_line
		(start 322.6816 -17.92224)
		(end 323.951346 -17.92224)
		(stroke
			(width 0.2)
			(type default)
		)
		(layer "In1.Cu")
	)
	(gr_arc
		(start 322.6816 -16.95196)
		(mid 322.19646 -17.4371)
		(end 322.6816 -17.92224)
		(stroke
			(width 0.2)
			(type default)
		)
		(layer "In1.Cu")
	)
	(gr_arc
		(start 323.10451 -249.385074)
		(mid 323.58965 -249.870214)
		(end 324.07479 -249.385074)
		(stroke
			(width 0.2)
			(type default)
		)
		(layer "In1.Cu")
	)
	(gr_line
		(start 323.10451 -248.115074)
		(end 323.10451 -249.385074)
		(stroke
			(width 0.2)
			(type default)
		)
		(layer "In1.Cu")
	)
	(gr_arc
		(start 323.951346 -132.922264)
		(mid 324.43674 -132.437251)
		(end 323.9516 -131.951984)
		(stroke
			(width 0.2)
			(type default)
		)
		(layer "In1.Cu")
	)
	(gr_arc
		(start 323.951346 -17.92224)
		(mid 324.43674 -17.437227)
		(end 323.9516 -16.95196)
		(stroke
			(width 0.2)
			(type default)
		)
		(layer "In1.Cu")
	)
	(gr_line
		(start 323.9516 -131.951984)
		(end 322.6816 -131.951984)
		(stroke
			(width 0.2)
			(type default)
		)
		(layer "In1.Cu")
	)
	(gr_line
		(start 323.9516 -16.95196)
		(end 322.6816 -16.95196)
		(stroke
			(width 0.2)
			(type default)
		)
		(layer "In1.Cu")
	)
	(gr_line
		(start 324.07479 -249.385074)
		(end 324.07479 -248.115328)
		(stroke
			(width 0.2)
			(type default)
		)
		(layer "In1.Cu")
	)
	(gr_arc
		(start 324.07479 -248.115328)
		(mid 323.589777 -247.629934)
		(end 323.10451 -248.115074)
		(stroke
			(width 0.2)
			(type default)
		)
		(layer "In1.Cu")
	)
	(gr_line
		(start 326.193912 -250.350274)
		(end 326.193912 -247.149874)
		(stroke
			(width 0.2)
			(type default)
		)
		(layer "In1.Cu")
	)
	(gr_line
		(start 326.193912 -247.149874)
		(end 328.556112 -247.149874)
		(stroke
			(width 0.2)
			(type default)
		)
		(layer "In1.Cu")
	)
	(gr_line
		(start 326.193912 -246.540274)
		(end 326.193912 -243.339874)
		(stroke
			(width 0.2)
			(type default)
		)
		(layer "In1.Cu")
	)
	(gr_line
		(start 326.193912 -243.339874)
		(end 328.556112 -243.339874)
		(stroke
			(width 0.2)
			(type default)
		)
		(layer "In1.Cu")
	)
	(gr_line
		(start 326.193912 -135.35025)
		(end 326.193912 -132.14985)
		(stroke
			(width 0.2)
			(type default)
		)
		(layer "In1.Cu")
	)
	(gr_line
		(start 326.193912 -132.14985)
		(end 328.556112 -132.14985)
		(stroke
			(width 0.2)
			(type default)
		)
		(layer "In1.Cu")
	)
	(gr_line
		(start 326.193912 -131.54025)
		(end 326.193912 -128.33985)
		(stroke
			(width 0.2)
			(type default)
		)
		(layer "In1.Cu")
	)
	(gr_line
		(start 326.193912 -128.33985)
		(end 328.556112 -128.33985)
		(stroke
			(width 0.2)
			(type default)
		)
		(layer "In1.Cu")
	)
	(gr_line
		(start 326.193912 -20.350226)
		(end 326.193912 -17.149826)
		(stroke
			(width 0.2)
			(type default)
		)
		(layer "In1.Cu")
	)
	(gr_line
		(start 326.193912 -17.149826)
		(end 328.556112 -17.149826)
		(stroke
			(width 0.2)
			(type default)
		)
		(layer "In1.Cu")
	)
	(gr_line
		(start 326.193912 -16.540226)
		(end 326.193912 -13.339826)
		(stroke
			(width 0.2)
			(type default)
		)
		(layer "In1.Cu")
	)
	(gr_line
		(start 326.193912 -13.339826)
		(end 328.556112 -13.339826)
		(stroke
			(width 0.2)
			(type default)
		)
		(layer "In1.Cu")
	)
	(gr_line
		(start 328.556112 -250.350274)
		(end 326.193912 -250.350274)
		(stroke
			(width 0.2)
			(type default)
		)
		(layer "In1.Cu")
	)
	(gr_line
		(start 328.556112 -247.149874)
		(end 328.556112 -250.350274)
		(stroke
			(width 0.2)
			(type default)
		)
		(layer "In1.Cu")
	)
	(gr_line
		(start 328.556112 -246.540274)
		(end 326.193912 -246.540274)
		(stroke
			(width 0.2)
			(type default)
		)
		(layer "In1.Cu")
	)
	(gr_line
		(start 328.556112 -243.339874)
		(end 328.556112 -246.540274)
		(stroke
			(width 0.2)
			(type default)
		)
		(layer "In1.Cu")
	)
	(gr_line
		(start 328.556112 -135.35025)
		(end 326.193912 -135.35025)
		(stroke
			(width 0.2)
			(type default)
		)
		(layer "In1.Cu")
	)
	(gr_line
		(start 328.556112 -132.14985)
		(end 328.556112 -135.35025)
		(stroke
			(width 0.2)
			(type default)
		)
		(layer "In1.Cu")
	)
	(gr_line
		(start 328.556112 -131.54025)
		(end 326.193912 -131.54025)
		(stroke
			(width 0.2)
			(type default)
		)
		(layer "In1.Cu")
	)
	(gr_line
		(start 328.556112 -128.33985)
		(end 328.556112 -131.54025)
		(stroke
			(width 0.2)
			(type default)
		)
		(layer "In1.Cu")
	)
	(gr_line
		(start 328.556112 -20.350226)
		(end 326.193912 -20.350226)
		(stroke
			(width 0.2)
			(type default)
		)
		(layer "In1.Cu")
	)
	(gr_line
		(start 328.556112 -17.149826)
		(end 328.556112 -20.350226)
		(stroke
			(width 0.2)
			(type default)
		)
		(layer "In1.Cu")
	)
	(gr_line
		(start 328.556112 -16.540226)
		(end 326.193912 -16.540226)
		(stroke
			(width 0.2)
			(type default)
		)
		(layer "In1.Cu")
	)
	(gr_line
		(start 328.556112 -13.339826)
		(end 328.556112 -16.540226)
		(stroke
			(width 0.2)
			(type default)
		)
		(layer "In1.Cu")
	)
	(gr_arc
		(start 350.457262 -245.46052)
		(mid 350.942275 -245.945914)
		(end 351.427542 -245.460774)
		(stroke
			(width 0.2)
			(type default)
		)
		(layer "In1.Cu")
	)
	(gr_line
		(start 350.457262 -244.317774)
		(end 350.457262 -245.46052)
		(stroke
			(width 0.2)
			(type default)
		)
		(layer "In1.Cu")
	)
	(gr_line
		(start 350.764602 -129.112264)
		(end 351.907602 -129.112264)
		(stroke
			(width 0.2)
			(type default)
		)
		(layer "In1.Cu")
	)
	(gr_line
		(start 350.764602 -14.11224)
		(end 351.907602 -14.11224)
		(stroke
			(width 0.2)
			(type default)
		)
		(layer "In1.Cu")
	)
	(gr_arc
		(start 350.764856 -128.141984)
		(mid 350.279462 -128.626997)
		(end 350.764602 -129.112264)
		(stroke
			(width 0.2)
			(type default)
		)
		(layer "In1.Cu")
	)
	(gr_arc
		(start 350.764856 -13.14196)
		(mid 350.279462 -13.626973)
		(end 350.764602 -14.11224)
		(stroke
			(width 0.2)
			(type default)
		)
		(layer "In1.Cu")
	)
	(gr_line
		(start 351.427542 -245.460774)
		(end 351.427542 -244.317774)
		(stroke
			(width 0.2)
			(type default)
		)
		(layer "In1.Cu")
	)
	(gr_arc
		(start 351.427542 -244.317774)
		(mid 350.942402 -243.832634)
		(end 350.457262 -244.317774)
		(stroke
			(width 0.2)
			(type default)
		)
		(layer "In1.Cu")
	)
	(gr_arc
		(start 351.907602 -129.112264)
		(mid 352.392742 -128.627124)
		(end 351.907602 -128.141984)
		(stroke
			(width 0.2)
			(type default)
		)
		(layer "In1.Cu")
	)
	(gr_line
		(start 351.907602 -128.141984)
		(end 350.764856 -128.141984)
		(stroke
			(width 0.2)
			(type default)
		)
		(layer "In1.Cu")
	)
	(gr_arc
		(start 351.907602 -14.11224)
		(mid 352.392742 -13.6271)
		(end 351.907602 -13.14196)
		(stroke
			(width 0.2)
			(type default)
		)
		(layer "In1.Cu")
	)
	(gr_line
		(start 351.907602 -13.14196)
		(end 350.764856 -13.14196)
		(stroke
			(width 0.2)
			(type default)
		)
		(layer "In1.Cu")
	)
	(gr_arc
		(start 352.727514 -245.321074)
		(mid 352.742393 -245.356995)
		(end 352.778314 -245.371874)
		(stroke
			(width 0.2)
			(type default)
		)
		(layer "In1.Cu")
	)
	(gr_line
		(start 352.727514 -245.117874)
		(end 352.727514 -245.321074)
		(stroke
			(width 0.2)
			(type default)
		)
		(layer "In1.Cu")
	)
	(gr_arc
		(start 352.727514 -244.762274)
		(mid 352.742393 -244.798195)
		(end 352.778314 -244.813074)
		(stroke
			(width 0.2)
			(type default)
		)
		(layer "In1.Cu")
	)
	(gr_line
		(start 352.727514 -244.559074)
		(end 352.727514 -244.762274)
		(stroke
			(width 0.2)
			(type default)
		)
		(layer "In1.Cu")
	)
	(gr_arc
		(start 352.727514 -130.32105)
		(mid 352.742393 -130.356971)
		(end 352.778314 -130.37185)
		(stroke
			(width 0.2)
			(type default)
		)
		(layer "In1.Cu")
	)
	(gr_line
		(start 352.727514 -130.11785)
		(end 352.727514 -130.32105)
		(stroke
			(width 0.2)
			(type default)
		)
		(layer "In1.Cu")
	)
	(gr_arc
		(start 352.727514 -129.76225)
		(mid 352.742393 -129.798171)
		(end 352.778314 -129.81305)
		(stroke
			(width 0.2)
			(type default)
		)
		(layer "In1.Cu")
	)
	(gr_line
		(start 352.727514 -129.55905)
		(end 352.727514 -129.76225)
		(stroke
			(width 0.2)
			(type default)
		)
		(layer "In1.Cu")
	)
	(gr_arc
		(start 352.727514 -15.321026)
		(mid 352.742393 -15.356947)
		(end 352.778314 -15.371826)
		(stroke
			(width 0.2)
			(type default)
		)
		(layer "In1.Cu")
	)
	(gr_line
		(start 352.727514 -15.117826)
		(end 352.727514 -15.321026)
		(stroke
			(width 0.2)
			(type default)
		)
		(layer "In1.Cu")
	)
	(gr_arc
		(start 352.727514 -14.762226)
		(mid 352.742393 -14.798147)
		(end 352.778314 -14.813026)
		(stroke
			(width 0.2)
			(type default)
		)
		(layer "In1.Cu")
	)
	(gr_line
		(start 352.727514 -14.559026)
		(end 352.727514 -14.762226)
		(stroke
			(width 0.2)
			(type default)
		)
		(layer "In1.Cu")
	)
	(gr_line
		(start 352.778314 -245.371874)
		(end 353.591114 -245.371874)
		(stroke
			(width 0.2)
			(type default)
		)
		(layer "In1.Cu")
	)
	(gr_arc
		(start 352.778314 -245.067074)
		(mid 352.742393 -245.081953)
		(end 352.727514 -245.117874)
		(stroke
			(width 0.2)
			(type default)
		)
		(layer "In1.Cu")
	)
	(gr_line
		(start 352.778314 -244.813074)
		(end 353.591114 -244.813074)
		(stroke
			(width 0.2)
			(type default)
		)
		(layer "In1.Cu")
	)
	(gr_arc
		(start 352.778314 -244.508274)
		(mid 352.742393 -244.523153)
		(end 352.727514 -244.559074)
		(stroke
			(width 0.2)
			(type default)
		)
		(layer "In1.Cu")
	)
	(gr_line
		(start 352.778314 -130.37185)
		(end 353.591114 -130.37185)
		(stroke
			(width 0.2)
			(type default)
		)
		(layer "In1.Cu")
	)
	(gr_arc
		(start 352.778314 -130.06705)
		(mid 352.742393 -130.081929)
		(end 352.727514 -130.11785)
		(stroke
			(width 0.2)
			(type default)
		)
		(layer "In1.Cu")
	)
	(gr_line
		(start 352.778314 -129.81305)
		(end 353.591114 -129.81305)
		(stroke
			(width 0.2)
			(type default)
		)
		(layer "In1.Cu")
	)
	(gr_arc
		(start 352.778314 -129.50825)
		(mid 352.742393 -129.523129)
		(end 352.727514 -129.55905)
		(stroke
			(width 0.2)
			(type default)
		)
		(layer "In1.Cu")
	)
	(gr_line
		(start 352.778314 -15.371826)
		(end 353.591114 -15.371826)
		(stroke
			(width 0.2)
			(type default)
		)
		(layer "In1.Cu")
	)
	(gr_arc
		(start 352.778314 -15.067026)
		(mid 352.742393 -15.081905)
		(end 352.727514 -15.117826)
		(stroke
			(width 0.2)
			(type default)
		)
		(layer "In1.Cu")
	)
	(gr_line
		(start 352.778314 -14.813026)
		(end 353.591114 -14.813026)
		(stroke
			(width 0.2)
			(type default)
		)
		(layer "In1.Cu")
	)
	(gr_arc
		(start 352.778314 -14.508226)
		(mid 352.742393 -14.523105)
		(end 352.727514 -14.559026)
		(stroke
			(width 0.2)
			(type default)
		)
		(layer "In1.Cu")
	)
	(gr_arc
		(start 353.591114 -245.371874)
		(mid 353.627035 -245.356995)
		(end 353.641914 -245.321074)
		(stroke
			(width 0.2)
			(type default)
		)
		(layer "In1.Cu")
	)
	(gr_line
		(start 353.591114 -245.067074)
		(end 352.778314 -245.067074)
		(stroke
			(width 0.2)
			(type default)
		)
		(layer "In1.Cu")
	)
	(gr_arc
		(start 353.591114 -244.813074)
		(mid 353.627035 -244.798195)
		(end 353.641914 -244.762274)
		(stroke
			(width 0.2)
			(type default)
		)
		(layer "In1.Cu")
	)
	(gr_line
		(start 353.591114 -244.508274)
		(end 352.778314 -244.508274)
		(stroke
			(width 0.2)
			(type default)
		)
		(layer "In1.Cu")
	)
	(gr_arc
		(start 353.591114 -130.37185)
		(mid 353.627035 -130.356971)
		(end 353.641914 -130.32105)
		(stroke
			(width 0.2)
			(type default)
		)
		(layer "In1.Cu")
	)
	(gr_line
		(start 353.591114 -130.06705)
		(end 352.778314 -130.06705)
		(stroke
			(width 0.2)
			(type default)
		)
		(layer "In1.Cu")
	)
	(gr_arc
		(start 353.591114 -129.81305)
		(mid 353.627035 -129.798171)
		(end 353.641914 -129.76225)
		(stroke
			(width 0.2)
			(type default)
		)
		(layer "In1.Cu")
	)
	(gr_line
		(start 353.591114 -129.50825)
		(end 352.778314 -129.50825)
		(stroke
			(width 0.2)
			(type default)
		)
		(layer "In1.Cu")
	)
	(gr_arc
		(start 353.591114 -15.371826)
		(mid 353.627035 -15.356947)
		(end 353.641914 -15.321026)
		(stroke
			(width 0.2)
			(type default)
		)
		(layer "In1.Cu")
	)
	(gr_line
		(start 353.591114 -15.067026)
		(end 352.778314 -15.067026)
		(stroke
			(width 0.2)
			(type default)
		)
		(layer "In1.Cu")
	)
	(gr_arc
		(start 353.591114 -14.813026)
		(mid 353.627035 -14.798147)
		(end 353.641914 -14.762226)
		(stroke
			(width 0.2)
			(type default)
		)
		(layer "In1.Cu")
	)
	(gr_line
		(start 353.591114 -14.508226)
		(end 352.778314 -14.508226)
		(stroke
			(width 0.2)
			(type default)
		)
		(layer "In1.Cu")
	)
	(gr_line
		(start 353.641914 -245.321074)
		(end 353.641914 -245.117874)
		(stroke
			(width 0.2)
			(type default)
		)
		(layer "In1.Cu")
	)
	(gr_arc
		(start 353.641914 -245.117874)
		(mid 353.627035 -245.081953)
		(end 353.591114 -245.067074)
		(stroke
			(width 0.2)
			(type default)
		)
		(layer "In1.Cu")
	)
	(gr_line
		(start 353.641914 -244.762274)
		(end 353.641914 -244.559074)
		(stroke
			(width 0.2)
			(type default)
		)
		(layer "In1.Cu")
	)
	(gr_arc
		(start 353.641914 -244.559074)
		(mid 353.627035 -244.523153)
		(end 353.591114 -244.508274)
		(stroke
			(width 0.2)
			(type default)
		)
		(layer "In1.Cu")
	)
	(gr_line
		(start 353.641914 -130.32105)
		(end 353.641914 -130.11785)
		(stroke
			(width 0.2)
			(type default)
		)
		(layer "In1.Cu")
	)
	(gr_arc
		(start 353.641914 -130.11785)
		(mid 353.627035 -130.081929)
		(end 353.591114 -130.06705)
		(stroke
			(width 0.2)
			(type default)
		)
		(layer "In1.Cu")
	)
	(gr_line
		(start 353.641914 -129.76225)
		(end 353.641914 -129.55905)
		(stroke
			(width 0.2)
			(type default)
		)
		(layer "In1.Cu")
	)
	(gr_arc
		(start 353.641914 -129.55905)
		(mid 353.627035 -129.523129)
		(end 353.591114 -129.50825)
		(stroke
			(width 0.2)
			(type default)
		)
		(layer "In1.Cu")
	)
	(gr_line
		(start 353.641914 -15.321026)
		(end 353.641914 -15.117826)
		(stroke
			(width 0.2)
			(type default)
		)
		(layer "In1.Cu")
	)
	(gr_arc
		(start 353.641914 -15.117826)
		(mid 353.627035 -15.081905)
		(end 353.591114 -15.067026)
		(stroke
			(width 0.2)
			(type default)
		)
		(layer "In1.Cu")
	)
	(gr_line
		(start 353.641914 -14.762226)
		(end 353.641914 -14.559026)
		(stroke
			(width 0.2)
			(type default)
		)
		(layer "In1.Cu")
	)
	(gr_arc
		(start 353.641914 -14.559026)
		(mid 353.627035 -14.523105)
		(end 353.591114 -14.508226)
		(stroke
			(width 0.2)
			(type default)
		)
		(layer "In1.Cu")
	)
	(gr_line
		(start 354.231702 -132.922264)
		(end 355.501702 -132.922264)
		(stroke
			(width 0.2)
			(type default)
		)
		(layer "In1.Cu")
	)
	(gr_line
		(start 354.231702 -17.92224)
		(end 355.501702 -17.92224)
		(stroke
			(width 0.2)
			(type default)
		)
		(layer "In1.Cu")
	)
	(gr_arc
		(start 354.231956 -131.951984)
		(mid 353.746562 -132.436997)
		(end 354.231702 -132.922264)
		(stroke
			(width 0.2)
			(type default)
		)
		(layer "In1.Cu")
	)
	(gr_arc
		(start 354.231956 -16.95196)
		(mid 353.746562 -17.436973)
		(end 354.231702 -17.92224)
		(stroke
			(width 0.2)
			(type default)
		)
		(layer "In1.Cu")
	)
	(gr_arc
		(start 354.654612 -249.385074)
		(mid 355.139752 -249.870214)
		(end 355.624892 -249.385074)
		(stroke
			(width 0.2)
			(type default)
		)
		(layer "In1.Cu")
	)
	(gr_line
		(start 354.654612 -248.115074)
		(end 354.654612 -249.385074)
		(stroke
			(width 0.2)
			(type default)
		)
		(layer "In1.Cu")
	)
	(gr_arc
		(start 355.501702 -132.922264)
		(mid 355.986842 -132.437124)
		(end 355.501702 -131.951984)
		(stroke
			(width 0.2)
			(type default)
		)
		(layer "In1.Cu")
	)
	(gr_line
		(start 355.501702 -131.951984)
		(end 354.231956 -131.951984)
		(stroke
			(width 0.2)
			(type default)
		)
		(layer "In1.Cu")
	)
	(gr_arc
		(start 355.501702 -17.92224)
		(mid 355.986842 -17.4371)
		(end 355.501702 -16.95196)
		(stroke
			(width 0.2)
			(type default)
		)
		(layer "In1.Cu")
	)
	(gr_line
		(start 355.501702 -16.95196)
		(end 354.231956 -16.95196)
		(stroke
			(width 0.2)
			(type default)
		)
		(layer "In1.Cu")
	)
	(gr_line
		(start 355.624892 -249.385074)
		(end 355.624892 -248.115328)
		(stroke
			(width 0.2)
			(type default)
		)
		(layer "In1.Cu")
	)
	(gr_arc
		(start 355.624892 -248.115328)
		(mid 355.139879 -247.629934)
		(end 354.654612 -248.115074)
		(stroke
			(width 0.2)
			(type default)
		)
		(layer "In1.Cu")
	)
	(gr_line
		(start 357.744014 -250.350274)
		(end 357.744014 -247.149874)
		(stroke
			(width 0.2)
			(type default)
		)
		(layer "In1.Cu")
	)
	(gr_line
		(start 357.744014 -247.149874)
		(end 360.106214 -247.149874)
		(stroke
			(width 0.2)
			(type default)
		)
		(layer "In1.Cu")
	)
	(gr_line
		(start 357.744014 -246.540274)
		(end 357.744014 -243.339874)
		(stroke
			(width 0.2)
			(type default)
		)
		(layer "In1.Cu")
	)
	(gr_line
		(start 357.744014 -243.339874)
		(end 360.106214 -243.339874)
		(stroke
			(width 0.2)
			(type default)
		)
		(layer "In1.Cu")
	)
	(gr_line
		(start 357.744014 -135.35025)
		(end 357.744014 -132.14985)
		(stroke
			(width 0.2)
			(type default)
		)
		(layer "In1.Cu")
	)
	(gr_line
		(start 357.744014 -132.14985)
		(end 360.106214 -132.14985)
		(stroke
			(width 0.2)
			(type default)
		)
		(layer "In1.Cu")
	)
	(gr_line
		(start 357.744014 -131.54025)
		(end 357.744014 -128.33985)
		(stroke
			(width 0.2)
			(type default)
		)
		(layer "In1.Cu")
	)
	(gr_line
		(start 357.744014 -128.33985)
		(end 360.106214 -128.33985)
		(stroke
			(width 0.2)
			(type default)
		)
		(layer "In1.Cu")
	)
	(gr_line
		(start 357.744014 -20.350226)
		(end 357.744014 -17.149826)
		(stroke
			(width 0.2)
			(type default)
		)
		(layer "In1.Cu")
	)
	(gr_line
		(start 357.744014 -17.149826)
		(end 360.106214 -17.149826)
		(stroke
			(width 0.2)
			(type default)
		)
		(layer "In1.Cu")
	)
	(gr_line
		(start 357.744014 -16.540226)
		(end 357.744014 -13.339826)
		(stroke
			(width 0.2)
			(type default)
		)
		(layer "In1.Cu")
	)
	(gr_line
		(start 357.744014 -13.339826)
		(end 360.106214 -13.339826)
		(stroke
			(width 0.2)
			(type default)
		)
		(layer "In1.Cu")
	)
	(gr_line
		(start 360.106214 -250.350274)
		(end 357.744014 -250.350274)
		(stroke
			(width 0.2)
			(type default)
		)
		(layer "In1.Cu")
	)
	(gr_line
		(start 360.106214 -247.149874)
		(end 360.106214 -250.350274)
		(stroke
			(width 0.2)
			(type default)
		)
		(layer "In1.Cu")
	)
	(gr_line
		(start 360.106214 -246.540274)
		(end 357.744014 -246.540274)
		(stroke
			(width 0.2)
			(type default)
		)
		(layer "In1.Cu")
	)
	(gr_line
		(start 360.106214 -243.339874)
		(end 360.106214 -246.540274)
		(stroke
			(width 0.2)
			(type default)
		)
		(layer "In1.Cu")
	)
	(gr_line
		(start 360.106214 -135.35025)
		(end 357.744014 -135.35025)
		(stroke
			(width 0.2)
			(type default)
		)
		(layer "In1.Cu")
	)
	(gr_line
		(start 360.106214 -132.14985)
		(end 360.106214 -135.35025)
		(stroke
			(width 0.2)
			(type default)
		)
		(layer "In1.Cu")
	)
	(gr_line
		(start 360.106214 -131.54025)
		(end 357.744014 -131.54025)
		(stroke
			(width 0.2)
			(type default)
		)
		(layer "In1.Cu")
	)
	(gr_line
		(start 360.106214 -128.33985)
		(end 360.106214 -131.54025)
		(stroke
			(width 0.2)
			(type default)
		)
		(layer "In1.Cu")
	)
	(gr_line
		(start 360.106214 -20.350226)
		(end 357.744014 -20.350226)
		(stroke
			(width 0.2)
			(type default)
		)
		(layer "In1.Cu")
	)
	(gr_line
		(start 360.106214 -17.149826)
		(end 360.106214 -20.350226)
		(stroke
			(width 0.2)
			(type default)
		)
		(layer "In1.Cu")
	)
	(gr_line
		(start 360.106214 -16.540226)
		(end 357.744014 -16.540226)
		(stroke
			(width 0.2)
			(type default)
		)
		(layer "In1.Cu")
	)
	(gr_line
		(start 360.106214 -13.339826)
		(end 360.106214 -16.540226)
		(stroke
			(width 0.2)
			(type default)
		)
		(layer "In1.Cu")
	)
	(gr_line
		(start 362.700062 -385.99999)
		(end 317.149988 -385.99999)
		(stroke
			(width 1.524)
			(type default)
		)
		(layer "In1.Cu")
	)
	(gr_arc
		(start 362.700062 -385.99999)
		(mid 363.407189 -385.70711)
		(end 363.70006 -384.999992)
		(stroke
			(width 1.524)
			(type default)
		)
		(layer "In1.Cu")
	)
	(gr_line
		(start 363.70006 -381)
		(end 363.70006 -384.999992)
		(stroke
			(width 1.524)
			(type default)
		)
		(layer "In1.Cu")
	)
	(gr_arc
		(start 364.700058 -380.000002)
		(mid 363.992953 -380.292895)
		(end 363.70006 -381)
		(stroke
			(width 1.524)
			(type default)
		)
		(layer "In1.Cu")
	)
	(gr_arc
		(start 382.00711 -245.44528)
		(mid 382.492123 -245.930674)
		(end 382.97739 -245.445534)
		(stroke
			(width 0.2)
			(type default)
		)
		(layer "In1.Cu")
	)
	(gr_line
		(start 382.00711 -244.302534)
		(end 382.00711 -245.44528)
		(stroke
			(width 0.2)
			(type default)
		)
		(layer "In1.Cu")
	)
	(gr_line
		(start 382.31445 -129.112264)
		(end 383.45745 -129.112264)
		(stroke
			(width 0.2)
			(type default)
		)
		(layer "In1.Cu")
	)
	(gr_line
		(start 382.31445 -14.11224)
		(end 383.45745 -14.11224)
		(stroke
			(width 0.2)
			(type default)
		)
		(layer "In1.Cu")
	)
	(gr_arc
		(start 382.314704 -128.141984)
		(mid 381.82931 -128.626997)
		(end 382.31445 -129.112264)
		(stroke
			(width 0.2)
			(type default)
		)
		(layer "In1.Cu")
	)
	(gr_arc
		(start 382.314704 -13.14196)
		(mid 381.82931 -13.626973)
		(end 382.31445 -14.11224)
		(stroke
			(width 0.2)
			(type default)
		)
		(layer "In1.Cu")
	)
	(gr_line
		(start 382.97739 -245.445534)
		(end 382.97739 -244.302534)
		(stroke
			(width 0.2)
			(type default)
		)
		(layer "In1.Cu")
	)
	(gr_arc
		(start 382.97739 -244.302534)
		(mid 382.49225 -243.817394)
		(end 382.00711 -244.302534)
		(stroke
			(width 0.2)
			(type default)
		)
		(layer "In1.Cu")
	)
	(gr_arc
		(start 383.45745 -129.112264)
		(mid 383.94259 -128.627124)
		(end 383.45745 -128.141984)
		(stroke
			(width 0.2)
			(type default)
		)
		(layer "In1.Cu")
	)
	(gr_line
		(start 383.45745 -128.141984)
		(end 382.314704 -128.141984)
		(stroke
			(width 0.2)
			(type default)
		)
		(layer "In1.Cu")
	)
	(gr_arc
		(start 383.45745 -14.11224)
		(mid 383.94259 -13.6271)
		(end 383.45745 -13.14196)
		(stroke
			(width 0.2)
			(type default)
		)
		(layer "In1.Cu")
	)
	(gr_line
		(start 383.45745 -13.14196)
		(end 382.314704 -13.14196)
		(stroke
			(width 0.2)
			(type default)
		)
		(layer "In1.Cu")
	)
	(gr_arc
		(start 384.277362 -245.321074)
		(mid 384.292241 -245.356995)
		(end 384.328162 -245.371874)
		(stroke
			(width 0.2)
			(type default)
		)
		(layer "In1.Cu")
	)
	(gr_line
		(start 384.277362 -245.117874)
		(end 384.277362 -245.321074)
		(stroke
			(width 0.2)
			(type default)
		)
		(layer "In1.Cu")
	)
	(gr_arc
		(start 384.277362 -244.762274)
		(mid 384.292241 -244.798195)
		(end 384.328162 -244.813074)
		(stroke
			(width 0.2)
			(type default)
		)
		(layer "In1.Cu")
	)
	(gr_line
		(start 384.277362 -244.559074)
		(end 384.277362 -244.762274)
		(stroke
			(width 0.2)
			(type default)
		)
		(layer "In1.Cu")
	)
	(gr_arc
		(start 384.277362 -130.32105)
		(mid 384.292241 -130.356971)
		(end 384.328162 -130.37185)
		(stroke
			(width 0.2)
			(type default)
		)
		(layer "In1.Cu")
	)
	(gr_line
		(start 384.277362 -130.11785)
		(end 384.277362 -130.32105)
		(stroke
			(width 0.2)
			(type default)
		)
		(layer "In1.Cu")
	)
	(gr_arc
		(start 384.277362 -129.76225)
		(mid 384.292241 -129.798171)
		(end 384.328162 -129.81305)
		(stroke
			(width 0.2)
			(type default)
		)
		(layer "In1.Cu")
	)
	(gr_line
		(start 384.277362 -129.55905)
		(end 384.277362 -129.76225)
		(stroke
			(width 0.2)
			(type default)
		)
		(layer "In1.Cu")
	)
	(gr_arc
		(start 384.277362 -15.321026)
		(mid 384.292241 -15.356947)
		(end 384.328162 -15.371826)
		(stroke
			(width 0.2)
			(type default)
		)
		(layer "In1.Cu")
	)
	(gr_line
		(start 384.277362 -15.117826)
		(end 384.277362 -15.321026)
		(stroke
			(width 0.2)
			(type default)
		)
		(layer "In1.Cu")
	)
	(gr_arc
		(start 384.277362 -14.762226)
		(mid 384.292241 -14.798147)
		(end 384.328162 -14.813026)
		(stroke
			(width 0.2)
			(type default)
		)
		(layer "In1.Cu")
	)
	(gr_line
		(start 384.277362 -14.559026)
		(end 384.277362 -14.762226)
		(stroke
			(width 0.2)
			(type default)
		)
		(layer "In1.Cu")
	)
	(gr_line
		(start 384.328162 -245.371874)
		(end 385.140962 -245.371874)
		(stroke
			(width 0.2)
			(type default)
		)
		(layer "In1.Cu")
	)
	(gr_arc
		(start 384.328162 -245.067074)
		(mid 384.292241 -245.081953)
		(end 384.277362 -245.117874)
		(stroke
			(width 0.2)
			(type default)
		)
		(layer "In1.Cu")
	)
	(gr_line
		(start 384.328162 -244.813074)
		(end 385.140962 -244.813074)
		(stroke
			(width 0.2)
			(type default)
		)
		(layer "In1.Cu")
	)
	(gr_arc
		(start 384.328162 -244.508274)
		(mid 384.292241 -244.523153)
		(end 384.277362 -244.559074)
		(stroke
			(width 0.2)
			(type default)
		)
		(layer "In1.Cu")
	)
	(gr_line
		(start 384.328162 -130.37185)
		(end 385.140962 -130.37185)
		(stroke
			(width 0.2)
			(type default)
		)
		(layer "In1.Cu")
	)
	(gr_arc
		(start 384.328162 -130.06705)
		(mid 384.292241 -130.081929)
		(end 384.277362 -130.11785)
		(stroke
			(width 0.2)
			(type default)
		)
		(layer "In1.Cu")
	)
	(gr_line
		(start 384.328162 -129.81305)
		(end 385.140962 -129.81305)
		(stroke
			(width 0.2)
			(type default)
		)
		(layer "In1.Cu")
	)
	(gr_arc
		(start 384.328162 -129.50825)
		(mid 384.292241 -129.523129)
		(end 384.277362 -129.55905)
		(stroke
			(width 0.2)
			(type default)
		)
		(layer "In1.Cu")
	)
	(gr_line
		(start 384.328162 -15.371826)
		(end 385.140962 -15.371826)
		(stroke
			(width 0.2)
			(type default)
		)
		(layer "In1.Cu")
	)
	(gr_arc
		(start 384.328162 -15.067026)
		(mid 384.292241 -15.081905)
		(end 384.277362 -15.117826)
		(stroke
			(width 0.2)
			(type default)
		)
		(layer "In1.Cu")
	)
	(gr_line
		(start 384.328162 -14.813026)
		(end 385.140962 -14.813026)
		(stroke
			(width 0.2)
			(type default)
		)
		(layer "In1.Cu")
	)
	(gr_arc
		(start 384.328162 -14.508226)
		(mid 384.292241 -14.523105)
		(end 384.277362 -14.559026)
		(stroke
			(width 0.2)
			(type default)
		)
		(layer "In1.Cu")
	)
	(gr_arc
		(start 385.140962 -245.371874)
		(mid 385.176883 -245.356995)
		(end 385.191762 -245.321074)
		(stroke
			(width 0.2)
			(type default)
		)
		(layer "In1.Cu")
	)
	(gr_line
		(start 385.140962 -245.067074)
		(end 384.328162 -245.067074)
		(stroke
			(width 0.2)
			(type default)
		)
		(layer "In1.Cu")
	)
	(gr_arc
		(start 385.140962 -244.813074)
		(mid 385.176883 -244.798195)
		(end 385.191762 -244.762274)
		(stroke
			(width 0.2)
			(type default)
		)
		(layer "In1.Cu")
	)
	(gr_line
		(start 385.140962 -244.508274)
		(end 384.328162 -244.508274)
		(stroke
			(width 0.2)
			(type default)
		)
		(layer "In1.Cu")
	)
	(gr_arc
		(start 385.140962 -130.37185)
		(mid 385.176883 -130.356971)
		(end 385.191762 -130.32105)
		(stroke
			(width 0.2)
			(type default)
		)
		(layer "In1.Cu")
	)
	(gr_line
		(start 385.140962 -130.06705)
		(end 384.328162 -130.06705)
		(stroke
			(width 0.2)
			(type default)
		)
		(layer "In1.Cu")
	)
	(gr_arc
		(start 385.140962 -129.81305)
		(mid 385.176883 -129.798171)
		(end 385.191762 -129.76225)
		(stroke
			(width 0.2)
			(type default)
		)
		(layer "In1.Cu")
	)
	(gr_line
		(start 385.140962 -129.50825)
		(end 384.328162 -129.50825)
		(stroke
			(width 0.2)
			(type default)
		)
		(layer "In1.Cu")
	)
	(gr_arc
		(start 385.140962 -15.371826)
		(mid 385.176883 -15.356947)
		(end 385.191762 -15.321026)
		(stroke
			(width 0.2)
			(type default)
		)
		(layer "In1.Cu")
	)
	(gr_line
		(start 385.140962 -15.067026)
		(end 384.328162 -15.067026)
		(stroke
			(width 0.2)
			(type default)
		)
		(layer "In1.Cu")
	)
	(gr_arc
		(start 385.140962 -14.813026)
		(mid 385.176883 -14.798147)
		(end 385.191762 -14.762226)
		(stroke
			(width 0.2)
			(type default)
		)
		(layer "In1.Cu")
	)
	(gr_line
		(start 385.140962 -14.508226)
		(end 384.328162 -14.508226)
		(stroke
			(width 0.2)
			(type default)
		)
		(layer "In1.Cu")
	)
	(gr_line
		(start 385.191762 -245.321074)
		(end 385.191762 -245.117874)
		(stroke
			(width 0.2)
			(type default)
		)
		(layer "In1.Cu")
	)
	(gr_arc
		(start 385.191762 -245.117874)
		(mid 385.176883 -245.081953)
		(end 385.140962 -245.067074)
		(stroke
			(width 0.2)
			(type default)
		)
		(layer "In1.Cu")
	)
	(gr_line
		(start 385.191762 -244.762274)
		(end 385.191762 -244.559074)
		(stroke
			(width 0.2)
			(type default)
		)
		(layer "In1.Cu")
	)
	(gr_arc
		(start 385.191762 -244.559074)
		(mid 385.176883 -244.523153)
		(end 385.140962 -244.508274)
		(stroke
			(width 0.2)
			(type default)
		)
		(layer "In1.Cu")
	)
	(gr_line
		(start 385.191762 -130.32105)
		(end 385.191762 -130.11785)
		(stroke
			(width 0.2)
			(type default)
		)
		(layer "In1.Cu")
	)
	(gr_arc
		(start 385.191762 -130.11785)
		(mid 385.176883 -130.081929)
		(end 385.140962 -130.06705)
		(stroke
			(width 0.2)
			(type default)
		)
		(layer "In1.Cu")
	)
	(gr_line
		(start 385.191762 -129.76225)
		(end 385.191762 -129.55905)
		(stroke
			(width 0.2)
			(type default)
		)
		(layer "In1.Cu")
	)
	(gr_arc
		(start 385.191762 -129.55905)
		(mid 385.176883 -129.523129)
		(end 385.140962 -129.50825)
		(stroke
			(width 0.2)
			(type default)
		)
		(layer "In1.Cu")
	)
	(gr_line
		(start 385.191762 -15.321026)
		(end 385.191762 -15.117826)
		(stroke
			(width 0.2)
			(type default)
		)
		(layer "In1.Cu")
	)
	(gr_arc
		(start 385.191762 -15.117826)
		(mid 385.176883 -15.081905)
		(end 385.140962 -15.067026)
		(stroke
			(width 0.2)
			(type default)
		)
		(layer "In1.Cu")
	)
	(gr_line
		(start 385.191762 -14.762226)
		(end 385.191762 -14.559026)
		(stroke
			(width 0.2)
			(type default)
		)
		(layer "In1.Cu")
	)
	(gr_arc
		(start 385.191762 -14.559026)
		(mid 385.176883 -14.523105)
		(end 385.140962 -14.508226)
		(stroke
			(width 0.2)
			(type default)
		)
		(layer "In1.Cu")
	)
	(gr_line
		(start 385.78155 -132.922264)
		(end 387.051296 -132.922264)
		(stroke
			(width 0.2)
			(type default)
		)
		(layer "In1.Cu")
	)
	(gr_arc
		(start 385.78155 -131.951984)
		(mid 385.29641 -132.437124)
		(end 385.78155 -132.922264)
		(stroke
			(width 0.2)
			(type default)
		)
		(layer "In1.Cu")
	)
	(gr_line
		(start 385.78155 -17.92224)
		(end 387.051296 -17.92224)
		(stroke
			(width 0.2)
			(type default)
		)
		(layer "In1.Cu")
	)
	(gr_arc
		(start 385.78155 -16.95196)
		(mid 385.29641 -17.4371)
		(end 385.78155 -17.92224)
		(stroke
			(width 0.2)
			(type default)
		)
		(layer "In1.Cu")
	)
	(gr_arc
		(start 386.20446 -249.385074)
		(mid 386.6896 -249.870214)
		(end 387.17474 -249.385074)
		(stroke
			(width 0.2)
			(type default)
		)
		(layer "In1.Cu")
	)
	(gr_line
		(start 386.20446 -248.115074)
		(end 386.20446 -249.385074)
		(stroke
			(width 0.2)
			(type default)
		)
		(layer "In1.Cu")
	)
	(gr_arc
		(start 387.051296 -132.922264)
		(mid 387.53669 -132.437251)
		(end 387.05155 -131.951984)
		(stroke
			(width 0.2)
			(type default)
		)
		(layer "In1.Cu")
	)
	(gr_arc
		(start 387.051296 -17.92224)
		(mid 387.53669 -17.437227)
		(end 387.05155 -16.95196)
		(stroke
			(width 0.2)
			(type default)
		)
		(layer "In1.Cu")
	)
	(gr_line
		(start 387.05155 -131.951984)
		(end 385.78155 -131.951984)
		(stroke
			(width 0.2)
			(type default)
		)
		(layer "In1.Cu")
	)
	(gr_line
		(start 387.05155 -16.95196)
		(end 385.78155 -16.95196)
		(stroke
			(width 0.2)
			(type default)
		)
		(layer "In1.Cu")
	)
	(gr_line
		(start 387.17474 -249.385074)
		(end 387.17474 -248.115328)
		(stroke
			(width 0.2)
			(type default)
		)
		(layer "In1.Cu")
	)
	(gr_arc
		(start 387.17474 -248.115328)
		(mid 386.689727 -247.629934)
		(end 386.20446 -248.115074)
		(stroke
			(width 0.2)
			(type default)
		)
		(layer "In1.Cu")
	)
	(gr_line
		(start 389.293862 -250.350274)
		(end 389.293862 -247.149874)
		(stroke
			(width 0.2)
			(type default)
		)
		(layer "In1.Cu")
	)
	(gr_line
		(start 389.293862 -247.149874)
		(end 391.656062 -247.149874)
		(stroke
			(width 0.2)
			(type default)
		)
		(layer "In1.Cu")
	)
	(gr_line
		(start 389.293862 -246.540274)
		(end 389.293862 -243.339874)
		(stroke
			(width 0.2)
			(type default)
		)
		(layer "In1.Cu")
	)
	(gr_line
		(start 389.293862 -243.339874)
		(end 391.656062 -243.339874)
		(stroke
			(width 0.2)
			(type default)
		)
		(layer "In1.Cu")
	)
	(gr_line
		(start 389.293862 -135.35025)
		(end 389.293862 -132.14985)
		(stroke
			(width 0.2)
			(type default)
		)
		(layer "In1.Cu")
	)
	(gr_line
		(start 389.293862 -132.14985)
		(end 391.656062 -132.14985)
		(stroke
			(width 0.2)
			(type default)
		)
		(layer "In1.Cu")
	)
	(gr_line
		(start 389.293862 -131.54025)
		(end 389.293862 -128.33985)
		(stroke
			(width 0.2)
			(type default)
		)
		(layer "In1.Cu")
	)
	(gr_line
		(start 389.293862 -128.33985)
		(end 391.656062 -128.33985)
		(stroke
			(width 0.2)
			(type default)
		)
		(layer "In1.Cu")
	)
	(gr_line
		(start 389.293862 -20.350226)
		(end 389.293862 -17.149826)
		(stroke
			(width 0.2)
			(type default)
		)
		(layer "In1.Cu")
	)
	(gr_line
		(start 389.293862 -17.149826)
		(end 391.656062 -17.149826)
		(stroke
			(width 0.2)
			(type default)
		)
		(layer "In1.Cu")
	)
	(gr_line
		(start 389.293862 -16.540226)
		(end 389.293862 -13.339826)
		(stroke
			(width 0.2)
			(type default)
		)
		(layer "In1.Cu")
	)
	(gr_line
		(start 389.293862 -13.339826)
		(end 391.656062 -13.339826)
		(stroke
			(width 0.2)
			(type default)
		)
		(layer "In1.Cu")
	)
	(gr_line
		(start 391.656062 -250.350274)
		(end 389.293862 -250.350274)
		(stroke
			(width 0.2)
			(type default)
		)
		(layer "In1.Cu")
	)
	(gr_line
		(start 391.656062 -247.149874)
		(end 391.656062 -250.350274)
		(stroke
			(width 0.2)
			(type default)
		)
		(layer "In1.Cu")
	)
	(gr_line
		(start 391.656062 -246.540274)
		(end 389.293862 -246.540274)
		(stroke
			(width 0.2)
			(type default)
		)
		(layer "In1.Cu")
	)
	(gr_line
		(start 391.656062 -243.339874)
		(end 391.656062 -246.540274)
		(stroke
			(width 0.2)
			(type default)
		)
		(layer "In1.Cu")
	)
	(gr_line
		(start 391.656062 -135.35025)
		(end 389.293862 -135.35025)
		(stroke
			(width 0.2)
			(type default)
		)
		(layer "In1.Cu")
	)
	(gr_line
		(start 391.656062 -132.14985)
		(end 391.656062 -135.35025)
		(stroke
			(width 0.2)
			(type default)
		)
		(layer "In1.Cu")
	)
	(gr_line
		(start 391.656062 -131.54025)
		(end 389.293862 -131.54025)
		(stroke
			(width 0.2)
			(type default)
		)
		(layer "In1.Cu")
	)
	(gr_line
		(start 391.656062 -128.33985)
		(end 391.656062 -131.54025)
		(stroke
			(width 0.2)
			(type default)
		)
		(layer "In1.Cu")
	)
	(gr_line
		(start 391.656062 -20.350226)
		(end 389.293862 -20.350226)
		(stroke
			(width 0.2)
			(type default)
		)
		(layer "In1.Cu")
	)
	(gr_line
		(start 391.656062 -17.149826)
		(end 391.656062 -20.350226)
		(stroke
			(width 0.2)
			(type default)
		)
		(layer "In1.Cu")
	)
	(gr_line
		(start 391.656062 -16.540226)
		(end 389.293862 -16.540226)
		(stroke
			(width 0.2)
			(type default)
		)
		(layer "In1.Cu")
	)
	(gr_line
		(start 391.656062 -13.339826)
		(end 391.656062 -16.540226)
		(stroke
			(width 0.2)
			(type default)
		)
		(layer "In1.Cu")
	)
	(gr_arc
		(start 413.557212 -245.58752)
		(mid 414.042225 -246.072914)
		(end 414.527492 -245.587774)
		(stroke
			(width 0.2)
			(type default)
		)
		(layer "In1.Cu")
	)
	(gr_line
		(start 413.557212 -244.444774)
		(end 413.557212 -245.58752)
		(stroke
			(width 0.2)
			(type default)
		)
		(layer "In1.Cu")
	)
	(gr_line
		(start 413.864552 -129.112264)
		(end 415.007552 -129.112264)
		(stroke
			(width 0.2)
			(type default)
		)
		(layer "In1.Cu")
	)
	(gr_line
		(start 413.864552 -14.11224)
		(end 415.007552 -14.11224)
		(stroke
			(width 0.2)
			(type default)
		)
		(layer "In1.Cu")
	)
	(gr_arc
		(start 413.864806 -128.141984)
		(mid 413.379412 -128.626997)
		(end 413.864552 -129.112264)
		(stroke
			(width 0.2)
			(type default)
		)
		(layer "In1.Cu")
	)
	(gr_arc
		(start 413.864806 -13.14196)
		(mid 413.379412 -13.626973)
		(end 413.864552 -14.11224)
		(stroke
			(width 0.2)
			(type default)
		)
		(layer "In1.Cu")
	)
	(gr_line
		(start 414.527492 -245.587774)
		(end 414.527492 -244.444774)
		(stroke
			(width 0.2)
			(type default)
		)
		(layer "In1.Cu")
	)
	(gr_arc
		(start 414.527492 -244.444774)
		(mid 414.042352 -243.959634)
		(end 413.557212 -244.444774)
		(stroke
			(width 0.2)
			(type default)
		)
		(layer "In1.Cu")
	)
	(gr_arc
		(start 415.007552 -129.112264)
		(mid 415.492692 -128.627124)
		(end 415.007552 -128.141984)
		(stroke
			(width 0.2)
			(type default)
		)
		(layer "In1.Cu")
	)
	(gr_line
		(start 415.007552 -128.141984)
		(end 413.864806 -128.141984)
		(stroke
			(width 0.2)
			(type default)
		)
		(layer "In1.Cu")
	)
	(gr_arc
		(start 415.007552 -14.11224)
		(mid 415.492692 -13.6271)
		(end 415.007552 -13.14196)
		(stroke
			(width 0.2)
			(type default)
		)
		(layer "In1.Cu")
	)
	(gr_line
		(start 415.007552 -13.14196)
		(end 413.864806 -13.14196)
		(stroke
			(width 0.2)
			(type default)
		)
		(layer "In1.Cu")
	)
	(gr_arc
		(start 415.827464 -245.321074)
		(mid 415.842343 -245.356995)
		(end 415.878264 -245.371874)
		(stroke
			(width 0.2)
			(type default)
		)
		(layer "In1.Cu")
	)
	(gr_line
		(start 415.827464 -245.117874)
		(end 415.827464 -245.321074)
		(stroke
			(width 0.2)
			(type default)
		)
		(layer "In1.Cu")
	)
	(gr_arc
		(start 415.827464 -244.762274)
		(mid 415.842343 -244.798195)
		(end 415.878264 -244.813074)
		(stroke
			(width 0.2)
			(type default)
		)
		(layer "In1.Cu")
	)
	(gr_line
		(start 415.827464 -244.559074)
		(end 415.827464 -244.762274)
		(stroke
			(width 0.2)
			(type default)
		)
		(layer "In1.Cu")
	)
	(gr_arc
		(start 415.827464 -130.32105)
		(mid 415.842343 -130.356971)
		(end 415.878264 -130.37185)
		(stroke
			(width 0.2)
			(type default)
		)
		(layer "In1.Cu")
	)
	(gr_line
		(start 415.827464 -130.11785)
		(end 415.827464 -130.32105)
		(stroke
			(width 0.2)
			(type default)
		)
		(layer "In1.Cu")
	)
	(gr_arc
		(start 415.827464 -129.76225)
		(mid 415.842343 -129.798171)
		(end 415.878264 -129.81305)
		(stroke
			(width 0.2)
			(type default)
		)
		(layer "In1.Cu")
	)
	(gr_line
		(start 415.827464 -129.55905)
		(end 415.827464 -129.76225)
		(stroke
			(width 0.2)
			(type default)
		)
		(layer "In1.Cu")
	)
	(gr_arc
		(start 415.827464 -15.321026)
		(mid 415.842343 -15.356947)
		(end 415.878264 -15.371826)
		(stroke
			(width 0.2)
			(type default)
		)
		(layer "In1.Cu")
	)
	(gr_line
		(start 415.827464 -15.117826)
		(end 415.827464 -15.321026)
		(stroke
			(width 0.2)
			(type default)
		)
		(layer "In1.Cu")
	)
	(gr_arc
		(start 415.827464 -14.762226)
		(mid 415.842343 -14.798147)
		(end 415.878264 -14.813026)
		(stroke
			(width 0.2)
			(type default)
		)
		(layer "In1.Cu")
	)
	(gr_line
		(start 415.827464 -14.559026)
		(end 415.827464 -14.762226)
		(stroke
			(width 0.2)
			(type default)
		)
		(layer "In1.Cu")
	)
	(gr_line
		(start 415.878264 -245.371874)
		(end 416.691064 -245.371874)
		(stroke
			(width 0.2)
			(type default)
		)
		(layer "In1.Cu")
	)
	(gr_arc
		(start 415.878264 -245.067074)
		(mid 415.842343 -245.081953)
		(end 415.827464 -245.117874)
		(stroke
			(width 0.2)
			(type default)
		)
		(layer "In1.Cu")
	)
	(gr_line
		(start 415.878264 -244.813074)
		(end 416.691064 -244.813074)
		(stroke
			(width 0.2)
			(type default)
		)
		(layer "In1.Cu")
	)
	(gr_arc
		(start 415.878264 -244.508274)
		(mid 415.842343 -244.523153)
		(end 415.827464 -244.559074)
		(stroke
			(width 0.2)
			(type default)
		)
		(layer "In1.Cu")
	)
	(gr_line
		(start 415.878264 -130.37185)
		(end 416.691064 -130.37185)
		(stroke
			(width 0.2)
			(type default)
		)
		(layer "In1.Cu")
	)
	(gr_arc
		(start 415.878264 -130.06705)
		(mid 415.842343 -130.081929)
		(end 415.827464 -130.11785)
		(stroke
			(width 0.2)
			(type default)
		)
		(layer "In1.Cu")
	)
	(gr_line
		(start 415.878264 -129.81305)
		(end 416.691064 -129.81305)
		(stroke
			(width 0.2)
			(type default)
		)
		(layer "In1.Cu")
	)
	(gr_arc
		(start 415.878264 -129.50825)
		(mid 415.842343 -129.523129)
		(end 415.827464 -129.55905)
		(stroke
			(width 0.2)
			(type default)
		)
		(layer "In1.Cu")
	)
	(gr_line
		(start 415.878264 -15.371826)
		(end 416.691064 -15.371826)
		(stroke
			(width 0.2)
			(type default)
		)
		(layer "In1.Cu")
	)
	(gr_arc
		(start 415.878264 -15.067026)
		(mid 415.842343 -15.081905)
		(end 415.827464 -15.117826)
		(stroke
			(width 0.2)
			(type default)
		)
		(layer "In1.Cu")
	)
	(gr_line
		(start 415.878264 -14.813026)
		(end 416.691064 -14.813026)
		(stroke
			(width 0.2)
			(type default)
		)
		(layer "In1.Cu")
	)
	(gr_arc
		(start 415.878264 -14.508226)
		(mid 415.842343 -14.523105)
		(end 415.827464 -14.559026)
		(stroke
			(width 0.2)
			(type default)
		)
		(layer "In1.Cu")
	)
	(gr_arc
		(start 416.691064 -245.371874)
		(mid 416.726985 -245.356995)
		(end 416.741864 -245.321074)
		(stroke
			(width 0.2)
			(type default)
		)
		(layer "In1.Cu")
	)
	(gr_line
		(start 416.691064 -245.067074)
		(end 415.878264 -245.067074)
		(stroke
			(width 0.2)
			(type default)
		)
		(layer "In1.Cu")
	)
	(gr_arc
		(start 416.691064 -244.813074)
		(mid 416.726985 -244.798195)
		(end 416.741864 -244.762274)
		(stroke
			(width 0.2)
			(type default)
		)
		(layer "In1.Cu")
	)
	(gr_line
		(start 416.691064 -244.508274)
		(end 415.878264 -244.508274)
		(stroke
			(width 0.2)
			(type default)
		)
		(layer "In1.Cu")
	)
	(gr_arc
		(start 416.691064 -130.37185)
		(mid 416.726985 -130.356971)
		(end 416.741864 -130.32105)
		(stroke
			(width 0.2)
			(type default)
		)
		(layer "In1.Cu")
	)
	(gr_line
		(start 416.691064 -130.06705)
		(end 415.878264 -130.06705)
		(stroke
			(width 0.2)
			(type default)
		)
		(layer "In1.Cu")
	)
	(gr_arc
		(start 416.691064 -129.81305)
		(mid 416.726985 -129.798171)
		(end 416.741864 -129.76225)
		(stroke
			(width 0.2)
			(type default)
		)
		(layer "In1.Cu")
	)
	(gr_line
		(start 416.691064 -129.50825)
		(end 415.878264 -129.50825)
		(stroke
			(width 0.2)
			(type default)
		)
		(layer "In1.Cu")
	)
	(gr_arc
		(start 416.691064 -15.371826)
		(mid 416.726985 -15.356947)
		(end 416.741864 -15.321026)
		(stroke
			(width 0.2)
			(type default)
		)
		(layer "In1.Cu")
	)
	(gr_line
		(start 416.691064 -15.067026)
		(end 415.878264 -15.067026)
		(stroke
			(width 0.2)
			(type default)
		)
		(layer "In1.Cu")
	)
	(gr_arc
		(start 416.691064 -14.813026)
		(mid 416.726985 -14.798147)
		(end 416.741864 -14.762226)
		(stroke
			(width 0.2)
			(type default)
		)
		(layer "In1.Cu")
	)
	(gr_line
		(start 416.691064 -14.508226)
		(end 415.878264 -14.508226)
		(stroke
			(width 0.2)
			(type default)
		)
		(layer "In1.Cu")
	)
	(gr_line
		(start 416.699954 -380.000002)
		(end 364.700058 -380.000002)
		(stroke
			(width 1.524)
			(type default)
		)
		(layer "In1.Cu")
	)
	(gr_line
		(start 416.741864 -245.321074)
		(end 416.741864 -245.117874)
		(stroke
			(width 0.2)
			(type default)
		)
		(layer "In1.Cu")
	)
	(gr_arc
		(start 416.741864 -245.117874)
		(mid 416.726985 -245.081953)
		(end 416.691064 -245.067074)
		(stroke
			(width 0.2)
			(type default)
		)
		(layer "In1.Cu")
	)
	(gr_line
		(start 416.741864 -244.762274)
		(end 416.741864 -244.559074)
		(stroke
			(width 0.2)
			(type default)
		)
		(layer "In1.Cu")
	)
	(gr_arc
		(start 416.741864 -244.559074)
		(mid 416.726985 -244.523153)
		(end 416.691064 -244.508274)
		(stroke
			(width 0.2)
			(type default)
		)
		(layer "In1.Cu")
	)
	(gr_line
		(start 416.741864 -130.32105)
		(end 416.741864 -130.11785)
		(stroke
			(width 0.2)
			(type default)
		)
		(layer "In1.Cu")
	)
	(gr_arc
		(start 416.741864 -130.11785)
		(mid 416.726985 -130.081929)
		(end 416.691064 -130.06705)
		(stroke
			(width 0.2)
			(type default)
		)
		(layer "In1.Cu")
	)
	(gr_line
		(start 416.741864 -129.76225)
		(end 416.741864 -129.55905)
		(stroke
			(width 0.2)
			(type default)
		)
		(layer "In1.Cu")
	)
	(gr_arc
		(start 416.741864 -129.55905)
		(mid 416.726985 -129.523129)
		(end 416.691064 -129.50825)
		(stroke
			(width 0.2)
			(type default)
		)
		(layer "In1.Cu")
	)
	(gr_line
		(start 416.741864 -15.321026)
		(end 416.741864 -15.117826)
		(stroke
			(width 0.2)
			(type default)
		)
		(layer "In1.Cu")
	)
	(gr_arc
		(start 416.741864 -15.117826)
		(mid 416.726985 -15.081905)
		(end 416.691064 -15.067026)
		(stroke
			(width 0.2)
			(type default)
		)
		(layer "In1.Cu")
	)
	(gr_line
		(start 416.741864 -14.762226)
		(end 416.741864 -14.559026)
		(stroke
			(width 0.2)
			(type default)
		)
		(layer "In1.Cu")
	)
	(gr_arc
		(start 416.741864 -14.559026)
		(mid 416.726985 -14.523105)
		(end 416.691064 -14.508226)
		(stroke
			(width 0.2)
			(type default)
		)
		(layer "In1.Cu")
	)
	(gr_line
		(start 417.331652 -132.922264)
		(end 418.601652 -132.922264)
		(stroke
			(width 0.2)
			(type default)
		)
		(layer "In1.Cu")
	)
	(gr_line
		(start 417.331652 -17.92224)
		(end 418.601652 -17.92224)
		(stroke
			(width 0.2)
			(type default)
		)
		(layer "In1.Cu")
	)
	(gr_arc
		(start 417.331906 -131.951984)
		(mid 416.846512 -132.436997)
		(end 417.331652 -132.922264)
		(stroke
			(width 0.2)
			(type default)
		)
		(layer "In1.Cu")
	)
	(gr_arc
		(start 417.331906 -16.95196)
		(mid 416.846512 -17.436973)
		(end 417.331652 -17.92224)
		(stroke
			(width 0.2)
			(type default)
		)
		(layer "In1.Cu")
	)
	(gr_line
		(start 417.699952 -384.999992)
		(end 417.699952 -381)
		(stroke
			(width 1.524)
			(type default)
		)
		(layer "In1.Cu")
	)
	(gr_arc
		(start 417.699952 -384.999992)
		(mid 417.992839 -385.70712)
		(end 418.69995 -385.99999)
		(stroke
			(width 1.524)
			(type default)
		)
		(layer "In1.Cu")
	)
	(gr_arc
		(start 417.699952 -381)
		(mid 417.407059 -380.292895)
		(end 416.699954 -380.000002)
		(stroke
			(width 1.524)
			(type default)
		)
		(layer "In1.Cu")
	)
	(gr_arc
		(start 417.754562 -249.385074)
		(mid 418.239702 -249.870214)
		(end 418.724842 -249.385074)
		(stroke
			(width 0.2)
			(type default)
		)
		(layer "In1.Cu")
	)
	(gr_line
		(start 417.754562 -248.115074)
		(end 417.754562 -249.385074)
		(stroke
			(width 0.2)
			(type default)
		)
		(layer "In1.Cu")
	)
	(gr_arc
		(start 418.601652 -132.922264)
		(mid 419.086792 -132.437124)
		(end 418.601652 -131.951984)
		(stroke
			(width 0.2)
			(type default)
		)
		(layer "In1.Cu")
	)
	(gr_line
		(start 418.601652 -131.951984)
		(end 417.331906 -131.951984)
		(stroke
			(width 0.2)
			(type default)
		)
		(layer "In1.Cu")
	)
	(gr_arc
		(start 418.601652 -17.92224)
		(mid 419.086792 -17.4371)
		(end 418.601652 -16.95196)
		(stroke
			(width 0.2)
			(type default)
		)
		(layer "In1.Cu")
	)
	(gr_line
		(start 418.601652 -16.95196)
		(end 417.331906 -16.95196)
		(stroke
			(width 0.2)
			(type default)
		)
		(layer "In1.Cu")
	)
	(gr_line
		(start 418.724842 -249.385074)
		(end 418.724842 -248.115328)
		(stroke
			(width 0.2)
			(type default)
		)
		(layer "In1.Cu")
	)
	(gr_arc
		(start 418.724842 -248.115328)
		(mid 418.239829 -247.629934)
		(end 417.754562 -248.115074)
		(stroke
			(width 0.2)
			(type default)
		)
		(layer "In1.Cu")
	)
	(gr_line
		(start 420.843964 -250.350274)
		(end 420.843964 -247.149874)
		(stroke
			(width 0.2)
			(type default)
		)
		(layer "In1.Cu")
	)
	(gr_line
		(start 420.843964 -247.149874)
		(end 423.206164 -247.149874)
		(stroke
			(width 0.2)
			(type default)
		)
		(layer "In1.Cu")
	)
	(gr_line
		(start 420.843964 -246.540274)
		(end 420.843964 -243.339874)
		(stroke
			(width 0.2)
			(type default)
		)
		(layer "In1.Cu")
	)
	(gr_line
		(start 420.843964 -243.339874)
		(end 423.206164 -243.339874)
		(stroke
			(width 0.2)
			(type default)
		)
		(layer "In1.Cu")
	)
	(gr_line
		(start 420.843964 -135.35025)
		(end 420.843964 -132.14985)
		(stroke
			(width 0.2)
			(type default)
		)
		(layer "In1.Cu")
	)
	(gr_line
		(start 420.843964 -132.14985)
		(end 423.206164 -132.14985)
		(stroke
			(width 0.2)
			(type default)
		)
		(layer "In1.Cu")
	)
	(gr_line
		(start 420.843964 -131.54025)
		(end 420.843964 -128.33985)
		(stroke
			(width 0.2)
			(type default)
		)
		(layer "In1.Cu")
	)
	(gr_line
		(start 420.843964 -128.33985)
		(end 423.206164 -128.33985)
		(stroke
			(width 0.2)
			(type default)
		)
		(layer "In1.Cu")
	)
	(gr_line
		(start 420.843964 -20.350226)
		(end 420.843964 -17.149826)
		(stroke
			(width 0.2)
			(type default)
		)
		(layer "In1.Cu")
	)
	(gr_line
		(start 420.843964 -17.149826)
		(end 423.206164 -17.149826)
		(stroke
			(width 0.2)
			(type default)
		)
		(layer "In1.Cu")
	)
	(gr_line
		(start 420.843964 -16.540226)
		(end 420.843964 -13.339826)
		(stroke
			(width 0.2)
			(type default)
		)
		(layer "In1.Cu")
	)
	(gr_line
		(start 420.843964 -13.339826)
		(end 423.206164 -13.339826)
		(stroke
			(width 0.2)
			(type default)
		)
		(layer "In1.Cu")
	)
	(gr_line
		(start 423.206164 -250.350274)
		(end 420.843964 -250.350274)
		(stroke
			(width 0.2)
			(type default)
		)
		(layer "In1.Cu")
	)
	(gr_line
		(start 423.206164 -247.149874)
		(end 423.206164 -250.350274)
		(stroke
			(width 0.2)
			(type default)
		)
		(layer "In1.Cu")
	)
	(gr_line
		(start 423.206164 -246.540274)
		(end 420.843964 -246.540274)
		(stroke
			(width 0.2)
			(type default)
		)
		(layer "In1.Cu")
	)
	(gr_line
		(start 423.206164 -243.339874)
		(end 423.206164 -246.540274)
		(stroke
			(width 0.2)
			(type default)
		)
		(layer "In1.Cu")
	)
	(gr_line
		(start 423.206164 -135.35025)
		(end 420.843964 -135.35025)
		(stroke
			(width 0.2)
			(type default)
		)
		(layer "In1.Cu")
	)
	(gr_line
		(start 423.206164 -132.14985)
		(end 423.206164 -135.35025)
		(stroke
			(width 0.2)
			(type default)
		)
		(layer "In1.Cu")
	)
	(gr_line
		(start 423.206164 -131.54025)
		(end 420.843964 -131.54025)
		(stroke
			(width 0.2)
			(type default)
		)
		(layer "In1.Cu")
	)
	(gr_line
		(start 423.206164 -128.33985)
		(end 423.206164 -131.54025)
		(stroke
			(width 0.2)
			(type default)
		)
		(layer "In1.Cu")
	)
	(gr_line
		(start 423.206164 -20.350226)
		(end 420.843964 -20.350226)
		(stroke
			(width 0.2)
			(type default)
		)
		(layer "In1.Cu")
	)
	(gr_line
		(start 423.206164 -17.149826)
		(end 423.206164 -20.350226)
		(stroke
			(width 0.2)
			(type default)
		)
		(layer "In1.Cu")
	)
	(gr_line
		(start 423.206164 -16.540226)
		(end 420.843964 -16.540226)
		(stroke
			(width 0.2)
			(type default)
		)
		(layer "In1.Cu")
	)
	(gr_line
		(start 423.206164 -13.339826)
		(end 423.206164 -16.540226)
		(stroke
			(width 0.2)
			(type default)
		)
		(layer "In1.Cu")
	)
	(gr_arc
		(start 445.11722 -245.45544)
		(mid 445.602233 -245.940834)
		(end 446.0875 -245.455694)
		(stroke
			(width 0.2)
			(type default)
		)
		(layer "In1.Cu")
	)
	(gr_line
		(start 445.11722 -244.312694)
		(end 445.11722 -245.45544)
		(stroke
			(width 0.2)
			(type default)
		)
		(layer "In1.Cu")
	)
	(gr_line
		(start 445.4144 -129.112264)
		(end 446.5574 -129.112264)
		(stroke
			(width 0.2)
			(type default)
		)
		(layer "In1.Cu")
	)
	(gr_line
		(start 445.4144 -14.11224)
		(end 446.5574 -14.11224)
		(stroke
			(width 0.2)
			(type default)
		)
		(layer "In1.Cu")
	)
	(gr_arc
		(start 445.414654 -128.141984)
		(mid 444.92926 -128.626997)
		(end 445.4144 -129.112264)
		(stroke
			(width 0.2)
			(type default)
		)
		(layer "In1.Cu")
	)
	(gr_arc
		(start 445.414654 -13.14196)
		(mid 444.92926 -13.626973)
		(end 445.4144 -14.11224)
		(stroke
			(width 0.2)
			(type default)
		)
		(layer "In1.Cu")
	)
	(gr_line
		(start 446.0875 -245.455694)
		(end 446.0875 -244.312694)
		(stroke
			(width 0.2)
			(type default)
		)
		(layer "In1.Cu")
	)
	(gr_arc
		(start 446.0875 -244.312694)
		(mid 445.60236 -243.827554)
		(end 445.11722 -244.312694)
		(stroke
			(width 0.2)
			(type default)
		)
		(layer "In1.Cu")
	)
	(gr_arc
		(start 446.5574 -129.112264)
		(mid 447.04254 -128.627124)
		(end 446.5574 -128.141984)
		(stroke
			(width 0.2)
			(type default)
		)
		(layer "In1.Cu")
	)
	(gr_line
		(start 446.5574 -128.141984)
		(end 445.414654 -128.141984)
		(stroke
			(width 0.2)
			(type default)
		)
		(layer "In1.Cu")
	)
	(gr_arc
		(start 446.5574 -14.11224)
		(mid 447.04254 -13.6271)
		(end 446.5574 -13.14196)
		(stroke
			(width 0.2)
			(type default)
		)
		(layer "In1.Cu")
	)
	(gr_line
		(start 446.5574 -13.14196)
		(end 445.414654 -13.14196)
		(stroke
			(width 0.2)
			(type default)
		)
		(layer "In1.Cu")
	)
	(gr_arc
		(start 447.377312 -245.321074)
		(mid 447.392191 -245.356995)
		(end 447.428112 -245.371874)
		(stroke
			(width 0.2)
			(type default)
		)
		(layer "In1.Cu")
	)
	(gr_line
		(start 447.377312 -245.117874)
		(end 447.377312 -245.321074)
		(stroke
			(width 0.2)
			(type default)
		)
		(layer "In1.Cu")
	)
	(gr_arc
		(start 447.377312 -244.762274)
		(mid 447.392191 -244.798195)
		(end 447.428112 -244.813074)
		(stroke
			(width 0.2)
			(type default)
		)
		(layer "In1.Cu")
	)
	(gr_line
		(start 447.377312 -244.559074)
		(end 447.377312 -244.762274)
		(stroke
			(width 0.2)
			(type default)
		)
		(layer "In1.Cu")
	)
	(gr_arc
		(start 447.377312 -130.32105)
		(mid 447.392191 -130.356971)
		(end 447.428112 -130.37185)
		(stroke
			(width 0.2)
			(type default)
		)
		(layer "In1.Cu")
	)
	(gr_line
		(start 447.377312 -130.11785)
		(end 447.377312 -130.32105)
		(stroke
			(width 0.2)
			(type default)
		)
		(layer "In1.Cu")
	)
	(gr_arc
		(start 447.377312 -129.76225)
		(mid 447.392191 -129.798171)
		(end 447.428112 -129.81305)
		(stroke
			(width 0.2)
			(type default)
		)
		(layer "In1.Cu")
	)
	(gr_line
		(start 447.377312 -129.55905)
		(end 447.377312 -129.76225)
		(stroke
			(width 0.2)
			(type default)
		)
		(layer "In1.Cu")
	)
	(gr_arc
		(start 447.377312 -15.321026)
		(mid 447.392191 -15.356947)
		(end 447.428112 -15.371826)
		(stroke
			(width 0.2)
			(type default)
		)
		(layer "In1.Cu")
	)
	(gr_line
		(start 447.377312 -15.117826)
		(end 447.377312 -15.321026)
		(stroke
			(width 0.2)
			(type default)
		)
		(layer "In1.Cu")
	)
	(gr_arc
		(start 447.377312 -14.762226)
		(mid 447.392191 -14.798147)
		(end 447.428112 -14.813026)
		(stroke
			(width 0.2)
			(type default)
		)
		(layer "In1.Cu")
	)
	(gr_line
		(start 447.377312 -14.559026)
		(end 447.377312 -14.762226)
		(stroke
			(width 0.2)
			(type default)
		)
		(layer "In1.Cu")
	)
	(gr_line
		(start 447.428112 -245.371874)
		(end 448.240912 -245.371874)
		(stroke
			(width 0.2)
			(type default)
		)
		(layer "In1.Cu")
	)
	(gr_arc
		(start 447.428112 -245.067074)
		(mid 447.392191 -245.081953)
		(end 447.377312 -245.117874)
		(stroke
			(width 0.2)
			(type default)
		)
		(layer "In1.Cu")
	)
	(gr_line
		(start 447.428112 -244.813074)
		(end 448.240912 -244.813074)
		(stroke
			(width 0.2)
			(type default)
		)
		(layer "In1.Cu")
	)
	(gr_arc
		(start 447.428112 -244.508274)
		(mid 447.392191 -244.523153)
		(end 447.377312 -244.559074)
		(stroke
			(width 0.2)
			(type default)
		)
		(layer "In1.Cu")
	)
	(gr_line
		(start 447.428112 -130.37185)
		(end 448.240912 -130.37185)
		(stroke
			(width 0.2)
			(type default)
		)
		(layer "In1.Cu")
	)
	(gr_arc
		(start 447.428112 -130.06705)
		(mid 447.392191 -130.081929)
		(end 447.377312 -130.11785)
		(stroke
			(width 0.2)
			(type default)
		)
		(layer "In1.Cu")
	)
	(gr_line
		(start 447.428112 -129.81305)
		(end 448.240912 -129.81305)
		(stroke
			(width 0.2)
			(type default)
		)
		(layer "In1.Cu")
	)
	(gr_arc
		(start 447.428112 -129.50825)
		(mid 447.392191 -129.523129)
		(end 447.377312 -129.55905)
		(stroke
			(width 0.2)
			(type default)
		)
		(layer "In1.Cu")
	)
	(gr_line
		(start 447.428112 -15.371826)
		(end 448.240912 -15.371826)
		(stroke
			(width 0.2)
			(type default)
		)
		(layer "In1.Cu")
	)
	(gr_arc
		(start 447.428112 -15.067026)
		(mid 447.392191 -15.081905)
		(end 447.377312 -15.117826)
		(stroke
			(width 0.2)
			(type default)
		)
		(layer "In1.Cu")
	)
	(gr_line
		(start 447.428112 -14.813026)
		(end 448.240912 -14.813026)
		(stroke
			(width 0.2)
			(type default)
		)
		(layer "In1.Cu")
	)
	(gr_arc
		(start 447.428112 -14.508226)
		(mid 447.392191 -14.523105)
		(end 447.377312 -14.559026)
		(stroke
			(width 0.2)
			(type default)
		)
		(layer "In1.Cu")
	)
	(gr_arc
		(start 448.240912 -245.371874)
		(mid 448.276833 -245.356995)
		(end 448.291712 -245.321074)
		(stroke
			(width 0.2)
			(type default)
		)
		(layer "In1.Cu")
	)
	(gr_line
		(start 448.240912 -245.067074)
		(end 447.428112 -245.067074)
		(stroke
			(width 0.2)
			(type default)
		)
		(layer "In1.Cu")
	)
	(gr_arc
		(start 448.240912 -244.813074)
		(mid 448.276833 -244.798195)
		(end 448.291712 -244.762274)
		(stroke
			(width 0.2)
			(type default)
		)
		(layer "In1.Cu")
	)
	(gr_line
		(start 448.240912 -244.508274)
		(end 447.428112 -244.508274)
		(stroke
			(width 0.2)
			(type default)
		)
		(layer "In1.Cu")
	)
	(gr_arc
		(start 448.240912 -130.37185)
		(mid 448.276833 -130.356971)
		(end 448.291712 -130.32105)
		(stroke
			(width 0.2)
			(type default)
		)
		(layer "In1.Cu")
	)
	(gr_line
		(start 448.240912 -130.06705)
		(end 447.428112 -130.06705)
		(stroke
			(width 0.2)
			(type default)
		)
		(layer "In1.Cu")
	)
	(gr_arc
		(start 448.240912 -129.81305)
		(mid 448.276833 -129.798171)
		(end 448.291712 -129.76225)
		(stroke
			(width 0.2)
			(type default)
		)
		(layer "In1.Cu")
	)
	(gr_line
		(start 448.240912 -129.50825)
		(end 447.428112 -129.50825)
		(stroke
			(width 0.2)
			(type default)
		)
		(layer "In1.Cu")
	)
	(gr_arc
		(start 448.240912 -15.371826)
		(mid 448.276833 -15.356947)
		(end 448.291712 -15.321026)
		(stroke
			(width 0.2)
			(type default)
		)
		(layer "In1.Cu")
	)
	(gr_line
		(start 448.240912 -15.067026)
		(end 447.428112 -15.067026)
		(stroke
			(width 0.2)
			(type default)
		)
		(layer "In1.Cu")
	)
	(gr_arc
		(start 448.240912 -14.813026)
		(mid 448.276833 -14.798147)
		(end 448.291712 -14.762226)
		(stroke
			(width 0.2)
			(type default)
		)
		(layer "In1.Cu")
	)
	(gr_line
		(start 448.240912 -14.508226)
		(end 447.428112 -14.508226)
		(stroke
			(width 0.2)
			(type default)
		)
		(layer "In1.Cu")
	)
	(gr_line
		(start 448.291712 -245.321074)
		(end 448.291712 -245.117874)
		(stroke
			(width 0.2)
			(type default)
		)
		(layer "In1.Cu")
	)
	(gr_arc
		(start 448.291712 -245.117874)
		(mid 448.276833 -245.081953)
		(end 448.240912 -245.067074)
		(stroke
			(width 0.2)
			(type default)
		)
		(layer "In1.Cu")
	)
	(gr_line
		(start 448.291712 -244.762274)
		(end 448.291712 -244.559074)
		(stroke
			(width 0.2)
			(type default)
		)
		(layer "In1.Cu")
	)
	(gr_arc
		(start 448.291712 -244.559074)
		(mid 448.276833 -244.523153)
		(end 448.240912 -244.508274)
		(stroke
			(width 0.2)
			(type default)
		)
		(layer "In1.Cu")
	)
	(gr_line
		(start 448.291712 -130.32105)
		(end 448.291712 -130.11785)
		(stroke
			(width 0.2)
			(type default)
		)
		(layer "In1.Cu")
	)
	(gr_arc
		(start 448.291712 -130.11785)
		(mid 448.276833 -130.081929)
		(end 448.240912 -130.06705)
		(stroke
			(width 0.2)
			(type default)
		)
		(layer "In1.Cu")
	)
	(gr_line
		(start 448.291712 -129.76225)
		(end 448.291712 -129.55905)
		(stroke
			(width 0.2)
			(type default)
		)
		(layer "In1.Cu")
	)
	(gr_arc
		(start 448.291712 -129.55905)
		(mid 448.276833 -129.523129)
		(end 448.240912 -129.50825)
		(stroke
			(width 0.2)
			(type default)
		)
		(layer "In1.Cu")
	)
	(gr_line
		(start 448.291712 -15.321026)
		(end 448.291712 -15.117826)
		(stroke
			(width 0.2)
			(type default)
		)
		(layer "In1.Cu")
	)
	(gr_arc
		(start 448.291712 -15.117826)
		(mid 448.276833 -15.081905)
		(end 448.240912 -15.067026)
		(stroke
			(width 0.2)
			(type default)
		)
		(layer "In1.Cu")
	)
	(gr_line
		(start 448.291712 -14.762226)
		(end 448.291712 -14.559026)
		(stroke
			(width 0.2)
			(type default)
		)
		(layer "In1.Cu")
	)
	(gr_arc
		(start 448.291712 -14.559026)
		(mid 448.276833 -14.523105)
		(end 448.240912 -14.508226)
		(stroke
			(width 0.2)
			(type default)
		)
		(layer "In1.Cu")
	)
	(gr_line
		(start 448.8815 -132.922264)
		(end 450.151246 -132.922264)
		(stroke
			(width 0.2)
			(type default)
		)
		(layer "In1.Cu")
	)
	(gr_arc
		(start 448.8815 -131.951984)
		(mid 448.39636 -132.437124)
		(end 448.8815 -132.922264)
		(stroke
			(width 0.2)
			(type default)
		)
		(layer "In1.Cu")
	)
	(gr_line
		(start 448.8815 -17.92224)
		(end 450.151246 -17.92224)
		(stroke
			(width 0.2)
			(type default)
		)
		(layer "In1.Cu")
	)
	(gr_arc
		(start 448.8815 -16.95196)
		(mid 448.39636 -17.4371)
		(end 448.8815 -17.92224)
		(stroke
			(width 0.2)
			(type default)
		)
		(layer "In1.Cu")
	)
	(gr_arc
		(start 449.30441 -249.385074)
		(mid 449.78955 -249.870214)
		(end 450.27469 -249.385074)
		(stroke
			(width 0.2)
			(type default)
		)
		(layer "In1.Cu")
	)
	(gr_line
		(start 449.30441 -248.115074)
		(end 449.30441 -249.385074)
		(stroke
			(width 0.2)
			(type default)
		)
		(layer "In1.Cu")
	)
	(gr_arc
		(start 450.151246 -132.922264)
		(mid 450.63664 -132.437251)
		(end 450.1515 -131.951984)
		(stroke
			(width 0.2)
			(type default)
		)
		(layer "In1.Cu")
	)
	(gr_arc
		(start 450.151246 -17.92224)
		(mid 450.63664 -17.437227)
		(end 450.1515 -16.95196)
		(stroke
			(width 0.2)
			(type default)
		)
		(layer "In1.Cu")
	)
	(gr_line
		(start 450.1515 -131.951984)
		(end 448.8815 -131.951984)
		(stroke
			(width 0.2)
			(type default)
		)
		(layer "In1.Cu")
	)
	(gr_line
		(start 450.1515 -16.95196)
		(end 448.8815 -16.95196)
		(stroke
			(width 0.2)
			(type default)
		)
		(layer "In1.Cu")
	)
	(gr_line
		(start 450.27469 -249.385074)
		(end 450.27469 -248.115328)
		(stroke
			(width 0.2)
			(type default)
		)
		(layer "In1.Cu")
	)
	(gr_arc
		(start 450.27469 -248.115328)
		(mid 449.789677 -247.629934)
		(end 449.30441 -248.115074)
		(stroke
			(width 0.2)
			(type default)
		)
		(layer "In1.Cu")
	)
	(gr_line
		(start 452.393812 -250.350274)
		(end 452.393812 -247.149874)
		(stroke
			(width 0.2)
			(type default)
		)
		(layer "In1.Cu")
	)
	(gr_line
		(start 452.393812 -247.149874)
		(end 454.756012 -247.149874)
		(stroke
			(width 0.2)
			(type default)
		)
		(layer "In1.Cu")
	)
	(gr_line
		(start 452.393812 -246.540274)
		(end 452.393812 -243.339874)
		(stroke
			(width 0.2)
			(type default)
		)
		(layer "In1.Cu")
	)
	(gr_line
		(start 452.393812 -243.339874)
		(end 454.756012 -243.339874)
		(stroke
			(width 0.2)
			(type default)
		)
		(layer "In1.Cu")
	)
	(gr_line
		(start 452.393812 -135.35025)
		(end 452.393812 -132.14985)
		(stroke
			(width 0.2)
			(type default)
		)
		(layer "In1.Cu")
	)
	(gr_line
		(start 452.393812 -132.14985)
		(end 454.756012 -132.14985)
		(stroke
			(width 0.2)
			(type default)
		)
		(layer "In1.Cu")
	)
	(gr_line
		(start 452.393812 -131.54025)
		(end 452.393812 -128.33985)
		(stroke
			(width 0.2)
			(type default)
		)
		(layer "In1.Cu")
	)
	(gr_line
		(start 452.393812 -128.33985)
		(end 454.756012 -128.33985)
		(stroke
			(width 0.2)
			(type default)
		)
		(layer "In1.Cu")
	)
	(gr_line
		(start 452.393812 -20.350226)
		(end 452.393812 -17.149826)
		(stroke
			(width 0.2)
			(type default)
		)
		(layer "In1.Cu")
	)
	(gr_line
		(start 452.393812 -17.149826)
		(end 454.756012 -17.149826)
		(stroke
			(width 0.2)
			(type default)
		)
		(layer "In1.Cu")
	)
	(gr_line
		(start 452.393812 -16.540226)
		(end 452.393812 -13.339826)
		(stroke
			(width 0.2)
			(type default)
		)
		(layer "In1.Cu")
	)
	(gr_line
		(start 452.393812 -13.339826)
		(end 454.756012 -13.339826)
		(stroke
			(width 0.2)
			(type default)
		)
		(layer "In1.Cu")
	)
	(gr_line
		(start 454.756012 -250.350274)
		(end 452.393812 -250.350274)
		(stroke
			(width 0.2)
			(type default)
		)
		(layer "In1.Cu")
	)
	(gr_line
		(start 454.756012 -247.149874)
		(end 454.756012 -250.350274)
		(stroke
			(width 0.2)
			(type default)
		)
		(layer "In1.Cu")
	)
	(gr_line
		(start 454.756012 -246.540274)
		(end 452.393812 -246.540274)
		(stroke
			(width 0.2)
			(type default)
		)
		(layer "In1.Cu")
	)
	(gr_line
		(start 454.756012 -243.339874)
		(end 454.756012 -246.540274)
		(stroke
			(width 0.2)
			(type default)
		)
		(layer "In1.Cu")
	)
	(gr_line
		(start 454.756012 -135.35025)
		(end 452.393812 -135.35025)
		(stroke
			(width 0.2)
			(type default)
		)
		(layer "In1.Cu")
	)
	(gr_line
		(start 454.756012 -132.14985)
		(end 454.756012 -135.35025)
		(stroke
			(width 0.2)
			(type default)
		)
		(layer "In1.Cu")
	)
	(gr_line
		(start 454.756012 -131.54025)
		(end 452.393812 -131.54025)
		(stroke
			(width 0.2)
			(type default)
		)
		(layer "In1.Cu")
	)
	(gr_line
		(start 454.756012 -128.33985)
		(end 454.756012 -131.54025)
		(stroke
			(width 0.2)
			(type default)
		)
		(layer "In1.Cu")
	)
	(gr_line
		(start 454.756012 -20.350226)
		(end 452.393812 -20.350226)
		(stroke
			(width 0.2)
			(type default)
		)
		(layer "In1.Cu")
	)
	(gr_line
		(start 454.756012 -17.149826)
		(end 454.756012 -20.350226)
		(stroke
			(width 0.2)
			(type default)
		)
		(layer "In1.Cu")
	)
	(gr_line
		(start 454.756012 -16.540226)
		(end 452.393812 -16.540226)
		(stroke
			(width 0.2)
			(type default)
		)
		(layer "In1.Cu")
	)
	(gr_line
		(start 454.756012 -13.339826)
		(end 454.756012 -16.540226)
		(stroke
			(width 0.2)
			(type default)
		)
		(layer "In1.Cu")
	)
	(gr_line
		(start 464.250024 -385.99999)
		(end 418.69995 -385.99999)
		(stroke
			(width 1.524)
			(type default)
		)
		(layer "In1.Cu")
	)
	(gr_arc
		(start 464.250024 -385.99999)
		(mid 464.957111 -385.707088)
		(end 465.250022 -384.999992)
		(stroke
			(width 1.524)
			(type default)
		)
		(layer "In1.Cu")
	)
	(gr_line
		(start 465.250022 -383.29997)
		(end 465.250022 -384.999992)
		(stroke
			(width 1.524)
			(type default)
		)
		(layer "In1.Cu")
	)
	(gr_arc
		(start 466.25002 -382.299972)
		(mid 465.542915 -382.592865)
		(end 465.250022 -383.29997)
		(stroke
			(width 1.524)
			(type default)
		)
		(layer "In1.Cu")
	)
	(gr_line
		(start 472.74988 -382.299972)
		(end 466.25002 -382.299972)
		(stroke
			(width 1.524)
			(type default)
		)
		(layer "In1.Cu")
	)
	(gr_line
		(start 473.749878 -384.999992)
		(end 473.749878 -383.29997)
		(stroke
			(width 1.524)
			(type default)
		)
		(layer "In1.Cu")
	)
	(gr_arc
		(start 473.749878 -384.999992)
		(mid 474.042766 -385.707111)
		(end 474.749876 -385.99999)
		(stroke
			(width 1.524)
			(type default)
		)
		(layer "In1.Cu")
	)
	(gr_arc
		(start 473.749878 -383.29997)
		(mid 473.456985 -382.592865)
		(end 472.74988 -382.299972)
		(stroke
			(width 1.524)
			(type default)
		)
		(layer "In1.Cu")
	)
	(gr_arc
		(start 476.667322 -245.45544)
		(mid 477.152335 -245.940834)
		(end 477.637602 -245.455694)
		(stroke
			(width 0.2)
			(type default)
		)
		(layer "In1.Cu")
	)
	(gr_line
		(start 476.667322 -244.312694)
		(end 476.667322 -245.45544)
		(stroke
			(width 0.2)
			(type default)
		)
		(layer "In1.Cu")
	)
	(gr_line
		(start 476.964502 -129.112264)
		(end 478.107502 -129.112264)
		(stroke
			(width 0.2)
			(type default)
		)
		(layer "In1.Cu")
	)
	(gr_line
		(start 476.964502 -14.11224)
		(end 478.107502 -14.11224)
		(stroke
			(width 0.2)
			(type default)
		)
		(layer "In1.Cu")
	)
	(gr_arc
		(start 476.964756 -128.141984)
		(mid 476.479362 -128.626997)
		(end 476.964502 -129.112264)
		(stroke
			(width 0.2)
			(type default)
		)
		(layer "In1.Cu")
	)
	(gr_arc
		(start 476.964756 -13.14196)
		(mid 476.479362 -13.626973)
		(end 476.964502 -14.11224)
		(stroke
			(width 0.2)
			(type default)
		)
		(layer "In1.Cu")
	)
	(gr_line
		(start 477.637602 -245.455694)
		(end 477.637602 -244.312694)
		(stroke
			(width 0.2)
			(type default)
		)
		(layer "In1.Cu")
	)
	(gr_arc
		(start 477.637602 -244.312694)
		(mid 477.152462 -243.827554)
		(end 476.667322 -244.312694)
		(stroke
			(width 0.2)
			(type default)
		)
		(layer "In1.Cu")
	)
	(gr_arc
		(start 478.107502 -129.112264)
		(mid 478.592642 -128.627124)
		(end 478.107502 -128.141984)
		(stroke
			(width 0.2)
			(type default)
		)
		(layer "In1.Cu")
	)
	(gr_line
		(start 478.107502 -128.141984)
		(end 476.964756 -128.141984)
		(stroke
			(width 0.2)
			(type default)
		)
		(layer "In1.Cu")
	)
	(gr_arc
		(start 478.107502 -14.11224)
		(mid 478.592642 -13.6271)
		(end 478.107502 -13.14196)
		(stroke
			(width 0.2)
			(type default)
		)
		(layer "In1.Cu")
	)
	(gr_line
		(start 478.107502 -13.14196)
		(end 476.964756 -13.14196)
		(stroke
			(width 0.2)
			(type default)
		)
		(layer "In1.Cu")
	)
	(gr_arc
		(start 478.927414 -245.321074)
		(mid 478.942293 -245.356995)
		(end 478.978214 -245.371874)
		(stroke
			(width 0.2)
			(type default)
		)
		(layer "In1.Cu")
	)
	(gr_line
		(start 478.927414 -245.117874)
		(end 478.927414 -245.321074)
		(stroke
			(width 0.2)
			(type default)
		)
		(layer "In1.Cu")
	)
	(gr_arc
		(start 478.927414 -244.762274)
		(mid 478.942293 -244.798195)
		(end 478.978214 -244.813074)
		(stroke
			(width 0.2)
			(type default)
		)
		(layer "In1.Cu")
	)
	(gr_line
		(start 478.927414 -244.559074)
		(end 478.927414 -244.762274)
		(stroke
			(width 0.2)
			(type default)
		)
		(layer "In1.Cu")
	)
	(gr_arc
		(start 478.927414 -130.32105)
		(mid 478.942293 -130.356971)
		(end 478.978214 -130.37185)
		(stroke
			(width 0.2)
			(type default)
		)
		(layer "In1.Cu")
	)
	(gr_line
		(start 478.927414 -130.11785)
		(end 478.927414 -130.32105)
		(stroke
			(width 0.2)
			(type default)
		)
		(layer "In1.Cu")
	)
	(gr_arc
		(start 478.927414 -129.76225)
		(mid 478.942293 -129.798171)
		(end 478.978214 -129.81305)
		(stroke
			(width 0.2)
			(type default)
		)
		(layer "In1.Cu")
	)
	(gr_line
		(start 478.927414 -129.55905)
		(end 478.927414 -129.76225)
		(stroke
			(width 0.2)
			(type default)
		)
		(layer "In1.Cu")
	)
	(gr_arc
		(start 478.927414 -15.321026)
		(mid 478.942293 -15.356947)
		(end 478.978214 -15.371826)
		(stroke
			(width 0.2)
			(type default)
		)
		(layer "In1.Cu")
	)
	(gr_line
		(start 478.927414 -15.117826)
		(end 478.927414 -15.321026)
		(stroke
			(width 0.2)
			(type default)
		)
		(layer "In1.Cu")
	)
	(gr_arc
		(start 478.927414 -14.762226)
		(mid 478.942293 -14.798147)
		(end 478.978214 -14.813026)
		(stroke
			(width 0.2)
			(type default)
		)
		(layer "In1.Cu")
	)
	(gr_line
		(start 478.927414 -14.559026)
		(end 478.927414 -14.762226)
		(stroke
			(width 0.2)
			(type default)
		)
		(layer "In1.Cu")
	)
	(gr_line
		(start 478.978214 -245.371874)
		(end 479.791014 -245.371874)
		(stroke
			(width 0.2)
			(type default)
		)
		(layer "In1.Cu")
	)
	(gr_arc
		(start 478.978214 -245.067074)
		(mid 478.942293 -245.081953)
		(end 478.927414 -245.117874)
		(stroke
			(width 0.2)
			(type default)
		)
		(layer "In1.Cu")
	)
	(gr_line
		(start 478.978214 -244.813074)
		(end 479.791014 -244.813074)
		(stroke
			(width 0.2)
			(type default)
		)
		(layer "In1.Cu")
	)
	(gr_arc
		(start 478.978214 -244.508274)
		(mid 478.942293 -244.523153)
		(end 478.927414 -244.559074)
		(stroke
			(width 0.2)
			(type default)
		)
		(layer "In1.Cu")
	)
	(gr_line
		(start 478.978214 -130.37185)
		(end 479.791014 -130.37185)
		(stroke
			(width 0.2)
			(type default)
		)
		(layer "In1.Cu")
	)
	(gr_arc
		(start 478.978214 -130.06705)
		(mid 478.942293 -130.081929)
		(end 478.927414 -130.11785)
		(stroke
			(width 0.2)
			(type default)
		)
		(layer "In1.Cu")
	)
	(gr_line
		(start 478.978214 -129.81305)
		(end 479.791014 -129.81305)
		(stroke
			(width 0.2)
			(type default)
		)
		(layer "In1.Cu")
	)
	(gr_arc
		(start 478.978214 -129.50825)
		(mid 478.942293 -129.523129)
		(end 478.927414 -129.55905)
		(stroke
			(width 0.2)
			(type default)
		)
		(layer "In1.Cu")
	)
	(gr_line
		(start 478.978214 -15.371826)
		(end 479.791014 -15.371826)
		(stroke
			(width 0.2)
			(type default)
		)
		(layer "In1.Cu")
	)
	(gr_arc
		(start 478.978214 -15.067026)
		(mid 478.942293 -15.081905)
		(end 478.927414 -15.117826)
		(stroke
			(width 0.2)
			(type default)
		)
		(layer "In1.Cu")
	)
	(gr_line
		(start 478.978214 -14.813026)
		(end 479.791014 -14.813026)
		(stroke
			(width 0.2)
			(type default)
		)
		(layer "In1.Cu")
	)
	(gr_arc
		(start 478.978214 -14.508226)
		(mid 478.942293 -14.523105)
		(end 478.927414 -14.559026)
		(stroke
			(width 0.2)
			(type default)
		)
		(layer "In1.Cu")
	)
	(gr_arc
		(start 479.791014 -245.371874)
		(mid 479.826935 -245.356995)
		(end 479.841814 -245.321074)
		(stroke
			(width 0.2)
			(type default)
		)
		(layer "In1.Cu")
	)
	(gr_line
		(start 479.791014 -245.067074)
		(end 478.978214 -245.067074)
		(stroke
			(width 0.2)
			(type default)
		)
		(layer "In1.Cu")
	)
	(gr_arc
		(start 479.791014 -244.813074)
		(mid 479.826935 -244.798195)
		(end 479.841814 -244.762274)
		(stroke
			(width 0.2)
			(type default)
		)
		(layer "In1.Cu")
	)
	(gr_line
		(start 479.791014 -244.508274)
		(end 478.978214 -244.508274)
		(stroke
			(width 0.2)
			(type default)
		)
		(layer "In1.Cu")
	)
	(gr_arc
		(start 479.791014 -130.37185)
		(mid 479.826935 -130.356971)
		(end 479.841814 -130.32105)
		(stroke
			(width 0.2)
			(type default)
		)
		(layer "In1.Cu")
	)
	(gr_line
		(start 479.791014 -130.06705)
		(end 478.978214 -130.06705)
		(stroke
			(width 0.2)
			(type default)
		)
		(layer "In1.Cu")
	)
	(gr_arc
		(start 479.791014 -129.81305)
		(mid 479.826935 -129.798171)
		(end 479.841814 -129.76225)
		(stroke
			(width 0.2)
			(type default)
		)
		(layer "In1.Cu")
	)
	(gr_line
		(start 479.791014 -129.50825)
		(end 478.978214 -129.50825)
		(stroke
			(width 0.2)
			(type default)
		)
		(layer "In1.Cu")
	)
	(gr_arc
		(start 479.791014 -15.371826)
		(mid 479.826935 -15.356947)
		(end 479.841814 -15.321026)
		(stroke
			(width 0.2)
			(type default)
		)
		(layer "In1.Cu")
	)
	(gr_line
		(start 479.791014 -15.067026)
		(end 478.978214 -15.067026)
		(stroke
			(width 0.2)
			(type default)
		)
		(layer "In1.Cu")
	)
	(gr_arc
		(start 479.791014 -14.813026)
		(mid 479.826935 -14.798147)
		(end 479.841814 -14.762226)
		(stroke
			(width 0.2)
			(type default)
		)
		(layer "In1.Cu")
	)
	(gr_line
		(start 479.791014 -14.508226)
		(end 478.978214 -14.508226)
		(stroke
			(width 0.2)
			(type default)
		)
		(layer "In1.Cu")
	)
	(gr_line
		(start 479.841814 -245.321074)
		(end 479.841814 -245.117874)
		(stroke
			(width 0.2)
			(type default)
		)
		(layer "In1.Cu")
	)
	(gr_arc
		(start 479.841814 -245.117874)
		(mid 479.826935 -245.081953)
		(end 479.791014 -245.067074)
		(stroke
			(width 0.2)
			(type default)
		)
		(layer "In1.Cu")
	)
	(gr_line
		(start 479.841814 -244.762274)
		(end 479.841814 -244.559074)
		(stroke
			(width 0.2)
			(type default)
		)
		(layer "In1.Cu")
	)
	(gr_arc
		(start 479.841814 -244.559074)
		(mid 479.826935 -244.523153)
		(end 479.791014 -244.508274)
		(stroke
			(width 0.2)
			(type default)
		)
		(layer "In1.Cu")
	)
	(gr_line
		(start 479.841814 -130.32105)
		(end 479.841814 -130.11785)
		(stroke
			(width 0.2)
			(type default)
		)
		(layer "In1.Cu")
	)
	(gr_arc
		(start 479.841814 -130.11785)
		(mid 479.826935 -130.081929)
		(end 479.791014 -130.06705)
		(stroke
			(width 0.2)
			(type default)
		)
		(layer "In1.Cu")
	)
	(gr_line
		(start 479.841814 -129.76225)
		(end 479.841814 -129.55905)
		(stroke
			(width 0.2)
			(type default)
		)
		(layer "In1.Cu")
	)
	(gr_arc
		(start 479.841814 -129.55905)
		(mid 479.826935 -129.523129)
		(end 479.791014 -129.50825)
		(stroke
			(width 0.2)
			(type default)
		)
		(layer "In1.Cu")
	)
	(gr_line
		(start 479.841814 -15.321026)
		(end 479.841814 -15.117826)
		(stroke
			(width 0.2)
			(type default)
		)
		(layer "In1.Cu")
	)
	(gr_arc
		(start 479.841814 -15.117826)
		(mid 479.826935 -15.081905)
		(end 479.791014 -15.067026)
		(stroke
			(width 0.2)
			(type default)
		)
		(layer "In1.Cu")
	)
	(gr_line
		(start 479.841814 -14.762226)
		(end 479.841814 -14.559026)
		(stroke
			(width 0.2)
			(type default)
		)
		(layer "In1.Cu")
	)
	(gr_arc
		(start 479.841814 -14.559026)
		(mid 479.826935 -14.523105)
		(end 479.791014 -14.508226)
		(stroke
			(width 0.2)
			(type default)
		)
		(layer "In1.Cu")
	)
	(gr_line
		(start 480.431602 -132.922264)
		(end 481.701602 -132.922264)
		(stroke
			(width 0.2)
			(type default)
		)
		(layer "In1.Cu")
	)
	(gr_line
		(start 480.431602 -17.92224)
		(end 481.701602 -17.92224)
		(stroke
			(width 0.2)
			(type default)
		)
		(layer "In1.Cu")
	)
	(gr_arc
		(start 480.431856 -131.951984)
		(mid 479.946462 -132.436997)
		(end 480.431602 -132.922264)
		(stroke
			(width 0.2)
			(type default)
		)
		(layer "In1.Cu")
	)
	(gr_arc
		(start 480.431856 -16.95196)
		(mid 479.946462 -17.436973)
		(end 480.431602 -17.92224)
		(stroke
			(width 0.2)
			(type default)
		)
		(layer "In1.Cu")
	)
	(gr_arc
		(start 480.854512 -249.385074)
		(mid 481.339652 -249.870214)
		(end 481.824792 -249.385074)
		(stroke
			(width 0.2)
			(type default)
		)
		(layer "In1.Cu")
	)
	(gr_line
		(start 480.854512 -248.115074)
		(end 480.854512 -249.385074)
		(stroke
			(width 0.2)
			(type default)
		)
		(layer "In1.Cu")
	)
	(gr_arc
		(start 481.701602 -132.922264)
		(mid 482.186742 -132.437124)
		(end 481.701602 -131.951984)
		(stroke
			(width 0.2)
			(type default)
		)
		(layer "In1.Cu")
	)
	(gr_line
		(start 481.701602 -131.951984)
		(end 480.431856 -131.951984)
		(stroke
			(width 0.2)
			(type default)
		)
		(layer "In1.Cu")
	)
	(gr_arc
		(start 481.701602 -17.92224)
		(mid 482.186742 -17.4371)
		(end 481.701602 -16.95196)
		(stroke
			(width 0.2)
			(type default)
		)
		(layer "In1.Cu")
	)
	(gr_line
		(start 481.701602 -16.95196)
		(end 480.431856 -16.95196)
		(stroke
			(width 0.2)
			(type default)
		)
		(layer "In1.Cu")
	)
	(gr_line
		(start 481.824792 -249.385074)
		(end 481.824792 -248.115328)
		(stroke
			(width 0.2)
			(type default)
		)
		(layer "In1.Cu")
	)
	(gr_arc
		(start 481.824792 -248.115328)
		(mid 481.339779 -247.629934)
		(end 480.854512 -248.115074)
		(stroke
			(width 0.2)
			(type default)
		)
		(layer "In1.Cu")
	)
	(gr_line
		(start 483.943914 -250.350274)
		(end 483.943914 -247.149874)
		(stroke
			(width 0.2)
			(type default)
		)
		(layer "In1.Cu")
	)
	(gr_line
		(start 483.943914 -247.149874)
		(end 486.306114 -247.149874)
		(stroke
			(width 0.2)
			(type default)
		)
		(layer "In1.Cu")
	)
	(gr_line
		(start 483.943914 -246.540274)
		(end 483.943914 -243.339874)
		(stroke
			(width 0.2)
			(type default)
		)
		(layer "In1.Cu")
	)
	(gr_line
		(start 483.943914 -243.339874)
		(end 486.306114 -243.339874)
		(stroke
			(width 0.2)
			(type default)
		)
		(layer "In1.Cu")
	)
	(gr_line
		(start 483.943914 -135.35025)
		(end 483.943914 -132.14985)
		(stroke
			(width 0.2)
			(type default)
		)
		(layer "In1.Cu")
	)
	(gr_line
		(start 483.943914 -132.14985)
		(end 486.306114 -132.14985)
		(stroke
			(width 0.2)
			(type default)
		)
		(layer "In1.Cu")
	)
	(gr_line
		(start 483.943914 -131.54025)
		(end 483.943914 -128.33985)
		(stroke
			(width 0.2)
			(type default)
		)
		(layer "In1.Cu")
	)
	(gr_line
		(start 483.943914 -128.33985)
		(end 486.306114 -128.33985)
		(stroke
			(width 0.2)
			(type default)
		)
		(layer "In1.Cu")
	)
	(gr_line
		(start 483.943914 -20.350226)
		(end 483.943914 -17.149826)
		(stroke
			(width 0.2)
			(type default)
		)
		(layer "In1.Cu")
	)
	(gr_line
		(start 483.943914 -17.149826)
		(end 486.306114 -17.149826)
		(stroke
			(width 0.2)
			(type default)
		)
		(layer "In1.Cu")
	)
	(gr_line
		(start 483.943914 -16.540226)
		(end 483.943914 -13.339826)
		(stroke
			(width 0.2)
			(type default)
		)
		(layer "In1.Cu")
	)
	(gr_line
		(start 483.943914 -13.339826)
		(end 486.306114 -13.339826)
		(stroke
			(width 0.2)
			(type default)
		)
		(layer "In1.Cu")
	)
	(gr_line
		(start 486.306114 -250.350274)
		(end 483.943914 -250.350274)
		(stroke
			(width 0.2)
			(type default)
		)
		(layer "In1.Cu")
	)
	(gr_line
		(start 486.306114 -247.149874)
		(end 486.306114 -250.350274)
		(stroke
			(width 0.2)
			(type default)
		)
		(layer "In1.Cu")
	)
	(gr_line
		(start 486.306114 -246.540274)
		(end 483.943914 -246.540274)
		(stroke
			(width 0.2)
			(type default)
		)
		(layer "In1.Cu")
	)
	(gr_line
		(start 486.306114 -243.339874)
		(end 486.306114 -246.540274)
		(stroke
			(width 0.2)
			(type default)
		)
		(layer "In1.Cu")
	)
	(gr_line
		(start 486.306114 -135.35025)
		(end 483.943914 -135.35025)
		(stroke
			(width 0.2)
			(type default)
		)
		(layer "In1.Cu")
	)
	(gr_line
		(start 486.306114 -132.14985)
		(end 486.306114 -135.35025)
		(stroke
			(width 0.2)
			(type default)
		)
		(layer "In1.Cu")
	)
	(gr_line
		(start 486.306114 -131.54025)
		(end 483.943914 -131.54025)
		(stroke
			(width 0.2)
			(type default)
		)
		(layer "In1.Cu")
	)
	(gr_line
		(start 486.306114 -128.33985)
		(end 486.306114 -131.54025)
		(stroke
			(width 0.2)
			(type default)
		)
		(layer "In1.Cu")
	)
	(gr_line
		(start 486.306114 -20.350226)
		(end 483.943914 -20.350226)
		(stroke
			(width 0.2)
			(type default)
		)
		(layer "In1.Cu")
	)
	(gr_line
		(start 486.306114 -17.149826)
		(end 486.306114 -20.350226)
		(stroke
			(width 0.2)
			(type default)
		)
		(layer "In1.Cu")
	)
	(gr_line
		(start 486.306114 -16.540226)
		(end 483.943914 -16.540226)
		(stroke
			(width 0.2)
			(type default)
		)
		(layer "In1.Cu")
	)
	(gr_line
		(start 486.306114 -13.339826)
		(end 486.306114 -16.540226)
		(stroke
			(width 0.2)
			(type default)
		)
		(layer "In1.Cu")
	)
	(gr_line
		(start 487.449876 -385.99999)
		(end 474.749876 -385.99999)
		(stroke
			(width 1.524)
			(type default)
		)
		(layer "In1.Cu")
	)
	(gr_arc
		(start 487.449876 -385.99999)
		(mid 488.156994 -385.707105)
		(end 488.449874 -384.999992)
		(stroke
			(width 1.524)
			(type default)
		)
		(layer "In1.Cu")
	)
	(gr_line
		(start 488.449874 -372.000018)
		(end 488.449874 -384.999992)
		(stroke
			(width 1.524)
			(type default)
		)
		(layer "In1.Cu")
	)
	(gr_arc
		(start 489.450126 -371.00002)
		(mid 488.742856 -371.292823)
		(end 488.449874 -372.000018)
		(stroke
			(width 1.524)
			(type default)
		)
		(layer "In1.Cu")
	)
	(gr_line
		(start 490.450124 -371.00002)
		(end 489.450126 -371.00002)
		(stroke
			(width 1.524)
			(type default)
		)
		(layer "In1.Cu")
	)
	(gr_arc
		(start 490.450124 -371.00002)
		(mid 491.157222 -370.70712)
		(end 491.450122 -370.000022)
		(stroke
			(width 1.524)
			(type default)
		)
		(layer "In1.Cu")
	)
	(gr_arc
		(start 491.450122 -0.999998)
		(mid 491.15723 -0.292885)
		(end 490.450124 0)
		(stroke
			(width 1.524)
			(type default)
		)
		(layer "In1.Cu")
	)
	(gr_line
		(start 491.450122 -0.999998)
		(end 491.450122 -370.000022)
		(stroke
			(width 1.524)
			(type default)
		)
		(layer "In1.Cu")
	)
	(gr_poly
		(pts
			(xy 112.649 -34.417) (xy 112.649 -34.07156) (xy 112.632739 -34.042075) (xy 112.606334 -33.98013)
			(xy 112.587219 -33.915562) (xy 112.575649 -33.849226) (xy 112.571775 -33.782) (xy 112.575649 -33.714774)
			(xy 112.587219 -33.648438) (xy 112.606334 -33.58387) (xy 112.632739 -33.521925) (xy 112.649 -33.49244)
			(xy 112.649 -32.51581) (xy 112.648534 -32.501174) (xy 112.640257 -32.473097) (xy 112.624353 -32.448524)
			(xy 112.602128 -32.429475) (xy 112.575411 -32.417517) (xy 112.546399 -32.413633) (xy 112.517477 -32.418142)
			(xy 112.491025 -32.430674) (xy 112.479836 -32.440118) (xy 112.453774 -32.462728) (xy 112.397268 -32.502324)
			(xy 112.336495 -32.534995) (xy 112.272299 -32.560289) (xy 112.205574 -32.577852) (xy 112.137245 -32.587441)
			(xy 112.068262 -32.588924) (xy 111.999585 -32.582279) (xy 111.932166 -32.567598) (xy 111.866944 -32.545086)
			(xy 111.804823 -32.515055) (xy 111.746668 -32.477923) (xy 111.693287 -32.434206) (xy 111.645421 -32.384511)
			(xy 111.603735 -32.329528) (xy 111.568808 -32.270023) (xy 111.541127 -32.20682) (xy 111.521075 -32.1408)
			(xy 111.508932 -32.072878) (xy 111.504865 -32.004) (xy 111.508932 -31.935122) (xy 111.521075 -31.8672)
			(xy 111.541127 -31.80118) (xy 111.568808 -31.737977) (xy 111.603735 -31.678472) (xy 111.645421 -31.623489)
			(xy 111.693287 -31.573794) (xy 111.746668 -31.530077) (xy 111.804823 -31.492945) (xy 111.866944 -31.462914)
			(xy 111.932166 -31.440402) (xy 111.999585 -31.425721) (xy 112.068262 -31.419076) (xy 112.137245 -31.420559)
			(xy 112.205574 -31.430148) (xy 112.272299 -31.447711) (xy 112.336495 -31.473005) (xy 112.397268 -31.505676)
			(xy 112.453774 -31.545272) (xy 112.479836 -31.567882) (xy 112.491062 -31.577251) (xy 112.517496 -31.589723)
			(xy 112.54638 -31.594196) (xy 112.575347 -31.590301) (xy 112.602025 -31.57836) (xy 112.624226 -31.559349)
			(xy 112.640131 -31.534827) (xy 112.648437 -31.506804) (xy 112.649 -31.49219) (xy 112.649 -30.353)
			(xy 114.3 -28.702) (xy 114.3 -23.4696) (xy 114.280608 -23.440339) (xy 114.24819 -23.378075) (xy 114.223459 -23.312378)
			(xy 114.206771 -23.244192) (xy 114.198367 -23.174499) (xy 114.198367 -23.104301) (xy 114.206771 -23.034608)
			(xy 114.223459 -22.966422) (xy 114.24819 -22.900725) (xy 114.280608 -22.838461) (xy 114.3 -22.8092)
			(xy 114.3 -19.7866) (xy 112.0902 -17.5768) (xy 107.8992 -17.5768) (xy 107.315 -18.161) (xy 107.315 -18.923)
			(xy 107.569 -19.177) (xy 109.093 -19.177) (xy 111.887 -21.971) (xy 111.887 -23.173427) (xy 112.801387 -23.173427)
			(xy 112.801387 -23.105373) (xy 112.809287 -23.03778) (xy 112.824981 -22.971562) (xy 112.848257 -22.907613)
			(xy 112.878799 -22.846798) (xy 112.916195 -22.789941) (xy 112.959938 -22.737809) (xy 113.009438 -22.691108)
			(xy 113.064025 -22.65047) (xy 113.122961 -22.616443) (xy 113.185449 -22.589489) (xy 113.250643 -22.569971)
			(xy 113.317662 -22.558153) (xy 113.3856 -22.554197) (xy 113.453538 -22.558153) (xy 113.520557 -22.569971)
			(xy 113.585751 -22.589489) (xy 113.648239 -22.616443) (xy 113.707175 -22.65047) (xy 113.761762 -22.691108)
			(xy 113.811262 -22.737809) (xy 113.855005 -22.789941) (xy 113.892401 -22.846798) (xy 113.922943 -22.907613)
			(xy 113.946219 -22.971562) (xy 113.961913 -23.03778) (xy 113.969813 -23.105373) (xy 113.970308 -23.1394)
			(xy 113.969813 -23.173427) (xy 113.961913 -23.24102) (xy 113.946219 -23.307238) (xy 113.922943 -23.371187)
			(xy 113.892401 -23.432002) (xy 113.855005 -23.488859) (xy 113.811262 -23.540991) (xy 113.761762 -23.587692)
			(xy 113.707175 -23.62833) (xy 113.648239 -23.662357) (xy 113.585751 -23.689311) (xy 113.520557 -23.708829)
			(xy 113.453538 -23.720647) (xy 113.3856 -23.724604) (xy 113.317662 -23.720647) (xy 113.250643 -23.708829)
			(xy 113.185449 -23.689311) (xy 113.122961 -23.662357) (xy 113.064025 -23.62833) (xy 113.009438 -23.587692)
			(xy 112.959938 -23.540991) (xy 112.916195 -23.488859) (xy 112.878799 -23.432002) (xy 112.848257 -23.371187)
			(xy 112.824981 -23.307238) (xy 112.809287 -23.24102) (xy 112.801387 -23.173427) (xy 111.887 -23.173427)
			(xy 111.887 -27.178) (xy 110.672381 -28.392619) (xy 111.391433 -28.392619) (xy 111.391433 -28.324565)
			(xy 111.399333 -28.256972) (xy 111.415027 -28.190754) (xy 111.438303 -28.126805) (xy 111.468845 -28.06599)
			(xy 111.506241 -28.009133) (xy 111.549984 -27.957001) (xy 111.599484 -27.9103) (xy 111.654071 -27.869662)
			(xy 111.713007 -27.835635) (xy 111.775495 -27.808681) (xy 111.840689 -27.789163) (xy 111.907708 -27.777345)
			(xy 111.975646 -27.773389) (xy 112.043584 -27.777345) (xy 112.110603 -27.789163) (xy 112.175797 -27.808681)
			(xy 112.238285 -27.835635) (xy 112.297221 -27.869662) (xy 112.351808 -27.9103) (xy 112.401308 -27.957001)
			(xy 112.445051 -28.009133) (xy 112.482447 -28.06599) (xy 112.512989 -28.126805) (xy 112.536265 -28.190754)
			(xy 112.551959 -28.256972) (xy 112.559859 -28.324565) (xy 112.560354 -28.358592) (xy 112.559859 -28.392619)
			(xy 112.551959 -28.460212) (xy 112.536265 -28.52643) (xy 112.512989 -28.590379) (xy 112.482447 -28.651194)
			(xy 112.445051 -28.708051) (xy 112.401308 -28.760183) (xy 112.351808 -28.806884) (xy 112.297221 -28.847522)
			(xy 112.238285 -28.881549) (xy 112.175797 -28.908503) (xy 112.110603 -28.928021) (xy 112.043584 -28.939839)
			(xy 111.975646 -28.943796) (xy 111.907708 -28.939839) (xy 111.840689 -28.928021) (xy 111.775495 -28.908503)
			(xy 111.713007 -28.881549) (xy 111.654071 -28.847522) (xy 111.599484 -28.806884) (xy 111.549984 -28.760183)
			(xy 111.506241 -28.708051) (xy 111.468845 -28.651194) (xy 111.438303 -28.590379) (xy 111.415027 -28.52643)
			(xy 111.399333 -28.460212) (xy 111.391433 -28.392619) (xy 110.672381 -28.392619) (xy 109.601 -29.464)
			(xy 109.601 -30.617922) (xy 109.626862 -30.63871) (xy 109.674196 -30.685214) (xy 109.71596 -30.736778)
			(xy 109.751618 -30.792739) (xy 109.780712 -30.852377) (xy 109.802866 -30.914925) (xy 109.817796 -30.979579)
			(xy 109.82531 -31.045509) (xy 109.825312 -31.111864) (xy 109.8178 -31.177794) (xy 109.802873 -31.242449)
			(xy 109.780722 -31.304998) (xy 109.751632 -31.364638) (xy 109.715976 -31.4206) (xy 109.674214 -31.472166)
			(xy 109.626882 -31.518672) (xy 109.601 -31.539434) (xy 109.601 -34.417) (xy 109.855 -34.671) (xy 112.395 -34.671)
		)
		(stroke
			(width 0)
			(type solid)
		)
		(fill yes)
		(layer "In2.Cu")
		(net "P12V_HDD27")
	)
	(gr_arc
		(start 0 -370.000022)
		(mid 0.292893 -370.707127)
		(end 0.999998 -371.00002)
		(stroke
			(width 2.54)
			(type default)
		)
		(layer "In3.Cu")
	)
	(gr_line
		(start 0 -0.999998)
		(end 0 -370.000022)
		(stroke
			(width 2.54)
			(type default)
		)
		(layer "In3.Cu")
	)
	(gr_line
		(start 0.999998 -371.00002)
		(end 1.999996 -371.00002)
		(stroke
			(width 2.54)
			(type default)
		)
		(layer "In3.Cu")
	)
	(gr_arc
		(start 0.999998 0)
		(mid 0.292893 -0.292893)
		(end 0 -0.999998)
		(stroke
			(width 2.54)
			(type default)
		)
		(layer "In3.Cu")
	)
	(gr_arc
		(start 2.999994 -384.999992)
		(mid 3.292887 -385.707097)
		(end 3.999992 -385.99999)
		(stroke
			(width 2.54)
			(type default)
		)
		(layer "In3.Cu")
	)
	(gr_arc
		(start 2.999994 -372.000018)
		(mid 2.707101 -371.292912)
		(end 1.999996 -371.00002)
		(stroke
			(width 2.54)
			(type default)
		)
		(layer "In3.Cu")
	)
	(gr_line
		(start 2.999994 -372.000018)
		(end 2.999994 -384.999992)
		(stroke
			(width 2.54)
			(type default)
		)
		(layer "In3.Cu")
	)
	(gr_line
		(start 3.999992 -385.99999)
		(end 15.249906 -385.99999)
		(stroke
			(width 2.54)
			(type default)
		)
		(layer "In3.Cu")
	)
	(gr_arc
		(start 15.249906 -385.99999)
		(mid 15.957011 -385.707097)
		(end 16.249904 -384.999992)
		(stroke
			(width 2.54)
			(type default)
		)
		(layer "In3.Cu")
	)
	(gr_line
		(start 16.249904 -384.999992)
		(end 16.249904 -383.29997)
		(stroke
			(width 2.54)
			(type default)
		)
		(layer "In3.Cu")
	)
	(gr_arc
		(start 17.249902 -382.299972)
		(mid 16.542795 -382.592864)
		(end 16.249904 -383.29997)
		(stroke
			(width 2.54)
			(type default)
		)
		(layer "In3.Cu")
	)
	(gr_line
		(start 17.249902 -382.299972)
		(end 23.750016 -382.299972)
		(stroke
			(width 2.54)
			(type default)
		)
		(layer "In3.Cu")
	)
	(gr_arc
		(start 24.750014 -384.999992)
		(mid 25.042907 -385.707097)
		(end 25.750012 -385.99999)
		(stroke
			(width 2.54)
			(type default)
		)
		(layer "In3.Cu")
	)
	(gr_arc
		(start 24.750014 -383.29997)
		(mid 24.457112 -382.592878)
		(end 23.750016 -382.299972)
		(stroke
			(width 2.54)
			(type default)
		)
		(layer "In3.Cu")
	)
	(gr_line
		(start 24.750014 -383.29997)
		(end 24.750014 -384.999992)
		(stroke
			(width 2.54)
			(type default)
		)
		(layer "In3.Cu")
	)
	(gr_line
		(start 25.750012 -385.99999)
		(end 71.300086 -385.99999)
		(stroke
			(width 2.54)
			(type default)
		)
		(layer "In3.Cu")
	)
	(gr_arc
		(start 32.023812 -249.385074)
		(mid 32.508952 -249.870214)
		(end 32.994092 -249.385074)
		(stroke
			(width 0.2)
			(type default)
		)
		(layer "In3.Cu")
	)
	(gr_line
		(start 32.023812 -248.115074)
		(end 32.023812 -249.385074)
		(stroke
			(width 0.2)
			(type default)
		)
		(layer "In3.Cu")
	)
	(gr_arc
		(start 32.023812 -134.384796)
		(mid 32.508825 -134.87019)
		(end 32.994092 -134.38505)
		(stroke
			(width 0.2)
			(type default)
		)
		(layer "In3.Cu")
	)
	(gr_line
		(start 32.023812 -133.11505)
		(end 32.023812 -134.384796)
		(stroke
			(width 0.2)
			(type default)
		)
		(layer "In3.Cu")
	)
	(gr_arc
		(start 32.023812 -19.385026)
		(mid 32.508952 -19.870166)
		(end 32.994092 -19.385026)
		(stroke
			(width 0.2)
			(type default)
		)
		(layer "In3.Cu")
	)
	(gr_line
		(start 32.023812 -18.115026)
		(end 32.023812 -19.385026)
		(stroke
			(width 0.2)
			(type default)
		)
		(layer "In3.Cu")
	)
	(gr_line
		(start 32.994092 -249.385074)
		(end 32.994092 -248.115328)
		(stroke
			(width 0.2)
			(type default)
		)
		(layer "In3.Cu")
	)
	(gr_arc
		(start 32.994092 -248.115328)
		(mid 32.509079 -247.629934)
		(end 32.023812 -248.115074)
		(stroke
			(width 0.2)
			(type default)
		)
		(layer "In3.Cu")
	)
	(gr_line
		(start 32.994092 -134.38505)
		(end 32.994092 -133.11505)
		(stroke
			(width 0.2)
			(type default)
		)
		(layer "In3.Cu")
	)
	(gr_arc
		(start 32.994092 -133.11505)
		(mid 32.508952 -132.62991)
		(end 32.023812 -133.11505)
		(stroke
			(width 0.2)
			(type default)
		)
		(layer "In3.Cu")
	)
	(gr_line
		(start 32.994092 -19.385026)
		(end 32.994092 -18.11528)
		(stroke
			(width 0.2)
			(type default)
		)
		(layer "In3.Cu")
	)
	(gr_arc
		(start 32.994092 -18.11528)
		(mid 32.509079 -17.629886)
		(end 32.023812 -18.115026)
		(stroke
			(width 0.2)
			(type default)
		)
		(layer "In3.Cu")
	)
	(gr_arc
		(start 33.800542 -245.56212)
		(mid 34.285555 -246.047514)
		(end 34.770822 -245.562374)
		(stroke
			(width 0.2)
			(type default)
		)
		(layer "In3.Cu")
	)
	(gr_line
		(start 33.800542 -244.419374)
		(end 33.800542 -245.56212)
		(stroke
			(width 0.2)
			(type default)
		)
		(layer "In3.Cu")
	)
	(gr_arc
		(start 33.800542 -130.56235)
		(mid 34.285682 -131.04749)
		(end 34.770822 -130.56235)
		(stroke
			(width 0.2)
			(type default)
		)
		(layer "In3.Cu")
	)
	(gr_line
		(start 33.800542 -129.41935)
		(end 33.800542 -130.56235)
		(stroke
			(width 0.2)
			(type default)
		)
		(layer "In3.Cu")
	)
	(gr_arc
		(start 33.800542 -15.562326)
		(mid 34.285682 -16.047466)
		(end 34.770822 -15.562326)
		(stroke
			(width 0.2)
			(type default)
		)
		(layer "In3.Cu")
	)
	(gr_line
		(start 33.800542 -14.419326)
		(end 33.800542 -15.562326)
		(stroke
			(width 0.2)
			(type default)
		)
		(layer "In3.Cu")
	)
	(gr_line
		(start 34.770822 -245.562374)
		(end 34.770822 -244.419374)
		(stroke
			(width 0.2)
			(type default)
		)
		(layer "In3.Cu")
	)
	(gr_arc
		(start 34.770822 -244.419374)
		(mid 34.285682 -243.934234)
		(end 33.800542 -244.419374)
		(stroke
			(width 0.2)
			(type default)
		)
		(layer "In3.Cu")
	)
	(gr_line
		(start 34.770822 -130.56235)
		(end 34.770822 -129.419604)
		(stroke
			(width 0.2)
			(type default)
		)
		(layer "In3.Cu")
	)
	(gr_arc
		(start 34.770822 -129.419604)
		(mid 34.285809 -128.93421)
		(end 33.800542 -129.41935)
		(stroke
			(width 0.2)
			(type default)
		)
		(layer "In3.Cu")
	)
	(gr_line
		(start 34.770822 -15.562326)
		(end 34.770822 -14.41958)
		(stroke
			(width 0.2)
			(type default)
		)
		(layer "In3.Cu")
	)
	(gr_arc
		(start 34.770822 -14.41958)
		(mid 34.285809 -13.934186)
		(end 33.800542 -14.419326)
		(stroke
			(width 0.2)
			(type default)
		)
		(layer "In3.Cu")
	)
	(gr_arc
		(start 63.57366 -249.385074)
		(mid 64.0588 -249.870214)
		(end 64.54394 -249.385074)
		(stroke
			(width 0.2)
			(type default)
		)
		(layer "In3.Cu")
	)
	(gr_line
		(start 63.57366 -248.115074)
		(end 63.57366 -249.385074)
		(stroke
			(width 0.2)
			(type default)
		)
		(layer "In3.Cu")
	)
	(gr_arc
		(start 63.57366 -134.384796)
		(mid 64.058673 -134.87019)
		(end 64.54394 -134.38505)
		(stroke
			(width 0.2)
			(type default)
		)
		(layer "In3.Cu")
	)
	(gr_line
		(start 63.57366 -133.11505)
		(end 63.57366 -134.384796)
		(stroke
			(width 0.2)
			(type default)
		)
		(layer "In3.Cu")
	)
	(gr_arc
		(start 63.57366 -19.385026)
		(mid 64.0588 -19.870166)
		(end 64.54394 -19.385026)
		(stroke
			(width 0.2)
			(type default)
		)
		(layer "In3.Cu")
	)
	(gr_line
		(start 63.57366 -18.115026)
		(end 63.57366 -19.385026)
		(stroke
			(width 0.2)
			(type default)
		)
		(layer "In3.Cu")
	)
	(gr_line
		(start 64.54394 -249.385074)
		(end 64.54394 -248.115328)
		(stroke
			(width 0.2)
			(type default)
		)
		(layer "In3.Cu")
	)
	(gr_arc
		(start 64.54394 -248.115328)
		(mid 64.058927 -247.629934)
		(end 63.57366 -248.115074)
		(stroke
			(width 0.2)
			(type default)
		)
		(layer "In3.Cu")
	)
	(gr_line
		(start 64.54394 -134.38505)
		(end 64.54394 -133.11505)
		(stroke
			(width 0.2)
			(type default)
		)
		(layer "In3.Cu")
	)
	(gr_arc
		(start 64.54394 -133.11505)
		(mid 64.0588 -132.62991)
		(end 63.57366 -133.11505)
		(stroke
			(width 0.2)
			(type default)
		)
		(layer "In3.Cu")
	)
	(gr_line
		(start 64.54394 -19.385026)
		(end 64.54394 -18.11528)
		(stroke
			(width 0.2)
			(type default)
		)
		(layer "In3.Cu")
	)
	(gr_arc
		(start 64.54394 -18.11528)
		(mid 64.058927 -17.629886)
		(end 63.57366 -18.115026)
		(stroke
			(width 0.2)
			(type default)
		)
		(layer "In3.Cu")
	)
	(gr_arc
		(start 65.35039 -245.56212)
		(mid 65.835403 -246.047514)
		(end 66.32067 -245.562374)
		(stroke
			(width 0.2)
			(type default)
		)
		(layer "In3.Cu")
	)
	(gr_line
		(start 65.35039 -244.419374)
		(end 65.35039 -245.56212)
		(stroke
			(width 0.2)
			(type default)
		)
		(layer "In3.Cu")
	)
	(gr_arc
		(start 65.35039 -130.56235)
		(mid 65.83553 -131.04749)
		(end 66.32067 -130.56235)
		(stroke
			(width 0.2)
			(type default)
		)
		(layer "In3.Cu")
	)
	(gr_line
		(start 65.35039 -129.41935)
		(end 65.35039 -130.56235)
		(stroke
			(width 0.2)
			(type default)
		)
		(layer "In3.Cu")
	)
	(gr_arc
		(start 65.35039 -15.562326)
		(mid 65.83553 -16.047466)
		(end 66.32067 -15.562326)
		(stroke
			(width 0.2)
			(type default)
		)
		(layer "In3.Cu")
	)
	(gr_line
		(start 65.35039 -14.419326)
		(end 65.35039 -15.562326)
		(stroke
			(width 0.2)
			(type default)
		)
		(layer "In3.Cu")
	)
	(gr_line
		(start 66.32067 -245.562374)
		(end 66.32067 -244.419374)
		(stroke
			(width 0.2)
			(type default)
		)
		(layer "In3.Cu")
	)
	(gr_arc
		(start 66.32067 -244.419374)
		(mid 65.83553 -243.934234)
		(end 65.35039 -244.419374)
		(stroke
			(width 0.2)
			(type default)
		)
		(layer "In3.Cu")
	)
	(gr_line
		(start 66.32067 -130.56235)
		(end 66.32067 -129.419604)
		(stroke
			(width 0.2)
			(type default)
		)
		(layer "In3.Cu")
	)
	(gr_arc
		(start 66.32067 -129.419604)
		(mid 65.835657 -128.93421)
		(end 65.35039 -129.41935)
		(stroke
			(width 0.2)
			(type default)
		)
		(layer "In3.Cu")
	)
	(gr_line
		(start 66.32067 -15.562326)
		(end 66.32067 -14.41958)
		(stroke
			(width 0.2)
			(type default)
		)
		(layer "In3.Cu")
	)
	(gr_arc
		(start 66.32067 -14.41958)
		(mid 65.835657 -13.934186)
		(end 65.35039 -14.419326)
		(stroke
			(width 0.2)
			(type default)
		)
		(layer "In3.Cu")
	)
	(gr_arc
		(start 71.300086 -385.99999)
		(mid 72.007191 -385.707097)
		(end 72.300084 -384.999992)
		(stroke
			(width 2.54)
			(type default)
		)
		(layer "In3.Cu")
	)
	(gr_line
		(start 72.300084 -384.999992)
		(end 72.300084 -381)
		(stroke
			(width 2.54)
			(type default)
		)
		(layer "In3.Cu")
	)
	(gr_arc
		(start 73.300082 -380.000002)
		(mid 72.592988 -380.292901)
		(end 72.300084 -381)
		(stroke
			(width 2.54)
			(type default)
		)
		(layer "In3.Cu")
	)
	(gr_line
		(start 73.300082 -380.000002)
		(end 125.299978 -380.000002)
		(stroke
			(width 2.54)
			(type default)
		)
		(layer "In3.Cu")
	)
	(gr_arc
		(start 95.123762 -249.385074)
		(mid 95.608902 -249.870214)
		(end 96.094042 -249.385074)
		(stroke
			(width 0.2)
			(type default)
		)
		(layer "In3.Cu")
	)
	(gr_line
		(start 95.123762 -248.115074)
		(end 95.123762 -249.385074)
		(stroke
			(width 0.2)
			(type default)
		)
		(layer "In3.Cu")
	)
	(gr_arc
		(start 95.123762 -134.384796)
		(mid 95.608775 -134.87019)
		(end 96.094042 -134.38505)
		(stroke
			(width 0.2)
			(type default)
		)
		(layer "In3.Cu")
	)
	(gr_line
		(start 95.123762 -133.11505)
		(end 95.123762 -134.384796)
		(stroke
			(width 0.2)
			(type default)
		)
		(layer "In3.Cu")
	)
	(gr_arc
		(start 95.123762 -19.385026)
		(mid 95.608902 -19.870166)
		(end 96.094042 -19.385026)
		(stroke
			(width 0.2)
			(type default)
		)
		(layer "In3.Cu")
	)
	(gr_line
		(start 95.123762 -18.115026)
		(end 95.123762 -19.385026)
		(stroke
			(width 0.2)
			(type default)
		)
		(layer "In3.Cu")
	)
	(gr_line
		(start 96.094042 -249.385074)
		(end 96.094042 -248.115328)
		(stroke
			(width 0.2)
			(type default)
		)
		(layer "In3.Cu")
	)
	(gr_arc
		(start 96.094042 -248.115328)
		(mid 95.609029 -247.629934)
		(end 95.123762 -248.115074)
		(stroke
			(width 0.2)
			(type default)
		)
		(layer "In3.Cu")
	)
	(gr_line
		(start 96.094042 -134.38505)
		(end 96.094042 -133.11505)
		(stroke
			(width 0.2)
			(type default)
		)
		(layer "In3.Cu")
	)
	(gr_arc
		(start 96.094042 -133.11505)
		(mid 95.608902 -132.62991)
		(end 95.123762 -133.11505)
		(stroke
			(width 0.2)
			(type default)
		)
		(layer "In3.Cu")
	)
	(gr_line
		(start 96.094042 -19.385026)
		(end 96.094042 -18.11528)
		(stroke
			(width 0.2)
			(type default)
		)
		(layer "In3.Cu")
	)
	(gr_arc
		(start 96.094042 -18.11528)
		(mid 95.609029 -17.629886)
		(end 95.123762 -18.115026)
		(stroke
			(width 0.2)
			(type default)
		)
		(layer "In3.Cu")
	)
	(gr_arc
		(start 96.900492 -245.56212)
		(mid 97.385505 -246.047514)
		(end 97.870772 -245.562374)
		(stroke
			(width 0.2)
			(type default)
		)
		(layer "In3.Cu")
	)
	(gr_line
		(start 96.900492 -244.419374)
		(end 96.900492 -245.56212)
		(stroke
			(width 0.2)
			(type default)
		)
		(layer "In3.Cu")
	)
	(gr_arc
		(start 96.900492 -130.56235)
		(mid 97.385632 -131.04749)
		(end 97.870772 -130.56235)
		(stroke
			(width 0.2)
			(type default)
		)
		(layer "In3.Cu")
	)
	(gr_line
		(start 96.900492 -129.41935)
		(end 96.900492 -130.56235)
		(stroke
			(width 0.2)
			(type default)
		)
		(layer "In3.Cu")
	)
	(gr_arc
		(start 96.900492 -15.562326)
		(mid 97.385632 -16.047466)
		(end 97.870772 -15.562326)
		(stroke
			(width 0.2)
			(type default)
		)
		(layer "In3.Cu")
	)
	(gr_line
		(start 96.900492 -14.419326)
		(end 96.900492 -15.562326)
		(stroke
			(width 0.2)
			(type default)
		)
		(layer "In3.Cu")
	)
	(gr_line
		(start 97.870772 -245.562374)
		(end 97.870772 -244.419374)
		(stroke
			(width 0.2)
			(type default)
		)
		(layer "In3.Cu")
	)
	(gr_arc
		(start 97.870772 -244.419374)
		(mid 97.385632 -243.934234)
		(end 96.900492 -244.419374)
		(stroke
			(width 0.2)
			(type default)
		)
		(layer "In3.Cu")
	)
	(gr_line
		(start 97.870772 -130.56235)
		(end 97.870772 -129.419604)
		(stroke
			(width 0.2)
			(type default)
		)
		(layer "In3.Cu")
	)
	(gr_arc
		(start 97.870772 -129.419604)
		(mid 97.385759 -128.93421)
		(end 96.900492 -129.41935)
		(stroke
			(width 0.2)
			(type default)
		)
		(layer "In3.Cu")
	)
	(gr_line
		(start 97.870772 -15.562326)
		(end 97.870772 -14.41958)
		(stroke
			(width 0.2)
			(type default)
		)
		(layer "In3.Cu")
	)
	(gr_arc
		(start 97.870772 -14.41958)
		(mid 97.385759 -13.934186)
		(end 96.900492 -14.419326)
		(stroke
			(width 0.2)
			(type default)
		)
		(layer "In3.Cu")
	)
	(gr_line
		(start 102.743 -346.202)
		(end 103.632 -347.091)
		(stroke
			(width 0.381)
			(type default)
		)
		(layer "In3.Cu")
	)
	(gr_line
		(start 102.743 -332.613)
		(end 102.743 -346.202)
		(stroke
			(width 0.381)
			(type default)
		)
		(layer "In3.Cu")
	)
	(gr_line
		(start 103.632 -364.269782)
		(end 104.043988 -364.68177)
		(stroke
			(width 0.381)
			(type default)
		)
		(layer "In3.Cu")
	)
	(gr_line
		(start 103.632 -347.091)
		(end 103.632 -364.269782)
		(stroke
			(width 0.381)
			(type default)
		)
		(layer "In3.Cu")
	)
	(gr_line
		(start 104.043988 -364.68177)
		(end 109.290612 -364.68177)
		(stroke
			(width 0.381)
			(type default)
		)
		(layer "In3.Cu")
	)
	(gr_line
		(start 104.146604 -331.209396)
		(end 102.743 -332.613)
		(stroke
			(width 0.381)
			(type default)
		)
		(layer "In3.Cu")
	)
	(gr_line
		(start 109.290612 -364.68177)
		(end 112.207802 -361.76458)
		(stroke
			(width 0.381)
			(type default)
		)
		(layer "In3.Cu")
	)
	(gr_line
		(start 112.207802 -361.76458)
		(end 123.074938 -361.76458)
		(stroke
			(width 0.381)
			(type default)
		)
		(layer "In3.Cu")
	)
	(gr_line
		(start 123.074938 -361.76458)
		(end 126.445518 -358.394)
		(stroke
			(width 0.381)
			(type default)
		)
		(layer "In3.Cu")
	)
	(gr_arc
		(start 126.299976 -384.999992)
		(mid 126.592869 -385.707097)
		(end 127.299974 -385.99999)
		(stroke
			(width 2.54)
			(type default)
		)
		(layer "In3.Cu")
	)
	(gr_arc
		(start 126.299976 -381)
		(mid 126.007082 -380.292902)
		(end 125.299978 -380.000002)
		(stroke
			(width 2.54)
			(type default)
		)
		(layer "In3.Cu")
	)
	(gr_line
		(start 126.299976 -381)
		(end 126.299976 -384.999992)
		(stroke
			(width 2.54)
			(type default)
		)
		(layer "In3.Cu")
	)
	(gr_line
		(start 126.445518 -358.394)
		(end 160.782 -358.394)
		(stroke
			(width 0.381)
			(type default)
		)
		(layer "In3.Cu")
	)
	(gr_arc
		(start 126.67361 -249.385074)
		(mid 127.15875 -249.870214)
		(end 127.64389 -249.385074)
		(stroke
			(width 0.2)
			(type default)
		)
		(layer "In3.Cu")
	)
	(gr_line
		(start 126.67361 -248.115074)
		(end 126.67361 -249.385074)
		(stroke
			(width 0.2)
			(type default)
		)
		(layer "In3.Cu")
	)
	(gr_arc
		(start 126.67361 -134.384796)
		(mid 127.158623 -134.87019)
		(end 127.64389 -134.38505)
		(stroke
			(width 0.2)
			(type default)
		)
		(layer "In3.Cu")
	)
	(gr_line
		(start 126.67361 -133.11505)
		(end 126.67361 -134.384796)
		(stroke
			(width 0.2)
			(type default)
		)
		(layer "In3.Cu")
	)
	(gr_arc
		(start 126.67361 -19.385026)
		(mid 127.15875 -19.870166)
		(end 127.64389 -19.385026)
		(stroke
			(width 0.2)
			(type default)
		)
		(layer "In3.Cu")
	)
	(gr_line
		(start 126.67361 -18.115026)
		(end 126.67361 -19.385026)
		(stroke
			(width 0.2)
			(type default)
		)
		(layer "In3.Cu")
	)
	(gr_line
		(start 127.299974 -385.99999)
		(end 172.850048 -385.99999)
		(stroke
			(width 2.54)
			(type default)
		)
		(layer "In3.Cu")
	)
	(gr_line
		(start 127.64389 -249.385074)
		(end 127.64389 -248.115328)
		(stroke
			(width 0.2)
			(type default)
		)
		(layer "In3.Cu")
	)
	(gr_arc
		(start 127.64389 -248.115328)
		(mid 127.158877 -247.629934)
		(end 126.67361 -248.115074)
		(stroke
			(width 0.2)
			(type default)
		)
		(layer "In3.Cu")
	)
	(gr_line
		(start 127.64389 -134.38505)
		(end 127.64389 -133.11505)
		(stroke
			(width 0.2)
			(type default)
		)
		(layer "In3.Cu")
	)
	(gr_arc
		(start 127.64389 -133.11505)
		(mid 127.15875 -132.62991)
		(end 126.67361 -133.11505)
		(stroke
			(width 0.2)
			(type default)
		)
		(layer "In3.Cu")
	)
	(gr_line
		(start 127.64389 -19.385026)
		(end 127.64389 -18.11528)
		(stroke
			(width 0.2)
			(type default)
		)
		(layer "In3.Cu")
	)
	(gr_arc
		(start 127.64389 -18.11528)
		(mid 127.158877 -17.629886)
		(end 126.67361 -18.115026)
		(stroke
			(width 0.2)
			(type default)
		)
		(layer "In3.Cu")
	)
	(gr_arc
		(start 128.45034 -245.56212)
		(mid 128.935353 -246.047514)
		(end 129.42062 -245.562374)
		(stroke
			(width 0.2)
			(type default)
		)
		(layer "In3.Cu")
	)
	(gr_line
		(start 128.45034 -244.419374)
		(end 128.45034 -245.56212)
		(stroke
			(width 0.2)
			(type default)
		)
		(layer "In3.Cu")
	)
	(gr_arc
		(start 128.45034 -130.56235)
		(mid 128.93548 -131.04749)
		(end 129.42062 -130.56235)
		(stroke
			(width 0.2)
			(type default)
		)
		(layer "In3.Cu")
	)
	(gr_line
		(start 128.45034 -129.41935)
		(end 128.45034 -130.56235)
		(stroke
			(width 0.2)
			(type default)
		)
		(layer "In3.Cu")
	)
	(gr_arc
		(start 128.45034 -15.562326)
		(mid 128.93548 -16.047466)
		(end 129.42062 -15.562326)
		(stroke
			(width 0.2)
			(type default)
		)
		(layer "In3.Cu")
	)
	(gr_line
		(start 128.45034 -14.419326)
		(end 128.45034 -15.562326)
		(stroke
			(width 0.2)
			(type default)
		)
		(layer "In3.Cu")
	)
	(gr_line
		(start 129.42062 -245.562374)
		(end 129.42062 -244.419374)
		(stroke
			(width 0.2)
			(type default)
		)
		(layer "In3.Cu")
	)
	(gr_arc
		(start 129.42062 -244.419374)
		(mid 128.93548 -243.934234)
		(end 128.45034 -244.419374)
		(stroke
			(width 0.2)
			(type default)
		)
		(layer "In3.Cu")
	)
	(gr_line
		(start 129.42062 -130.56235)
		(end 129.42062 -129.419604)
		(stroke
			(width 0.2)
			(type default)
		)
		(layer "In3.Cu")
	)
	(gr_arc
		(start 129.42062 -129.419604)
		(mid 128.935607 -128.93421)
		(end 128.45034 -129.41935)
		(stroke
			(width 0.2)
			(type default)
		)
		(layer "In3.Cu")
	)
	(gr_line
		(start 129.42062 -15.562326)
		(end 129.42062 -14.41958)
		(stroke
			(width 0.2)
			(type default)
		)
		(layer "In3.Cu")
	)
	(gr_arc
		(start 129.42062 -14.41958)
		(mid 128.935607 -13.934186)
		(end 128.45034 -14.419326)
		(stroke
			(width 0.2)
			(type default)
		)
		(layer "In3.Cu")
	)
	(gr_line
		(start 151.263604 -331.209396)
		(end 104.146604 -331.209396)
		(stroke
			(width 0.381)
			(type default)
		)
		(layer "In3.Cu")
	)
	(gr_line
		(start 151.638 -330.835)
		(end 151.263604 -331.209396)
		(stroke
			(width 0.381)
			(type default)
		)
		(layer "In3.Cu")
	)
	(gr_line
		(start 151.638 -327.66)
		(end 151.638 -330.835)
		(stroke
			(width 0.381)
			(type default)
		)
		(layer "In3.Cu")
	)
	(gr_line
		(start 152.273 -327.025)
		(end 151.638 -327.66)
		(stroke
			(width 0.381)
			(type default)
		)
		(layer "In3.Cu")
	)
	(gr_line
		(start 157.353 -327.025)
		(end 152.273 -327.025)
		(stroke
			(width 0.381)
			(type default)
		)
		(layer "In3.Cu")
	)
	(gr_line
		(start 157.607 -328.549)
		(end 157.607 -327.279)
		(stroke
			(width 0.381)
			(type default)
		)
		(layer "In3.Cu")
	)
	(gr_line
		(start 157.607 -327.279)
		(end 157.353 -327.025)
		(stroke
			(width 0.381)
			(type default)
		)
		(layer "In3.Cu")
	)
	(gr_line
		(start 157.988 -328.93)
		(end 157.607 -328.549)
		(stroke
			(width 0.381)
			(type default)
		)
		(layer "In3.Cu")
	)
	(gr_arc
		(start 158.223712 -249.38482)
		(mid 158.708725 -249.870214)
		(end 159.193992 -249.385074)
		(stroke
			(width 0.2)
			(type default)
		)
		(layer "In3.Cu")
	)
	(gr_line
		(start 158.223712 -248.115074)
		(end 158.223712 -249.38482)
		(stroke
			(width 0.2)
			(type default)
		)
		(layer "In3.Cu")
	)
	(gr_arc
		(start 158.223712 -134.384796)
		(mid 158.708725 -134.87019)
		(end 159.193992 -134.38505)
		(stroke
			(width 0.2)
			(type default)
		)
		(layer "In3.Cu")
	)
	(gr_line
		(start 158.223712 -133.11505)
		(end 158.223712 -134.384796)
		(stroke
			(width 0.2)
			(type default)
		)
		(layer "In3.Cu")
	)
	(gr_arc
		(start 158.223712 -19.385026)
		(mid 158.708852 -19.870166)
		(end 159.193992 -19.385026)
		(stroke
			(width 0.2)
			(type default)
		)
		(layer "In3.Cu")
	)
	(gr_line
		(start 158.223712 -18.115026)
		(end 158.223712 -19.385026)
		(stroke
			(width 0.2)
			(type default)
		)
		(layer "In3.Cu")
	)
	(gr_line
		(start 159.193992 -249.385074)
		(end 159.193992 -248.115074)
		(stroke
			(width 0.2)
			(type default)
		)
		(layer "In3.Cu")
	)
	(gr_arc
		(start 159.193992 -248.115074)
		(mid 158.708852 -247.629934)
		(end 158.223712 -248.115074)
		(stroke
			(width 0.2)
			(type default)
		)
		(layer "In3.Cu")
	)
	(gr_line
		(start 159.193992 -134.38505)
		(end 159.193992 -133.11505)
		(stroke
			(width 0.2)
			(type default)
		)
		(layer "In3.Cu")
	)
	(gr_arc
		(start 159.193992 -133.11505)
		(mid 158.708852 -132.62991)
		(end 158.223712 -133.11505)
		(stroke
			(width 0.2)
			(type default)
		)
		(layer "In3.Cu")
	)
	(gr_line
		(start 159.193992 -19.385026)
		(end 159.193992 -18.11528)
		(stroke
			(width 0.2)
			(type default)
		)
		(layer "In3.Cu")
	)
	(gr_arc
		(start 159.193992 -18.11528)
		(mid 158.708979 -17.629886)
		(end 158.223712 -18.115026)
		(stroke
			(width 0.2)
			(type default)
		)
		(layer "In3.Cu")
	)
	(gr_arc
		(start 160.000442 -245.56212)
		(mid 160.485455 -246.047514)
		(end 160.970722 -245.562374)
		(stroke
			(width 0.2)
			(type default)
		)
		(layer "In3.Cu")
	)
	(gr_line
		(start 160.000442 -244.419374)
		(end 160.000442 -245.56212)
		(stroke
			(width 0.2)
			(type default)
		)
		(layer "In3.Cu")
	)
	(gr_arc
		(start 160.000442 -130.56235)
		(mid 160.485582 -131.04749)
		(end 160.970722 -130.56235)
		(stroke
			(width 0.2)
			(type default)
		)
		(layer "In3.Cu")
	)
	(gr_line
		(start 160.000442 -129.41935)
		(end 160.000442 -130.56235)
		(stroke
			(width 0.2)
			(type default)
		)
		(layer "In3.Cu")
	)
	(gr_arc
		(start 160.000442 -15.562326)
		(mid 160.485582 -16.047466)
		(end 160.970722 -15.562326)
		(stroke
			(width 0.2)
			(type default)
		)
		(layer "In3.Cu")
	)
	(gr_line
		(start 160.000442 -14.419326)
		(end 160.000442 -15.562326)
		(stroke
			(width 0.2)
			(type default)
		)
		(layer "In3.Cu")
	)
	(gr_line
		(start 160.6042 -358.2162)
		(end 160.6042 -329.1078)
		(stroke
			(width 0.2)
			(type default)
		)
		(layer "In3.Cu")
	)
	(gr_line
		(start 160.6042 -329.1078)
		(end 166.3573 -329.1078)
		(stroke
			(width 0.2)
			(type default)
		)
		(layer "In3.Cu")
	)
	(gr_line
		(start 160.782 -358.394)
		(end 160.782 -328.93)
		(stroke
			(width 0.381)
			(type default)
		)
		(layer "In3.Cu")
	)
	(gr_line
		(start 160.782 -328.93)
		(end 157.988 -328.93)
		(stroke
			(width 0.381)
			(type default)
		)
		(layer "In3.Cu")
	)
	(gr_line
		(start 160.970722 -245.562374)
		(end 160.970722 -244.419374)
		(stroke
			(width 0.2)
			(type default)
		)
		(layer "In3.Cu")
	)
	(gr_arc
		(start 160.970722 -244.419374)
		(mid 160.485582 -243.934234)
		(end 160.000442 -244.419374)
		(stroke
			(width 0.2)
			(type default)
		)
		(layer "In3.Cu")
	)
	(gr_line
		(start 160.970722 -130.56235)
		(end 160.970722 -129.419604)
		(stroke
			(width 0.2)
			(type default)
		)
		(layer "In3.Cu")
	)
	(gr_arc
		(start 160.970722 -129.419604)
		(mid 160.485709 -128.93421)
		(end 160.000442 -129.41935)
		(stroke
			(width 0.2)
			(type default)
		)
		(layer "In3.Cu")
	)
	(gr_line
		(start 160.970722 -15.562326)
		(end 160.970722 -14.41958)
		(stroke
			(width 0.2)
			(type default)
		)
		(layer "In3.Cu")
	)
	(gr_arc
		(start 160.970722 -14.41958)
		(mid 160.485709 -13.934186)
		(end 160.000442 -14.419326)
		(stroke
			(width 0.2)
			(type default)
		)
		(layer "In3.Cu")
	)
	(gr_line
		(start 166.2049 -358.394)
		(end 166.2049 -328.93)
		(stroke
			(width 0.381)
			(type default)
		)
		(layer "In3.Cu")
	)
	(gr_line
		(start 166.3573 -358.2162)
		(end 160.6042 -358.2162)
		(stroke
			(width 0.2)
			(type default)
		)
		(layer "In3.Cu")
	)
	(gr_line
		(start 166.3573 -329.1078)
		(end 166.3573 -358.2162)
		(stroke
			(width 0.2)
			(type default)
		)
		(layer "In3.Cu")
	)
	(gr_line
		(start 166.5859 -358.394)
		(end 166.2049 -358.394)
		(stroke
			(width 0.381)
			(type default)
		)
		(layer "In3.Cu")
	)
	(gr_arc
		(start 172.850048 -385.99999)
		(mid 173.557153 -385.707097)
		(end 173.850046 -384.999992)
		(stroke
			(width 2.54)
			(type default)
		)
		(layer "In3.Cu")
	)
	(gr_line
		(start 173.850046 -384.999992)
		(end 173.850046 -383.29997)
		(stroke
			(width 2.54)
			(type default)
		)
		(layer "In3.Cu")
	)
	(gr_arc
		(start 174.850044 -382.299972)
		(mid 174.1429 -382.592847)
		(end 173.850046 -383.29997)
		(stroke
			(width 2.54)
			(type default)
		)
		(layer "In3.Cu")
	)
	(gr_line
		(start 174.850044 -382.299972)
		(end 181.349904 -382.299972)
		(stroke
			(width 2.54)
			(type default)
		)
		(layer "In3.Cu")
	)
	(gr_arc
		(start 182.349902 -384.999992)
		(mid 182.642795 -385.707097)
		(end 183.3499 -385.99999)
		(stroke
			(width 2.54)
			(type default)
		)
		(layer "In3.Cu")
	)
	(gr_arc
		(start 182.349902 -383.29997)
		(mid 182.056999 -382.592883)
		(end 181.349904 -382.299972)
		(stroke
			(width 2.54)
			(type default)
		)
		(layer "In3.Cu")
	)
	(gr_line
		(start 182.349902 -383.29997)
		(end 182.349902 -384.999992)
		(stroke
			(width 2.54)
			(type default)
		)
		(layer "In3.Cu")
	)
	(gr_line
		(start 183.3499 -385.99999)
		(end 197.000114 -385.99999)
		(stroke
			(width 2.54)
			(type default)
		)
		(layer "In3.Cu")
	)
	(gr_arc
		(start 189.773814 -249.385074)
		(mid 190.258954 -249.870214)
		(end 190.744094 -249.385074)
		(stroke
			(width 0.2)
			(type default)
		)
		(layer "In3.Cu")
	)
	(gr_line
		(start 189.773814 -248.115074)
		(end 189.773814 -249.385074)
		(stroke
			(width 0.2)
			(type default)
		)
		(layer "In3.Cu")
	)
	(gr_arc
		(start 189.773814 -134.38505)
		(mid 190.258954 -134.87019)
		(end 190.744094 -134.38505)
		(stroke
			(width 0.2)
			(type default)
		)
		(layer "In3.Cu")
	)
	(gr_line
		(start 189.773814 -133.11505)
		(end 189.773814 -134.38505)
		(stroke
			(width 0.2)
			(type default)
		)
		(layer "In3.Cu")
	)
	(gr_arc
		(start 189.773814 -19.385026)
		(mid 190.258954 -19.870166)
		(end 190.744094 -19.385026)
		(stroke
			(width 0.2)
			(type default)
		)
		(layer "In3.Cu")
	)
	(gr_line
		(start 189.773814 -18.115026)
		(end 189.773814 -19.385026)
		(stroke
			(width 0.2)
			(type default)
		)
		(layer "In3.Cu")
	)
	(gr_line
		(start 190.744094 -249.385074)
		(end 190.744094 -248.115328)
		(stroke
			(width 0.2)
			(type default)
		)
		(layer "In3.Cu")
	)
	(gr_arc
		(start 190.744094 -248.115328)
		(mid 190.259081 -247.629934)
		(end 189.773814 -248.115074)
		(stroke
			(width 0.2)
			(type default)
		)
		(layer "In3.Cu")
	)
	(gr_line
		(start 190.744094 -134.38505)
		(end 190.744094 -133.115304)
		(stroke
			(width 0.2)
			(type default)
		)
		(layer "In3.Cu")
	)
	(gr_arc
		(start 190.744094 -133.115304)
		(mid 190.259081 -132.62991)
		(end 189.773814 -133.11505)
		(stroke
			(width 0.2)
			(type default)
		)
		(layer "In3.Cu")
	)
	(gr_line
		(start 190.744094 -19.385026)
		(end 190.744094 -18.11528)
		(stroke
			(width 0.2)
			(type default)
		)
		(layer "In3.Cu")
	)
	(gr_arc
		(start 190.744094 -18.11528)
		(mid 190.259081 -17.629886)
		(end 189.773814 -18.115026)
		(stroke
			(width 0.2)
			(type default)
		)
		(layer "In3.Cu")
	)
	(gr_arc
		(start 191.550544 -245.56212)
		(mid 192.035557 -246.047514)
		(end 192.520824 -245.562374)
		(stroke
			(width 0.2)
			(type default)
		)
		(layer "In3.Cu")
	)
	(gr_line
		(start 191.550544 -244.419374)
		(end 191.550544 -245.56212)
		(stroke
			(width 0.2)
			(type default)
		)
		(layer "In3.Cu")
	)
	(gr_arc
		(start 191.550544 -130.56235)
		(mid 192.035684 -131.04749)
		(end 192.520824 -130.56235)
		(stroke
			(width 0.2)
			(type default)
		)
		(layer "In3.Cu")
	)
	(gr_line
		(start 191.550544 -129.41935)
		(end 191.550544 -130.56235)
		(stroke
			(width 0.2)
			(type default)
		)
		(layer "In3.Cu")
	)
	(gr_arc
		(start 191.550544 -15.562326)
		(mid 192.035684 -16.047466)
		(end 192.520824 -15.562326)
		(stroke
			(width 0.2)
			(type default)
		)
		(layer "In3.Cu")
	)
	(gr_line
		(start 191.550544 -14.419326)
		(end 191.550544 -15.562326)
		(stroke
			(width 0.2)
			(type default)
		)
		(layer "In3.Cu")
	)
	(gr_line
		(start 192.520824 -245.562374)
		(end 192.520824 -244.419374)
		(stroke
			(width 0.2)
			(type default)
		)
		(layer "In3.Cu")
	)
	(gr_arc
		(start 192.520824 -244.419374)
		(mid 192.035684 -243.934234)
		(end 191.550544 -244.419374)
		(stroke
			(width 0.2)
			(type default)
		)
		(layer "In3.Cu")
	)
	(gr_line
		(start 192.520824 -130.56235)
		(end 192.520824 -129.419604)
		(stroke
			(width 0.2)
			(type default)
		)
		(layer "In3.Cu")
	)
	(gr_arc
		(start 192.520824 -129.419604)
		(mid 192.035811 -128.93421)
		(end 191.550544 -129.41935)
		(stroke
			(width 0.2)
			(type default)
		)
		(layer "In3.Cu")
	)
	(gr_line
		(start 192.520824 -15.562326)
		(end 192.520824 -14.41958)
		(stroke
			(width 0.2)
			(type default)
		)
		(layer "In3.Cu")
	)
	(gr_arc
		(start 192.520824 -14.41958)
		(mid 192.035811 -13.934186)
		(end 191.550544 -14.419326)
		(stroke
			(width 0.2)
			(type default)
		)
		(layer "In3.Cu")
	)
	(gr_line
		(start 196.482716 -249.64009)
		(end 198.556626 -251.714)
		(stroke
			(width 0.381)
			(type default)
		)
		(layer "In3.Cu")
	)
	(gr_line
		(start 196.482716 -153.529284)
		(end 196.482716 -249.64009)
		(stroke
			(width 0.381)
			(type default)
		)
		(layer "In3.Cu")
	)
	(gr_arc
		(start 197.000114 -385.99999)
		(mid 197.707219 -385.707097)
		(end 198.000112 -384.999992)
		(stroke
			(width 2.54)
			(type default)
		)
		(layer "In3.Cu")
	)
	(gr_line
		(start 198.000112 -384.999992)
		(end 198.000112 -381)
		(stroke
			(width 2.54)
			(type default)
		)
		(layer "In3.Cu")
	)
	(gr_line
		(start 198.000112 0)
		(end 0.999998 0)
		(stroke
			(width 2.54)
			(type default)
		)
		(layer "In3.Cu")
	)
	(gr_line
		(start 198.12 -151.892)
		(end 196.482716 -153.529284)
		(stroke
			(width 0.381)
			(type default)
		)
		(layer "In3.Cu")
	)
	(gr_line
		(start 198.556626 -251.714)
		(end 230.251 -251.714)
		(stroke
			(width 0.381)
			(type default)
		)
		(layer "In3.Cu")
	)
	(gr_arc
		(start 199.00011 -380.000002)
		(mid 198.292998 -380.292891)
		(end 198.000112 -381)
		(stroke
			(width 2.54)
			(type default)
		)
		(layer "In3.Cu")
	)
	(gr_line
		(start 199.00011 -380.000002)
		(end 251.000006 -380.000002)
		(stroke
			(width 2.54)
			(type default)
		)
		(layer "In3.Cu")
	)
	(gr_line
		(start 199.00011 -47.200058)
		(end 199.00011 -0.999998)
		(stroke
			(width 2.54)
			(type default)
		)
		(layer "In3.Cu")
	)
	(gr_arc
		(start 199.00011 -47.200058)
		(mid 199.292988 -47.907188)
		(end 200.000108 -48.200056)
		(stroke
			(width 2.54)
			(type default)
		)
		(layer "In3.Cu")
	)
	(gr_arc
		(start 199.00011 -0.999998)
		(mid 198.707217 -0.292893)
		(end 198.000112 0)
		(stroke
			(width 2.54)
			(type default)
		)
		(layer "In3.Cu")
	)
	(gr_line
		(start 206.000096 -48.200056)
		(end 200.000108 -48.200056)
		(stroke
			(width 2.54)
			(type default)
		)
		(layer "In3.Cu")
	)
	(gr_line
		(start 207.000094 -61.999876)
		(end 207.000094 -49.200054)
		(stroke
			(width 2.54)
			(type default)
		)
		(layer "In3.Cu")
	)
	(gr_arc
		(start 207.000094 -61.999876)
		(mid 207.292978 -62.707)
		(end 208.000092 -62.999874)
		(stroke
			(width 2.54)
			(type default)
		)
		(layer "In3.Cu")
	)
	(gr_arc
		(start 207.000094 -49.200054)
		(mid 206.707201 -48.492949)
		(end 206.000096 -48.200056)
		(stroke
			(width 2.54)
			(type default)
		)
		(layer "In3.Cu")
	)
	(gr_line
		(start 208.614772 -63.961772)
		(end 208.198974 -63.546228)
		(stroke
			(width 0.381)
			(type default)
		)
		(layer "In3.Cu")
	)
	(gr_line
		(start 208.788 -64.516)
		(end 208.8134 -64.4906)
		(stroke
			(width 0.381)
			(type default)
		)
		(layer "In3.Cu")
	)
	(gr_line
		(start 208.808828 -64.520826)
		(end 208.8134 -64.516254)
		(stroke
			(width 0.381)
			(type default)
		)
		(layer "In3.Cu")
	)
	(gr_line
		(start 208.8134 -81.2038)
		(end 209.4738 -81.8642)
		(stroke
			(width 0.381)
			(type default)
		)
		(layer "In3.Cu")
	)
	(gr_line
		(start 208.8134 -64.5414)
		(end 207.899 -63.627)
		(stroke
			(width 0.381)
			(type default)
		)
		(layer "In3.Cu")
	)
	(gr_line
		(start 208.8134 -64.5414)
		(end 208.8134 -64.4906)
		(stroke
			(width 0.381)
			(type default)
		)
		(layer "In3.Cu")
	)
	(gr_line
		(start 208.8134 -64.526668)
		(end 208.8134 -81.2038)
		(stroke
			(width 0.381)
			(type default)
		)
		(layer "In3.Cu")
	)
	(gr_line
		(start 208.8134 -64.516254)
		(end 208.8134 -64.069214)
		(stroke
			(width 0.381)
			(type default)
		)
		(layer "In3.Cu")
	)
	(gr_line
		(start 208.8134 -64.4906)
		(end 208.8134 -62.437518)
		(stroke
			(width 0.381)
			(type default)
		)
		(layer "In3.Cu")
	)
	(gr_arc
		(start 208.820766 -64.508888)
		(mid 208.815369 -64.51706)
		(end 208.8134 -64.526668)
		(stroke
			(width 0.381)
			(type default)
		)
		(layer "In3.Cu")
	)
	(gr_arc
		(start 208.820766 -64.051434)
		(mid 208.8153 -64.059584)
		(end 208.8134 -64.069214)
		(stroke
			(width 0.381)
			(type default)
		)
		(layer "In3.Cu")
	)
	(gr_line
		(start 208.820766 -64.051434)
		(end 209.325972 -63.545974)
		(stroke
			(width 0.381)
			(type default)
		)
		(layer "In3.Cu")
	)
	(gr_line
		(start 209.224372 -64.105028)
		(end 208.820766 -64.508888)
		(stroke
			(width 0.381)
			(type default)
		)
		(layer "In3.Cu")
	)
	(gr_circle
		(center 209.242406 -64.123062)
		(end 209.267806 -64.123062)
		(stroke
			(width 0.381)
			(type default)
		)
		(fill no)
		(layer "In3.Cu")
	)
	(gr_arc
		(start 209.451448 -78.999842)
		(mid 210.000088 -79.548482)
		(end 210.548728 -78.999842)
		(stroke
			(width 0.2)
			(type default)
		)
		(layer "In3.Cu")
	)
	(gr_line
		(start 209.451448 -77.600048)
		(end 209.451448 -78.999842)
		(stroke
			(width 0.2)
			(type default)
		)
		(layer "In3.Cu")
	)
	(gr_arc
		(start 209.451448 -75.399646)
		(mid 209.999961 -75.94854)
		(end 210.548728 -75.3999)
		(stroke
			(width 0.2)
			(type default)
		)
		(layer "In3.Cu")
	)
	(gr_line
		(start 209.451448 -73.999852)
		(end 209.451448 -75.399646)
		(stroke
			(width 0.2)
			(type default)
		)
		(layer "In3.Cu")
	)
	(gr_arc
		(start 209.451448 -71.799704)
		(mid 209.999961 -72.348598)
		(end 210.548728 -71.799958)
		(stroke
			(width 0.2)
			(type default)
		)
		(layer "In3.Cu")
	)
	(gr_line
		(start 209.451448 -70.39991)
		(end 209.451448 -71.799704)
		(stroke
			(width 0.2)
			(type default)
		)
		(layer "In3.Cu")
	)
	(gr_line
		(start 209.4738 -81.8642)
		(end 223.3676 -81.8642)
		(stroke
			(width 0.381)
			(type default)
		)
		(layer "In3.Cu")
	)
	(gr_line
		(start 209.6897 -63.6397)
		(end 209.224372 -64.105028)
		(stroke
			(width 0.381)
			(type default)
		)
		(layer "In3.Cu")
	)
	(gr_line
		(start 210.548728 -78.999842)
		(end 210.548728 -77.600302)
		(stroke
			(width 0.2)
			(type default)
		)
		(layer "In3.Cu")
	)
	(gr_arc
		(start 210.548728 -77.600302)
		(mid 210.000215 -77.051408)
		(end 209.451448 -77.600048)
		(stroke
			(width 0.2)
			(type default)
		)
		(layer "In3.Cu")
	)
	(gr_line
		(start 210.548728 -75.3999)
		(end 210.548728 -73.999852)
		(stroke
			(width 0.2)
			(type default)
		)
		(layer "In3.Cu")
	)
	(gr_arc
		(start 210.548728 -73.999852)
		(mid 210.000088 -73.451212)
		(end 209.451448 -73.999852)
		(stroke
			(width 0.2)
			(type default)
		)
		(layer "In3.Cu")
	)
	(gr_line
		(start 210.548728 -71.799958)
		(end 210.548728 -70.39991)
		(stroke
			(width 0.2)
			(type default)
		)
		(layer "In3.Cu")
	)
	(gr_arc
		(start 210.548728 -70.39991)
		(mid 210.000088 -69.85127)
		(end 209.451448 -70.39991)
		(stroke
			(width 0.2)
			(type default)
		)
		(layer "In3.Cu")
	)
	(gr_arc
		(start 211.251546 -77.799692)
		(mid 211.800059 -78.348586)
		(end 212.348826 -77.799946)
		(stroke
			(width 0.2)
			(type default)
		)
		(layer "In3.Cu")
	)
	(gr_line
		(start 211.251546 -76.399898)
		(end 211.251546 -77.799692)
		(stroke
			(width 0.2)
			(type default)
		)
		(layer "In3.Cu")
	)
	(gr_arc
		(start 211.251546 -66.999612)
		(mid 211.800059 -67.548506)
		(end 212.348826 -66.999866)
		(stroke
			(width 0.2)
			(type default)
		)
		(layer "In3.Cu")
	)
	(gr_line
		(start 211.251546 -65.600072)
		(end 211.251546 -66.999612)
		(stroke
			(width 0.2)
			(type default)
		)
		(layer "In3.Cu")
	)
	(gr_line
		(start 212.348826 -77.799946)
		(end 212.348826 -76.399898)
		(stroke
			(width 0.2)
			(type default)
		)
		(layer "In3.Cu")
	)
	(gr_arc
		(start 212.348826 -76.399898)
		(mid 211.800186 -75.851258)
		(end 211.251546 -76.399898)
		(stroke
			(width 0.2)
			(type default)
		)
		(layer "In3.Cu")
	)
	(gr_line
		(start 212.348826 -66.999866)
		(end 212.348826 -65.600072)
		(stroke
			(width 0.2)
			(type default)
		)
		(layer "In3.Cu")
	)
	(gr_arc
		(start 212.348826 -65.600072)
		(mid 211.800186 -65.051432)
		(end 211.251546 -65.600072)
		(stroke
			(width 0.2)
			(type default)
		)
		(layer "In3.Cu")
	)
	(gr_arc
		(start 213.05139 -78.999842)
		(mid 213.60003 -79.548482)
		(end 214.14867 -78.999842)
		(stroke
			(width 0.2)
			(type default)
		)
		(layer "In3.Cu")
	)
	(gr_line
		(start 213.05139 -77.600048)
		(end 213.05139 -78.999842)
		(stroke
			(width 0.2)
			(type default)
		)
		(layer "In3.Cu")
	)
	(gr_arc
		(start 213.05139 -71.799704)
		(mid 213.599903 -72.348598)
		(end 214.14867 -71.799958)
		(stroke
			(width 0.2)
			(type default)
		)
		(layer "In3.Cu")
	)
	(gr_line
		(start 213.05139 -70.39991)
		(end 213.05139 -71.799704)
		(stroke
			(width 0.2)
			(type default)
		)
		(layer "In3.Cu")
	)
	(gr_line
		(start 213.106 -151.892)
		(end 198.12 -151.892)
		(stroke
			(width 0.381)
			(type default)
		)
		(layer "In3.Cu")
	)
	(gr_line
		(start 214.122 -150.876)
		(end 213.106 -151.892)
		(stroke
			(width 0.381)
			(type default)
		)
		(layer "In3.Cu")
	)
	(gr_line
		(start 214.122 -106.426)
		(end 214.122 -150.876)
		(stroke
			(width 0.381)
			(type default)
		)
		(layer "In3.Cu")
	)
	(gr_line
		(start 214.14867 -78.999842)
		(end 214.14867 -77.600302)
		(stroke
			(width 0.2)
			(type default)
		)
		(layer "In3.Cu")
	)
	(gr_arc
		(start 214.14867 -77.600302)
		(mid 213.600157 -77.051408)
		(end 213.05139 -77.600048)
		(stroke
			(width 0.2)
			(type default)
		)
		(layer "In3.Cu")
	)
	(gr_line
		(start 214.14867 -71.799958)
		(end 214.14867 -70.39991)
		(stroke
			(width 0.2)
			(type default)
		)
		(layer "In3.Cu")
	)
	(gr_arc
		(start 214.14867 -70.39991)
		(mid 213.60003 -69.85127)
		(end 213.05139 -70.39991)
		(stroke
			(width 0.2)
			(type default)
		)
		(layer "In3.Cu")
	)
	(gr_arc
		(start 214.851488 -77.799692)
		(mid 215.400001 -78.348586)
		(end 215.948768 -77.799946)
		(stroke
			(width 0.2)
			(type default)
		)
		(layer "In3.Cu")
	)
	(gr_line
		(start 214.851488 -76.399898)
		(end 214.851488 -77.799692)
		(stroke
			(width 0.2)
			(type default)
		)
		(layer "In3.Cu")
	)
	(gr_arc
		(start 214.851488 -66.999612)
		(mid 215.400001 -67.548506)
		(end 215.948768 -66.999866)
		(stroke
			(width 0.2)
			(type default)
		)
		(layer "In3.Cu")
	)
	(gr_line
		(start 214.851488 -65.600072)
		(end 214.851488 -66.999612)
		(stroke
			(width 0.2)
			(type default)
		)
		(layer "In3.Cu")
	)
	(gr_line
		(start 215.9 -104.648)
		(end 214.122 -106.426)
		(stroke
			(width 0.381)
			(type default)
		)
		(layer "In3.Cu")
	)
	(gr_line
		(start 215.948768 -77.799946)
		(end 215.948768 -76.399898)
		(stroke
			(width 0.2)
			(type default)
		)
		(layer "In3.Cu")
	)
	(gr_arc
		(start 215.948768 -76.399898)
		(mid 215.400128 -75.851258)
		(end 214.851488 -76.399898)
		(stroke
			(width 0.2)
			(type default)
		)
		(layer "In3.Cu")
	)
	(gr_line
		(start 215.948768 -66.999866)
		(end 215.948768 -65.600072)
		(stroke
			(width 0.2)
			(type default)
		)
		(layer "In3.Cu")
	)
	(gr_arc
		(start 215.948768 -65.600072)
		(mid 215.400128 -65.051432)
		(end 214.851488 -65.600072)
		(stroke
			(width 0.2)
			(type default)
		)
		(layer "In3.Cu")
	)
	(gr_arc
		(start 216.651332 -78.999842)
		(mid 217.199972 -79.548482)
		(end 217.748612 -78.999842)
		(stroke
			(width 0.2)
			(type default)
		)
		(layer "In3.Cu")
	)
	(gr_line
		(start 216.651332 -77.600048)
		(end 216.651332 -78.999842)
		(stroke
			(width 0.2)
			(type default)
		)
		(layer "In3.Cu")
	)
	(gr_arc
		(start 216.651332 -71.799704)
		(mid 217.199845 -72.348598)
		(end 217.748612 -71.799958)
		(stroke
			(width 0.2)
			(type default)
		)
		(layer "In3.Cu")
	)
	(gr_line
		(start 216.651332 -70.39991)
		(end 216.651332 -71.799704)
		(stroke
			(width 0.2)
			(type default)
		)
		(layer "In3.Cu")
	)
	(gr_line
		(start 217.748612 -78.999842)
		(end 217.748612 -77.600302)
		(stroke
			(width 0.2)
			(type default)
		)
		(layer "In3.Cu")
	)
	(gr_arc
		(start 217.748612 -77.600302)
		(mid 217.200099 -77.051408)
		(end 216.651332 -77.600048)
		(stroke
			(width 0.2)
			(type default)
		)
		(layer "In3.Cu")
	)
	(gr_line
		(start 217.748612 -71.799958)
		(end 217.748612 -70.39991)
		(stroke
			(width 0.2)
			(type default)
		)
		(layer "In3.Cu")
	)
	(gr_arc
		(start 217.748612 -70.39991)
		(mid 217.199972 -69.85127)
		(end 216.651332 -70.39991)
		(stroke
			(width 0.2)
			(type default)
		)
		(layer "In3.Cu")
	)
	(gr_arc
		(start 218.45143 -77.799692)
		(mid 218.999943 -78.348586)
		(end 219.54871 -77.799946)
		(stroke
			(width 0.2)
			(type default)
		)
		(layer "In3.Cu")
	)
	(gr_line
		(start 218.45143 -76.399898)
		(end 218.45143 -77.799692)
		(stroke
			(width 0.2)
			(type default)
		)
		(layer "In3.Cu")
	)
	(gr_arc
		(start 218.45143 -66.999612)
		(mid 218.999943 -67.548506)
		(end 219.54871 -66.999866)
		(stroke
			(width 0.2)
			(type default)
		)
		(layer "In3.Cu")
	)
	(gr_line
		(start 218.45143 -65.600072)
		(end 218.45143 -66.999612)
		(stroke
			(width 0.2)
			(type default)
		)
		(layer "In3.Cu")
	)
	(gr_line
		(start 218.948 -130.048)
		(end 218.948 -111.379)
		(stroke
			(width 0.381)
			(type default)
		)
		(layer "In3.Cu")
	)
	(gr_line
		(start 218.948 -111.379)
		(end 219.71 -110.617)
		(stroke
			(width 0.381)
			(type default)
		)
		(layer "In3.Cu")
	)
	(gr_line
		(start 219.54871 -77.799946)
		(end 219.54871 -76.399898)
		(stroke
			(width 0.2)
			(type default)
		)
		(layer "In3.Cu")
	)
	(gr_arc
		(start 219.54871 -76.399898)
		(mid 219.00007 -75.851258)
		(end 218.45143 -76.399898)
		(stroke
			(width 0.2)
			(type default)
		)
		(layer "In3.Cu")
	)
	(gr_line
		(start 219.54871 -66.999866)
		(end 219.54871 -65.600072)
		(stroke
			(width 0.2)
			(type default)
		)
		(layer "In3.Cu")
	)
	(gr_arc
		(start 219.54871 -65.600072)
		(mid 219.00007 -65.051432)
		(end 218.45143 -65.600072)
		(stroke
			(width 0.2)
			(type default)
		)
		(layer "In3.Cu")
	)
	(gr_line
		(start 219.6592 -130.7592)
		(end 218.948 -130.048)
		(stroke
			(width 0.381)
			(type default)
		)
		(layer "In3.Cu")
	)
	(gr_line
		(start 219.71 -110.617)
		(end 228.902006 -110.617)
		(stroke
			(width 0.381)
			(type default)
		)
		(layer "In3.Cu")
	)
	(gr_arc
		(start 220.251528 -78.999842)
		(mid 220.800168 -79.548482)
		(end 221.348808 -78.999842)
		(stroke
			(width 0.2)
			(type default)
		)
		(layer "In3.Cu")
	)
	(gr_line
		(start 220.251528 -77.600048)
		(end 220.251528 -78.999842)
		(stroke
			(width 0.2)
			(type default)
		)
		(layer "In3.Cu")
	)
	(gr_arc
		(start 220.251528 -71.799704)
		(mid 220.800041 -72.348598)
		(end 221.348808 -71.799958)
		(stroke
			(width 0.2)
			(type default)
		)
		(layer "In3.Cu")
	)
	(gr_line
		(start 220.251528 -70.39991)
		(end 220.251528 -71.799704)
		(stroke
			(width 0.2)
			(type default)
		)
		(layer "In3.Cu")
	)
	(gr_line
		(start 221.348808 -78.999842)
		(end 221.348808 -77.600302)
		(stroke
			(width 0.2)
			(type default)
		)
		(layer "In3.Cu")
	)
	(gr_arc
		(start 221.348808 -77.600302)
		(mid 220.800295 -77.051408)
		(end 220.251528 -77.600048)
		(stroke
			(width 0.2)
			(type default)
		)
		(layer "In3.Cu")
	)
	(gr_line
		(start 221.348808 -71.799958)
		(end 221.348808 -70.39991)
		(stroke
			(width 0.2)
			(type default)
		)
		(layer "In3.Cu")
	)
	(gr_arc
		(start 221.348808 -70.39991)
		(mid 220.800168 -69.85127)
		(end 220.251528 -70.39991)
		(stroke
			(width 0.2)
			(type default)
		)
		(layer "In3.Cu")
	)
	(gr_arc
		(start 222.051372 -77.799692)
		(mid 222.599885 -78.348586)
		(end 223.148652 -77.799946)
		(stroke
			(width 0.2)
			(type default)
		)
		(layer "In3.Cu")
	)
	(gr_line
		(start 222.051372 -76.399898)
		(end 222.051372 -77.799692)
		(stroke
			(width 0.2)
			(type default)
		)
		(layer "In3.Cu")
	)
	(gr_arc
		(start 222.051372 -66.999866)
		(mid 222.600012 -67.548506)
		(end 223.148652 -66.999866)
		(stroke
			(width 0.2)
			(type default)
		)
		(layer "In3.Cu")
	)
	(gr_line
		(start 222.051372 -65.600072)
		(end 222.051372 -66.999866)
		(stroke
			(width 0.2)
			(type default)
		)
		(layer "In3.Cu")
	)
	(gr_line
		(start 223.148652 -77.799946)
		(end 223.148652 -76.399898)
		(stroke
			(width 0.2)
			(type default)
		)
		(layer "In3.Cu")
	)
	(gr_arc
		(start 223.148652 -76.399898)
		(mid 222.600012 -75.851258)
		(end 222.051372 -76.399898)
		(stroke
			(width 0.2)
			(type default)
		)
		(layer "In3.Cu")
	)
	(gr_line
		(start 223.148652 -66.999866)
		(end 223.148652 -65.600326)
		(stroke
			(width 0.2)
			(type default)
		)
		(layer "In3.Cu")
	)
	(gr_arc
		(start 223.148652 -65.600326)
		(mid 222.600139 -65.051432)
		(end 222.051372 -65.600072)
		(stroke
			(width 0.2)
			(type default)
		)
		(layer "In3.Cu")
	)
	(gr_line
		(start 223.3676 -81.8642)
		(end 224.0026 -81.2292)
		(stroke
			(width 0.381)
			(type default)
		)
		(layer "In3.Cu")
	)
	(gr_line
		(start 224.0026 -81.2292)
		(end 224.0026 -62.999874)
		(stroke
			(width 0.381)
			(type default)
		)
		(layer "In3.Cu")
	)
	(gr_line
		(start 224.0026 -64.389)
		(end 224.0026 -64.3636)
		(stroke
			(width 0.381)
			(type default)
		)
		(layer "In3.Cu")
	)
	(gr_line
		(start 224.0026 -64.3636)
		(end 224.0026 -62.488318)
		(stroke
			(width 0.381)
			(type default)
		)
		(layer "In3.Cu")
	)
	(gr_line
		(start 224.0026 -64.3636)
		(end 224.8662 -63.5)
		(stroke
			(width 0.381)
			(type default)
		)
		(layer "In3.Cu")
	)
	(gr_line
		(start 224.0026 -64.1096)
		(end 223.565974 -63.673228)
		(stroke
			(width 0.381)
			(type default)
		)
		(layer "In3.Cu")
	)
	(gr_line
		(start 224.0026 -62.999874)
		(end 208.000092 -62.999874)
		(stroke
			(width 2.54)
			(type default)
		)
		(layer "In3.Cu")
	)
	(gr_line
		(start 224.489772 -63.673228)
		(end 224.074228 -64.089026)
		(stroke
			(width 0.381)
			(type default)
		)
		(layer "In3.Cu")
	)
	(gr_line
		(start 228.902006 -110.617)
		(end 236.1946 -103.324406)
		(stroke
			(width 0.381)
			(type default)
		)
		(layer "In3.Cu")
	)
	(gr_line
		(start 229.235 -104.648)
		(end 215.9 -104.648)
		(stroke
			(width 0.381)
			(type default)
		)
		(layer "In3.Cu")
	)
	(gr_line
		(start 230.251 -251.714)
		(end 232.837482 -249.127518)
		(stroke
			(width 0.381)
			(type default)
		)
		(layer "In3.Cu")
	)
	(gr_line
		(start 230.5558 -81.2546)
		(end 232.156 -82.8548)
		(stroke
			(width 0.381)
			(type default)
		)
		(layer "In3.Cu")
	)
	(gr_line
		(start 230.5558 -76.4794)
		(end 230.5558 -81.2546)
		(stroke
			(width 0.381)
			(type default)
		)
		(layer "In3.Cu")
	)
	(gr_line
		(start 231.1654 -75.8698)
		(end 230.5558 -76.4794)
		(stroke
			(width 0.381)
			(type default)
		)
		(layer "In3.Cu")
	)
	(gr_line
		(start 232.156 -101.727)
		(end 229.235 -104.648)
		(stroke
			(width 0.381)
			(type default)
		)
		(layer "In3.Cu")
	)
	(gr_line
		(start 232.156 -82.8548)
		(end 232.156 -101.727)
		(stroke
			(width 0.381)
			(type default)
		)
		(layer "In3.Cu")
	)
	(gr_line
		(start 232.837482 -249.127518)
		(end 232.837482 -239.575594)
		(stroke
			(width 0.381)
			(type default)
		)
		(layer "In3.Cu")
	)
	(gr_line
		(start 232.837482 -239.575594)
		(end 239.063276 -233.3498)
		(stroke
			(width 0.381)
			(type default)
		)
		(layer "In3.Cu")
	)
	(gr_line
		(start 234.1626 -75.8698)
		(end 231.1654 -75.8698)
		(stroke
			(width 0.381)
			(type default)
		)
		(layer "In3.Cu")
	)
	(gr_line
		(start 236.1946 -103.324406)
		(end 236.1946 -77.9018)
		(stroke
			(width 0.381)
			(type default)
		)
		(layer "In3.Cu")
	)
	(gr_line
		(start 236.1946 -77.9018)
		(end 234.1626 -75.8698)
		(stroke
			(width 0.381)
			(type default)
		)
		(layer "In3.Cu")
	)
	(gr_line
		(start 239.063276 -233.3498)
		(end 265.83513 -233.3498)
		(stroke
			(width 0.381)
			(type default)
		)
		(layer "In3.Cu")
	)
	(gr_arc
		(start 252.000004 -384.999992)
		(mid 252.292897 -385.707097)
		(end 253.000002 -385.99999)
		(stroke
			(width 2.54)
			(type default)
		)
		(layer "In3.Cu")
	)
	(gr_arc
		(start 252.000004 -381)
		(mid 251.707112 -380.292893)
		(end 251.000006 -380.000002)
		(stroke
			(width 2.54)
			(type default)
		)
		(layer "In3.Cu")
	)
	(gr_line
		(start 252.000004 -381)
		(end 252.000004 -384.999992)
		(stroke
			(width 2.54)
			(type default)
		)
		(layer "In3.Cu")
	)
	(gr_line
		(start 253.000002 -385.99999)
		(end 269.035784 -385.99999)
		(stroke
			(width 2.54)
			(type default)
		)
		(layer "In3.Cu")
	)
	(gr_line
		(start 265.83513 -233.3498)
		(end 267.6398 -231.54513)
		(stroke
			(width 0.381)
			(type default)
		)
		(layer "In3.Cu")
	)
	(gr_line
		(start 266.875006 -130.7592)
		(end 219.6592 -130.7592)
		(stroke
			(width 0.381)
			(type default)
		)
		(layer "In3.Cu")
	)
	(gr_line
		(start 267.6398 -231.54513)
		(end 267.6398 -131.523994)
		(stroke
			(width 0.381)
			(type default)
		)
		(layer "In3.Cu")
	)
	(gr_line
		(start 267.6398 -131.523994)
		(end 266.875006 -130.7592)
		(stroke
			(width 0.381)
			(type default)
		)
		(layer "In3.Cu")
	)
	(gr_line
		(start 267.999972 -62.999874)
		(end 224.0026 -62.999874)
		(stroke
			(width 2.54)
			(type default)
		)
		(layer "In3.Cu")
	)
	(gr_arc
		(start 267.999972 -62.999874)
		(mid 268.707087 -62.70699)
		(end 268.99997 -61.999876)
		(stroke
			(width 2.54)
			(type default)
		)
		(layer "In3.Cu")
	)
	(gr_line
		(start 268.99997 -49.200054)
		(end 268.99997 -61.999876)
		(stroke
			(width 2.54)
			(type default)
		)
		(layer "In3.Cu")
	)
	(gr_arc
		(start 269.035784 -385.99999)
		(mid 269.418467 -385.92387)
		(end 269.74292 -385.707128)
		(stroke
			(width 2.54)
			(type default)
		)
		(layer "In3.Cu")
	)
	(gr_line
		(start 269.74292 -385.707128)
		(end 272.15719 -383.292858)
		(stroke
			(width 2.54)
			(type default)
		)
		(layer "In3.Cu")
	)
	(gr_arc
		(start 269.999968 -48.200056)
		(mid 269.292863 -48.492949)
		(end 268.99997 -49.200054)
		(stroke
			(width 2.54)
			(type default)
		)
		(layer "In3.Cu")
	)
	(gr_arc
		(start 272.15719 -383.292858)
		(mid 272.373972 -382.968421)
		(end 272.450052 -382.585722)
		(stroke
			(width 2.54)
			(type default)
		)
		(layer "In3.Cu")
	)
	(gr_line
		(start 272.450052 -382.585722)
		(end 272.450052 -361.00004)
		(stroke
			(width 2.54)
			(type default)
		)
		(layer "In3.Cu")
	)
	(gr_arc
		(start 273.45005 -360.000042)
		(mid 272.742991 -360.292955)
		(end 272.450052 -361.00004)
		(stroke
			(width 2.54)
			(type default)
		)
		(layer "In3.Cu")
	)
	(gr_line
		(start 273.45005 -360.000042)
		(end 275.75002 -360.000042)
		(stroke
			(width 2.54)
			(type default)
		)
		(layer "In3.Cu")
	)
	(gr_line
		(start 274.7264 -145.6436)
		(end 275.9202 -146.8374)
		(stroke
			(width 0.381)
			(type default)
		)
		(layer "In3.Cu")
	)
	(gr_line
		(start 274.7264 -130.7592)
		(end 274.7264 -145.6436)
		(stroke
			(width 0.381)
			(type default)
		)
		(layer "In3.Cu")
	)
	(gr_line
		(start 275.2344 -239.13973)
		(end 276.42947 -240.3348)
		(stroke
			(width 0.381)
			(type default)
		)
		(layer "In3.Cu")
	)
	(gr_line
		(start 275.2344 -175.4632)
		(end 275.2344 -239.13973)
		(stroke
			(width 0.381)
			(type default)
		)
		(layer "In3.Cu")
	)
	(gr_line
		(start 275.3868 -130.0988)
		(end 274.7264 -130.7592)
		(stroke
			(width 0.381)
			(type default)
		)
		(layer "In3.Cu")
	)
	(gr_line
		(start 275.9202 -146.8374)
		(end 289.4838 -146.8374)
		(stroke
			(width 0.381)
			(type default)
		)
		(layer "In3.Cu")
	)
	(gr_line
		(start 276.42947 -240.3348)
		(end 289.8648 -240.3348)
		(stroke
			(width 0.381)
			(type default)
		)
		(layer "In3.Cu")
	)
	(gr_line
		(start 276.5298 -174.1678)
		(end 275.2344 -175.4632)
		(stroke
			(width 0.381)
			(type default)
		)
		(layer "In3.Cu")
	)
	(gr_arc
		(start 276.750018 -382.585722)
		(mid 276.826138 -382.968405)
		(end 277.04288 -383.292858)
		(stroke
			(width 2.54)
			(type default)
		)
		(layer "In3.Cu")
	)
	(gr_arc
		(start 276.750018 -361.00004)
		(mid 276.457141 -360.292902)
		(end 275.75002 -360.000042)
		(stroke
			(width 2.54)
			(type default)
		)
		(layer "In3.Cu")
	)
	(gr_line
		(start 276.750018 -361.00004)
		(end 276.750018 -382.585722)
		(stroke
			(width 2.54)
			(type default)
		)
		(layer "In3.Cu")
	)
	(gr_line
		(start 277.04288 -383.292858)
		(end 279.45715 -385.707128)
		(stroke
			(width 2.54)
			(type default)
		)
		(layer "In3.Cu")
	)
	(gr_line
		(start 278.23668 -237.44301)
		(end 279.636728 -237.44301)
		(stroke
			(width 0.2)
			(type default)
		)
		(layer "In3.Cu")
	)
	(gr_arc
		(start 278.23668 -236.34573)
		(mid 277.68804 -236.89437)
		(end 278.23668 -237.44301)
		(stroke
			(width 0.2)
			(type default)
		)
		(layer "In3.Cu")
	)
	(gr_line
		(start 278.23668 -233.843068)
		(end 279.636728 -233.843068)
		(stroke
			(width 0.2)
			(type default)
		)
		(layer "In3.Cu")
	)
	(gr_arc
		(start 278.23668 -232.745788)
		(mid 277.68804 -233.294428)
		(end 278.23668 -233.843068)
		(stroke
			(width 0.2)
			(type default)
		)
		(layer "In3.Cu")
	)
	(gr_line
		(start 278.23668 -230.243126)
		(end 279.636728 -230.243126)
		(stroke
			(width 0.2)
			(type default)
		)
		(layer "In3.Cu")
	)
	(gr_arc
		(start 278.23668 -229.145846)
		(mid 277.68804 -229.694486)
		(end 278.23668 -230.243126)
		(stroke
			(width 0.2)
			(type default)
		)
		(layer "In3.Cu")
	)
	(gr_line
		(start 278.23668 -226.643184)
		(end 279.636728 -226.643184)
		(stroke
			(width 0.2)
			(type default)
		)
		(layer "In3.Cu")
	)
	(gr_arc
		(start 278.23668 -225.545904)
		(mid 277.68804 -226.094544)
		(end 278.23668 -226.643184)
		(stroke
			(width 0.2)
			(type default)
		)
		(layer "In3.Cu")
	)
	(gr_line
		(start 278.23668 -223.042988)
		(end 279.636728 -223.042988)
		(stroke
			(width 0.2)
			(type default)
		)
		(layer "In3.Cu")
	)
	(gr_arc
		(start 278.23668 -221.945708)
		(mid 277.68804 -222.494348)
		(end 278.23668 -223.042988)
		(stroke
			(width 0.2)
			(type default)
		)
		(layer "In3.Cu")
	)
	(gr_line
		(start 278.23668 -219.443046)
		(end 279.636728 -219.443046)
		(stroke
			(width 0.2)
			(type default)
		)
		(layer "In3.Cu")
	)
	(gr_arc
		(start 278.23668 -218.345766)
		(mid 277.68804 -218.894406)
		(end 278.23668 -219.443046)
		(stroke
			(width 0.2)
			(type default)
		)
		(layer "In3.Cu")
	)
	(gr_line
		(start 278.23668 -215.843104)
		(end 279.636728 -215.843104)
		(stroke
			(width 0.2)
			(type default)
		)
		(layer "In3.Cu")
	)
	(gr_arc
		(start 278.23668 -214.745824)
		(mid 277.68804 -215.294464)
		(end 278.23668 -215.843104)
		(stroke
			(width 0.2)
			(type default)
		)
		(layer "In3.Cu")
	)
	(gr_line
		(start 278.23668 -212.243162)
		(end 279.636728 -212.243162)
		(stroke
			(width 0.2)
			(type default)
		)
		(layer "In3.Cu")
	)
	(gr_arc
		(start 278.23668 -211.145882)
		(mid 277.68804 -211.694522)
		(end 278.23668 -212.243162)
		(stroke
			(width 0.2)
			(type default)
		)
		(layer "In3.Cu")
	)
	(gr_line
		(start 278.23668 -208.64322)
		(end 279.636728 -208.64322)
		(stroke
			(width 0.2)
			(type default)
		)
		(layer "In3.Cu")
	)
	(gr_arc
		(start 278.23668 -207.54594)
		(mid 277.68804 -208.09458)
		(end 278.23668 -208.64322)
		(stroke
			(width 0.2)
			(type default)
		)
		(layer "In3.Cu")
	)
	(gr_line
		(start 278.23668 -205.043024)
		(end 279.636728 -205.043024)
		(stroke
			(width 0.2)
			(type default)
		)
		(layer "In3.Cu")
	)
	(gr_arc
		(start 278.23668 -203.945744)
		(mid 277.68804 -204.494384)
		(end 278.23668 -205.043024)
		(stroke
			(width 0.2)
			(type default)
		)
		(layer "In3.Cu")
	)
	(gr_line
		(start 278.23668 -201.443082)
		(end 279.636728 -201.443082)
		(stroke
			(width 0.2)
			(type default)
		)
		(layer "In3.Cu")
	)
	(gr_arc
		(start 278.23668 -200.345802)
		(mid 277.68804 -200.894442)
		(end 278.23668 -201.443082)
		(stroke
			(width 0.2)
			(type default)
		)
		(layer "In3.Cu")
	)
	(gr_line
		(start 278.23668 -197.84314)
		(end 279.636728 -197.84314)
		(stroke
			(width 0.2)
			(type default)
		)
		(layer "In3.Cu")
	)
	(gr_arc
		(start 278.23668 -196.74586)
		(mid 277.68804 -197.2945)
		(end 278.23668 -197.84314)
		(stroke
			(width 0.2)
			(type default)
		)
		(layer "In3.Cu")
	)
	(gr_line
		(start 278.23668 -194.243198)
		(end 279.636728 -194.243198)
		(stroke
			(width 0.2)
			(type default)
		)
		(layer "In3.Cu")
	)
	(gr_arc
		(start 278.23668 -193.145918)
		(mid 277.68804 -193.694558)
		(end 278.23668 -194.243198)
		(stroke
			(width 0.2)
			(type default)
		)
		(layer "In3.Cu")
	)
	(gr_line
		(start 278.23668 -190.643002)
		(end 279.636728 -190.643002)
		(stroke
			(width 0.2)
			(type default)
		)
		(layer "In3.Cu")
	)
	(gr_arc
		(start 278.23668 -189.545722)
		(mid 277.68804 -190.094362)
		(end 278.23668 -190.643002)
		(stroke
			(width 0.2)
			(type default)
		)
		(layer "In3.Cu")
	)
	(gr_line
		(start 278.23668 -187.04306)
		(end 279.636728 -187.04306)
		(stroke
			(width 0.2)
			(type default)
		)
		(layer "In3.Cu")
	)
	(gr_arc
		(start 278.23668 -185.94578)
		(mid 277.68804 -186.49442)
		(end 278.23668 -187.04306)
		(stroke
			(width 0.2)
			(type default)
		)
		(layer "In3.Cu")
	)
	(gr_line
		(start 278.23668 -183.443118)
		(end 279.636728 -183.443118)
		(stroke
			(width 0.2)
			(type default)
		)
		(layer "In3.Cu")
	)
	(gr_arc
		(start 278.23668 -182.345838)
		(mid 277.68804 -182.894478)
		(end 278.23668 -183.443118)
		(stroke
			(width 0.2)
			(type default)
		)
		(layer "In3.Cu")
	)
	(gr_line
		(start 278.23668 -179.843176)
		(end 279.636728 -179.843176)
		(stroke
			(width 0.2)
			(type default)
		)
		(layer "In3.Cu")
	)
	(gr_arc
		(start 278.23668 -178.745896)
		(mid 277.68804 -179.294536)
		(end 278.23668 -179.843176)
		(stroke
			(width 0.2)
			(type default)
		)
		(layer "In3.Cu")
	)
	(gr_line
		(start 278.23668 -176.243234)
		(end 279.636728 -176.243234)
		(stroke
			(width 0.2)
			(type default)
		)
		(layer "In3.Cu")
	)
	(gr_arc
		(start 278.23668 -175.145954)
		(mid 277.68804 -175.694594)
		(end 278.23668 -176.243234)
		(stroke
			(width 0.2)
			(type default)
		)
		(layer "In3.Cu")
	)
	(gr_line
		(start 278.23668 -143.442944)
		(end 279.636728 -143.442944)
		(stroke
			(width 0.2)
			(type default)
		)
		(layer "In3.Cu")
	)
	(gr_arc
		(start 278.23668 -142.345664)
		(mid 277.68804 -142.894304)
		(end 278.23668 -143.442944)
		(stroke
			(width 0.2)
			(type default)
		)
		(layer "In3.Cu")
	)
	(gr_line
		(start 278.23668 -139.843002)
		(end 279.636728 -139.843002)
		(stroke
			(width 0.2)
			(type default)
		)
		(layer "In3.Cu")
	)
	(gr_arc
		(start 278.23668 -138.745722)
		(mid 277.68804 -139.294362)
		(end 278.23668 -139.843002)
		(stroke
			(width 0.2)
			(type default)
		)
		(layer "In3.Cu")
	)
	(gr_line
		(start 278.23668 -136.24306)
		(end 279.636728 -136.24306)
		(stroke
			(width 0.2)
			(type default)
		)
		(layer "In3.Cu")
	)
	(gr_arc
		(start 278.23668 -135.14578)
		(mid 277.68804 -135.69442)
		(end 278.23668 -136.24306)
		(stroke
			(width 0.2)
			(type default)
		)
		(layer "In3.Cu")
	)
	(gr_line
		(start 278.23668 -132.643118)
		(end 279.636728 -132.643118)
		(stroke
			(width 0.2)
			(type default)
		)
		(layer "In3.Cu")
	)
	(gr_arc
		(start 278.23668 -131.545838)
		(mid 277.68804 -132.094478)
		(end 278.23668 -132.643118)
		(stroke
			(width 0.2)
			(type default)
		)
		(layer "In3.Cu")
	)
	(gr_line
		(start 279.236678 -239.243108)
		(end 280.636726 -239.243108)
		(stroke
			(width 0.2)
			(type default)
		)
		(layer "In3.Cu")
	)
	(gr_arc
		(start 279.236678 -238.145828)
		(mid 278.688038 -238.694468)
		(end 279.236678 -239.243108)
		(stroke
			(width 0.2)
			(type default)
		)
		(layer "In3.Cu")
	)
	(gr_line
		(start 279.236678 -235.643166)
		(end 280.636726 -235.643166)
		(stroke
			(width 0.2)
			(type default)
		)
		(layer "In3.Cu")
	)
	(gr_arc
		(start 279.236678 -234.545886)
		(mid 278.688038 -235.094526)
		(end 279.236678 -235.643166)
		(stroke
			(width 0.2)
			(type default)
		)
		(layer "In3.Cu")
	)
	(gr_line
		(start 279.236678 -232.043224)
		(end 280.636726 -232.043224)
		(stroke
			(width 0.2)
			(type default)
		)
		(layer "In3.Cu")
	)
	(gr_arc
		(start 279.236678 -230.945944)
		(mid 278.688038 -231.494584)
		(end 279.236678 -232.043224)
		(stroke
			(width 0.2)
			(type default)
		)
		(layer "In3.Cu")
	)
	(gr_line
		(start 279.236678 -228.443028)
		(end 280.636726 -228.443028)
		(stroke
			(width 0.2)
			(type default)
		)
		(layer "In3.Cu")
	)
	(gr_arc
		(start 279.236678 -227.345748)
		(mid 278.688038 -227.894388)
		(end 279.236678 -228.443028)
		(stroke
			(width 0.2)
			(type default)
		)
		(layer "In3.Cu")
	)
	(gr_line
		(start 279.236678 -224.843086)
		(end 280.636726 -224.843086)
		(stroke
			(width 0.2)
			(type default)
		)
		(layer "In3.Cu")
	)
	(gr_arc
		(start 279.236678 -223.745806)
		(mid 278.688038 -224.294446)
		(end 279.236678 -224.843086)
		(stroke
			(width 0.2)
			(type default)
		)
		(layer "In3.Cu")
	)
	(gr_line
		(start 279.236678 -221.243144)
		(end 280.636726 -221.243144)
		(stroke
			(width 0.2)
			(type default)
		)
		(layer "In3.Cu")
	)
	(gr_arc
		(start 279.236678 -220.145864)
		(mid 278.688038 -220.694504)
		(end 279.236678 -221.243144)
		(stroke
			(width 0.2)
			(type default)
		)
		(layer "In3.Cu")
	)
	(gr_line
		(start 279.236678 -217.643202)
		(end 280.636726 -217.643202)
		(stroke
			(width 0.2)
			(type default)
		)
		(layer "In3.Cu")
	)
	(gr_arc
		(start 279.236678 -216.545922)
		(mid 278.688038 -217.094562)
		(end 279.236678 -217.643202)
		(stroke
			(width 0.2)
			(type default)
		)
		(layer "In3.Cu")
	)
	(gr_line
		(start 279.236678 -214.043006)
		(end 280.636726 -214.043006)
		(stroke
			(width 0.2)
			(type default)
		)
		(layer "In3.Cu")
	)
	(gr_arc
		(start 279.236678 -212.945726)
		(mid 278.688038 -213.494366)
		(end 279.236678 -214.043006)
		(stroke
			(width 0.2)
			(type default)
		)
		(layer "In3.Cu")
	)
	(gr_line
		(start 279.236678 -210.443064)
		(end 280.636726 -210.443064)
		(stroke
			(width 0.2)
			(type default)
		)
		(layer "In3.Cu")
	)
	(gr_arc
		(start 279.236678 -209.345784)
		(mid 278.688038 -209.894424)
		(end 279.236678 -210.443064)
		(stroke
			(width 0.2)
			(type default)
		)
		(layer "In3.Cu")
	)
	(gr_line
		(start 279.236678 -206.843122)
		(end 280.636726 -206.843122)
		(stroke
			(width 0.2)
			(type default)
		)
		(layer "In3.Cu")
	)
	(gr_arc
		(start 279.236678 -205.745842)
		(mid 278.688038 -206.294482)
		(end 279.236678 -206.843122)
		(stroke
			(width 0.2)
			(type default)
		)
		(layer "In3.Cu")
	)
	(gr_line
		(start 279.236678 -203.24318)
		(end 280.636726 -203.24318)
		(stroke
			(width 0.2)
			(type default)
		)
		(layer "In3.Cu")
	)
	(gr_arc
		(start 279.236678 -202.1459)
		(mid 278.688038 -202.69454)
		(end 279.236678 -203.24318)
		(stroke
			(width 0.2)
			(type default)
		)
		(layer "In3.Cu")
	)
	(gr_line
		(start 279.236678 -199.642984)
		(end 280.636726 -199.642984)
		(stroke
			(width 0.2)
			(type default)
		)
		(layer "In3.Cu")
	)
	(gr_arc
		(start 279.236678 -198.545704)
		(mid 278.688038 -199.094344)
		(end 279.236678 -199.642984)
		(stroke
			(width 0.2)
			(type default)
		)
		(layer "In3.Cu")
	)
	(gr_line
		(start 279.236678 -196.043042)
		(end 280.636726 -196.043042)
		(stroke
			(width 0.2)
			(type default)
		)
		(layer "In3.Cu")
	)
	(gr_arc
		(start 279.236678 -194.945762)
		(mid 278.688038 -195.494402)
		(end 279.236678 -196.043042)
		(stroke
			(width 0.2)
			(type default)
		)
		(layer "In3.Cu")
	)
	(gr_line
		(start 279.236678 -192.4431)
		(end 280.636726 -192.4431)
		(stroke
			(width 0.2)
			(type default)
		)
		(layer "In3.Cu")
	)
	(gr_arc
		(start 279.236678 -191.34582)
		(mid 278.688038 -191.89446)
		(end 279.236678 -192.4431)
		(stroke
			(width 0.2)
			(type default)
		)
		(layer "In3.Cu")
	)
	(gr_line
		(start 279.236678 -188.843158)
		(end 280.636726 -188.843158)
		(stroke
			(width 0.2)
			(type default)
		)
		(layer "In3.Cu")
	)
	(gr_arc
		(start 279.236678 -187.745878)
		(mid 278.688038 -188.294518)
		(end 279.236678 -188.843158)
		(stroke
			(width 0.2)
			(type default)
		)
		(layer "In3.Cu")
	)
	(gr_line
		(start 279.236678 -185.243216)
		(end 280.636726 -185.243216)
		(stroke
			(width 0.2)
			(type default)
		)
		(layer "In3.Cu")
	)
	(gr_arc
		(start 279.236678 -184.145936)
		(mid 278.688038 -184.694576)
		(end 279.236678 -185.243216)
		(stroke
			(width 0.2)
			(type default)
		)
		(layer "In3.Cu")
	)
	(gr_line
		(start 279.236678 -181.64302)
		(end 280.636726 -181.64302)
		(stroke
			(width 0.2)
			(type default)
		)
		(layer "In3.Cu")
	)
	(gr_arc
		(start 279.236678 -180.54574)
		(mid 278.688038 -181.09438)
		(end 279.236678 -181.64302)
		(stroke
			(width 0.2)
			(type default)
		)
		(layer "In3.Cu")
	)
	(gr_line
		(start 279.236678 -178.043078)
		(end 280.636726 -178.043078)
		(stroke
			(width 0.2)
			(type default)
		)
		(layer "In3.Cu")
	)
	(gr_arc
		(start 279.236678 -176.945798)
		(mid 278.688038 -177.494438)
		(end 279.236678 -178.043078)
		(stroke
			(width 0.2)
			(type default)
		)
		(layer "In3.Cu")
	)
	(gr_line
		(start 279.236678 -145.243042)
		(end 280.636726 -145.243042)
		(stroke
			(width 0.2)
			(type default)
		)
		(layer "In3.Cu")
	)
	(gr_arc
		(start 279.236678 -144.145762)
		(mid 278.688038 -144.694402)
		(end 279.236678 -145.243042)
		(stroke
			(width 0.2)
			(type default)
		)
		(layer "In3.Cu")
	)
	(gr_line
		(start 279.236678 -141.6431)
		(end 280.636726 -141.6431)
		(stroke
			(width 0.2)
			(type default)
		)
		(layer "In3.Cu")
	)
	(gr_arc
		(start 279.236678 -140.54582)
		(mid 278.688038 -141.09446)
		(end 279.236678 -141.6431)
		(stroke
			(width 0.2)
			(type default)
		)
		(layer "In3.Cu")
	)
	(gr_line
		(start 279.236678 -138.045698)
		(end 280.636726 -138.045698)
		(stroke
			(width 0.2)
			(type default)
		)
		(layer "In3.Cu")
	)
	(gr_arc
		(start 279.236678 -136.943338)
		(mid 278.685498 -137.494518)
		(end 279.236678 -138.045698)
		(stroke
			(width 0.2)
			(type default)
		)
		(layer "In3.Cu")
	)
	(gr_line
		(start 279.236678 -134.442962)
		(end 280.636726 -134.442962)
		(stroke
			(width 0.2)
			(type default)
		)
		(layer "In3.Cu")
	)
	(gr_arc
		(start 279.236678 -133.345682)
		(mid 278.688038 -133.894322)
		(end 279.236678 -134.442962)
		(stroke
			(width 0.2)
			(type default)
		)
		(layer "In3.Cu")
	)
	(gr_line
		(start 279.236932 -136.943338)
		(end 279.236678 -136.943338)
		(stroke
			(width 0.2)
			(type default)
		)
		(layer "In3.Cu")
	)
	(gr_arc
		(start 279.45715 -385.707128)
		(mid 279.781587 -385.92391)
		(end 280.164286 -385.99999)
		(stroke
			(width 2.54)
			(type default)
		)
		(layer "In3.Cu")
	)
	(gr_arc
		(start 279.636728 -237.44301)
		(mid 280.185368 -236.89437)
		(end 279.636728 -236.34573)
		(stroke
			(width 0.2)
			(type default)
		)
		(layer "In3.Cu")
	)
	(gr_line
		(start 279.636728 -236.34573)
		(end 278.23668 -236.34573)
		(stroke
			(width 0.2)
			(type default)
		)
		(layer "In3.Cu")
	)
	(gr_arc
		(start 279.636728 -233.843068)
		(mid 280.185368 -233.294428)
		(end 279.636728 -232.745788)
		(stroke
			(width 0.2)
			(type default)
		)
		(layer "In3.Cu")
	)
	(gr_line
		(start 279.636728 -232.745788)
		(end 278.23668 -232.745788)
		(stroke
			(width 0.2)
			(type default)
		)
		(layer "In3.Cu")
	)
	(gr_arc
		(start 279.636728 -230.243126)
		(mid 280.185368 -229.694486)
		(end 279.636728 -229.145846)
		(stroke
			(width 0.2)
			(type default)
		)
		(layer "In3.Cu")
	)
	(gr_line
		(start 279.636728 -229.145846)
		(end 278.23668 -229.145846)
		(stroke
			(width 0.2)
			(type default)
		)
		(layer "In3.Cu")
	)
	(gr_arc
		(start 279.636728 -226.643184)
		(mid 280.185368 -226.094544)
		(end 279.636728 -225.545904)
		(stroke
			(width 0.2)
			(type default)
		)
		(layer "In3.Cu")
	)
	(gr_line
		(start 279.636728 -225.545904)
		(end 278.23668 -225.545904)
		(stroke
			(width 0.2)
			(type default)
		)
		(layer "In3.Cu")
	)
	(gr_arc
		(start 279.636728 -223.042988)
		(mid 280.185368 -222.494348)
		(end 279.636728 -221.945708)
		(stroke
			(width 0.2)
			(type default)
		)
		(layer "In3.Cu")
	)
	(gr_line
		(start 279.636728 -221.945708)
		(end 278.23668 -221.945708)
		(stroke
			(width 0.2)
			(type default)
		)
		(layer "In3.Cu")
	)
	(gr_arc
		(start 279.636728 -219.443046)
		(mid 280.185368 -218.894406)
		(end 279.636728 -218.345766)
		(stroke
			(width 0.2)
			(type default)
		)
		(layer "In3.Cu")
	)
	(gr_line
		(start 279.636728 -218.345766)
		(end 278.23668 -218.345766)
		(stroke
			(width 0.2)
			(type default)
		)
		(layer "In3.Cu")
	)
	(gr_arc
		(start 279.636728 -215.843104)
		(mid 280.185368 -215.294464)
		(end 279.636728 -214.745824)
		(stroke
			(width 0.2)
			(type default)
		)
		(layer "In3.Cu")
	)
	(gr_line
		(start 279.636728 -214.745824)
		(end 278.23668 -214.745824)
		(stroke
			(width 0.2)
			(type default)
		)
		(layer "In3.Cu")
	)
	(gr_arc
		(start 279.636728 -212.243162)
		(mid 280.185368 -211.694522)
		(end 279.636728 -211.145882)
		(stroke
			(width 0.2)
			(type default)
		)
		(layer "In3.Cu")
	)
	(gr_line
		(start 279.636728 -211.145882)
		(end 278.23668 -211.145882)
		(stroke
			(width 0.2)
			(type default)
		)
		(layer "In3.Cu")
	)
	(gr_arc
		(start 279.636728 -208.64322)
		(mid 280.185368 -208.09458)
		(end 279.636728 -207.54594)
		(stroke
			(width 0.2)
			(type default)
		)
		(layer "In3.Cu")
	)
	(gr_line
		(start 279.636728 -207.54594)
		(end 278.23668 -207.54594)
		(stroke
			(width 0.2)
			(type default)
		)
		(layer "In3.Cu")
	)
	(gr_arc
		(start 279.636728 -205.043024)
		(mid 280.185368 -204.494384)
		(end 279.636728 -203.945744)
		(stroke
			(width 0.2)
			(type default)
		)
		(layer "In3.Cu")
	)
	(gr_line
		(start 279.636728 -203.945744)
		(end 278.23668 -203.945744)
		(stroke
			(width 0.2)
			(type default)
		)
		(layer "In3.Cu")
	)
	(gr_arc
		(start 279.636728 -201.443082)
		(mid 280.185368 -200.894442)
		(end 279.636728 -200.345802)
		(stroke
			(width 0.2)
			(type default)
		)
		(layer "In3.Cu")
	)
	(gr_line
		(start 279.636728 -200.345802)
		(end 278.23668 -200.345802)
		(stroke
			(width 0.2)
			(type default)
		)
		(layer "In3.Cu")
	)
	(gr_arc
		(start 279.636728 -197.84314)
		(mid 280.185368 -197.2945)
		(end 279.636728 -196.74586)
		(stroke
			(width 0.2)
			(type default)
		)
		(layer "In3.Cu")
	)
	(gr_line
		(start 279.636728 -196.74586)
		(end 278.23668 -196.74586)
		(stroke
			(width 0.2)
			(type default)
		)
		(layer "In3.Cu")
	)
	(gr_arc
		(start 279.636728 -194.243198)
		(mid 280.185368 -193.694558)
		(end 279.636728 -193.145918)
		(stroke
			(width 0.2)
			(type default)
		)
		(layer "In3.Cu")
	)
	(gr_line
		(start 279.636728 -193.145918)
		(end 278.23668 -193.145918)
		(stroke
			(width 0.2)
			(type default)
		)
		(layer "In3.Cu")
	)
	(gr_arc
		(start 279.636728 -190.643002)
		(mid 280.185368 -190.094362)
		(end 279.636728 -189.545722)
		(stroke
			(width 0.2)
			(type default)
		)
		(layer "In3.Cu")
	)
	(gr_line
		(start 279.636728 -189.545722)
		(end 278.23668 -189.545722)
		(stroke
			(width 0.2)
			(type default)
		)
		(layer "In3.Cu")
	)
	(gr_arc
		(start 279.636728 -187.04306)
		(mid 280.185368 -186.49442)
		(end 279.636728 -185.94578)
		(stroke
			(width 0.2)
			(type default)
		)
		(layer "In3.Cu")
	)
	(gr_line
		(start 279.636728 -185.94578)
		(end 278.23668 -185.94578)
		(stroke
			(width 0.2)
			(type default)
		)
		(layer "In3.Cu")
	)
	(gr_arc
		(start 279.636728 -183.443118)
		(mid 280.185368 -182.894478)
		(end 279.636728 -182.345838)
		(stroke
			(width 0.2)
			(type default)
		)
		(layer "In3.Cu")
	)
	(gr_line
		(start 279.636728 -182.345838)
		(end 278.23668 -182.345838)
		(stroke
			(width 0.2)
			(type default)
		)
		(layer "In3.Cu")
	)
	(gr_arc
		(start 279.636728 -179.843176)
		(mid 280.185368 -179.294536)
		(end 279.636728 -178.745896)
		(stroke
			(width 0.2)
			(type default)
		)
		(layer "In3.Cu")
	)
	(gr_line
		(start 279.636728 -178.745896)
		(end 278.23668 -178.745896)
		(stroke
			(width 0.2)
			(type default)
		)
		(layer "In3.Cu")
	)
	(gr_arc
		(start 279.636728 -176.243234)
		(mid 280.185368 -175.694594)
		(end 279.636728 -175.145954)
		(stroke
			(width 0.2)
			(type default)
		)
		(layer "In3.Cu")
	)
	(gr_line
		(start 279.636728 -175.145954)
		(end 278.23668 -175.145954)
		(stroke
			(width 0.2)
			(type default)
		)
		(layer "In3.Cu")
	)
	(gr_arc
		(start 279.636728 -143.442944)
		(mid 280.185368 -142.894304)
		(end 279.636728 -142.345664)
		(stroke
			(width 0.2)
			(type default)
		)
		(layer "In3.Cu")
	)
	(gr_line
		(start 279.636728 -142.345664)
		(end 278.23668 -142.345664)
		(stroke
			(width 0.2)
			(type default)
		)
		(layer "In3.Cu")
	)
	(gr_arc
		(start 279.636728 -139.843002)
		(mid 280.185368 -139.294362)
		(end 279.636728 -138.745722)
		(stroke
			(width 0.2)
			(type default)
		)
		(layer "In3.Cu")
	)
	(gr_line
		(start 279.636728 -138.745722)
		(end 278.23668 -138.745722)
		(stroke
			(width 0.2)
			(type default)
		)
		(layer "In3.Cu")
	)
	(gr_arc
		(start 279.636728 -136.24306)
		(mid 280.185368 -135.69442)
		(end 279.636728 -135.14578)
		(stroke
			(width 0.2)
			(type default)
		)
		(layer "In3.Cu")
	)
	(gr_line
		(start 279.636728 -135.14578)
		(end 278.23668 -135.14578)
		(stroke
			(width 0.2)
			(type default)
		)
		(layer "In3.Cu")
	)
	(gr_arc
		(start 279.636728 -132.643118)
		(mid 280.185368 -132.094478)
		(end 279.636728 -131.545838)
		(stroke
			(width 0.2)
			(type default)
		)
		(layer "In3.Cu")
	)
	(gr_line
		(start 279.636728 -131.545838)
		(end 278.23668 -131.545838)
		(stroke
			(width 0.2)
			(type default)
		)
		(layer "In3.Cu")
	)
	(gr_line
		(start 280.164286 -385.99999)
		(end 306.649882 -385.99999)
		(stroke
			(width 2.54)
			(type default)
		)
		(layer "In3.Cu")
	)
	(gr_arc
		(start 280.636726 -239.243108)
		(mid 281.185366 -238.694468)
		(end 280.636726 -238.145828)
		(stroke
			(width 0.2)
			(type default)
		)
		(layer "In3.Cu")
	)
	(gr_line
		(start 280.636726 -238.145828)
		(end 279.236678 -238.145828)
		(stroke
			(width 0.2)
			(type default)
		)
		(layer "In3.Cu")
	)
	(gr_arc
		(start 280.636726 -235.643166)
		(mid 281.185366 -235.094526)
		(end 280.636726 -234.545886)
		(stroke
			(width 0.2)
			(type default)
		)
		(layer "In3.Cu")
	)
	(gr_line
		(start 280.636726 -234.545886)
		(end 279.236678 -234.545886)
		(stroke
			(width 0.2)
			(type default)
		)
		(layer "In3.Cu")
	)
	(gr_arc
		(start 280.636726 -232.043224)
		(mid 281.185366 -231.494584)
		(end 280.636726 -230.945944)
		(stroke
			(width 0.2)
			(type default)
		)
		(layer "In3.Cu")
	)
	(gr_line
		(start 280.636726 -230.945944)
		(end 279.236678 -230.945944)
		(stroke
			(width 0.2)
			(type default)
		)
		(layer "In3.Cu")
	)
	(gr_arc
		(start 280.636726 -228.443028)
		(mid 281.185366 -227.894388)
		(end 280.636726 -227.345748)
		(stroke
			(width 0.2)
			(type default)
		)
		(layer "In3.Cu")
	)
	(gr_line
		(start 280.636726 -227.345748)
		(end 279.236678 -227.345748)
		(stroke
			(width 0.2)
			(type default)
		)
		(layer "In3.Cu")
	)
	(gr_arc
		(start 280.636726 -224.843086)
		(mid 281.185366 -224.294446)
		(end 280.636726 -223.745806)
		(stroke
			(width 0.2)
			(type default)
		)
		(layer "In3.Cu")
	)
	(gr_line
		(start 280.636726 -223.745806)
		(end 279.236678 -223.745806)
		(stroke
			(width 0.2)
			(type default)
		)
		(layer "In3.Cu")
	)
	(gr_arc
		(start 280.636726 -221.243144)
		(mid 281.185366 -220.694504)
		(end 280.636726 -220.145864)
		(stroke
			(width 0.2)
			(type default)
		)
		(layer "In3.Cu")
	)
	(gr_line
		(start 280.636726 -220.145864)
		(end 279.236678 -220.145864)
		(stroke
			(width 0.2)
			(type default)
		)
		(layer "In3.Cu")
	)
	(gr_arc
		(start 280.636726 -217.643202)
		(mid 281.185366 -217.094562)
		(end 280.636726 -216.545922)
		(stroke
			(width 0.2)
			(type default)
		)
		(layer "In3.Cu")
	)
	(gr_line
		(start 280.636726 -216.545922)
		(end 279.236678 -216.545922)
		(stroke
			(width 0.2)
			(type default)
		)
		(layer "In3.Cu")
	)
	(gr_arc
		(start 280.636726 -214.043006)
		(mid 281.185366 -213.494366)
		(end 280.636726 -212.945726)
		(stroke
			(width 0.2)
			(type default)
		)
		(layer "In3.Cu")
	)
	(gr_line
		(start 280.636726 -212.945726)
		(end 279.236678 -212.945726)
		(stroke
			(width 0.2)
			(type default)
		)
		(layer "In3.Cu")
	)
	(gr_arc
		(start 280.636726 -210.443064)
		(mid 281.185366 -209.894424)
		(end 280.636726 -209.345784)
		(stroke
			(width 0.2)
			(type default)
		)
		(layer "In3.Cu")
	)
	(gr_line
		(start 280.636726 -209.345784)
		(end 279.236678 -209.345784)
		(stroke
			(width 0.2)
			(type default)
		)
		(layer "In3.Cu")
	)
	(gr_arc
		(start 280.636726 -206.843122)
		(mid 281.185366 -206.294482)
		(end 280.636726 -205.745842)
		(stroke
			(width 0.2)
			(type default)
		)
		(layer "In3.Cu")
	)
	(gr_line
		(start 280.636726 -205.745842)
		(end 279.236678 -205.745842)
		(stroke
			(width 0.2)
			(type default)
		)
		(layer "In3.Cu")
	)
	(gr_arc
		(start 280.636726 -203.24318)
		(mid 281.185366 -202.69454)
		(end 280.636726 -202.1459)
		(stroke
			(width 0.2)
			(type default)
		)
		(layer "In3.Cu")
	)
	(gr_line
		(start 280.636726 -202.1459)
		(end 279.236678 -202.1459)
		(stroke
			(width 0.2)
			(type default)
		)
		(layer "In3.Cu")
	)
	(gr_arc
		(start 280.636726 -199.642984)
		(mid 281.185366 -199.094344)
		(end 280.636726 -198.545704)
		(stroke
			(width 0.2)
			(type default)
		)
		(layer "In3.Cu")
	)
	(gr_line
		(start 280.636726 -198.545704)
		(end 279.236678 -198.545704)
		(stroke
			(width 0.2)
			(type default)
		)
		(layer "In3.Cu")
	)
	(gr_arc
		(start 280.636726 -196.043042)
		(mid 281.185366 -195.494402)
		(end 280.636726 -194.945762)
		(stroke
			(width 0.2)
			(type default)
		)
		(layer "In3.Cu")
	)
	(gr_line
		(start 280.636726 -194.945762)
		(end 279.236678 -194.945762)
		(stroke
			(width 0.2)
			(type default)
		)
		(layer "In3.Cu")
	)
	(gr_arc
		(start 280.636726 -192.4431)
		(mid 281.185366 -191.89446)
		(end 280.636726 -191.34582)
		(stroke
			(width 0.2)
			(type default)
		)
		(layer "In3.Cu")
	)
	(gr_line
		(start 280.636726 -191.34582)
		(end 279.236678 -191.34582)
		(stroke
			(width 0.2)
			(type default)
		)
		(layer "In3.Cu")
	)
	(gr_arc
		(start 280.636726 -188.843158)
		(mid 281.185366 -188.294518)
		(end 280.636726 -187.745878)
		(stroke
			(width 0.2)
			(type default)
		)
		(layer "In3.Cu")
	)
	(gr_line
		(start 280.636726 -187.745878)
		(end 279.236678 -187.745878)
		(stroke
			(width 0.2)
			(type default)
		)
		(layer "In3.Cu")
	)
	(gr_arc
		(start 280.636726 -185.243216)
		(mid 281.185366 -184.694576)
		(end 280.636726 -184.145936)
		(stroke
			(width 0.2)
			(type default)
		)
		(layer "In3.Cu")
	)
	(gr_line
		(start 280.636726 -184.145936)
		(end 279.236678 -184.145936)
		(stroke
			(width 0.2)
			(type default)
		)
		(layer "In3.Cu")
	)
	(gr_arc
		(start 280.636726 -181.64302)
		(mid 281.185366 -181.09438)
		(end 280.636726 -180.54574)
		(stroke
			(width 0.2)
			(type default)
		)
		(layer "In3.Cu")
	)
	(gr_line
		(start 280.636726 -180.54574)
		(end 279.236678 -180.54574)
		(stroke
			(width 0.2)
			(type default)
		)
		(layer "In3.Cu")
	)
	(gr_arc
		(start 280.636726 -178.043078)
		(mid 281.185366 -177.494438)
		(end 280.636726 -176.945798)
		(stroke
			(width 0.2)
			(type default)
		)
		(layer "In3.Cu")
	)
	(gr_line
		(start 280.636726 -176.945798)
		(end 279.236678 -176.945798)
		(stroke
			(width 0.2)
			(type default)
		)
		(layer "In3.Cu")
	)
	(gr_arc
		(start 280.636726 -145.243042)
		(mid 281.185366 -144.694402)
		(end 280.636726 -144.145762)
		(stroke
			(width 0.2)
			(type default)
		)
		(layer "In3.Cu")
	)
	(gr_line
		(start 280.636726 -144.145762)
		(end 279.236678 -144.145762)
		(stroke
			(width 0.2)
			(type default)
		)
		(layer "In3.Cu")
	)
	(gr_arc
		(start 280.636726 -141.6431)
		(mid 281.185366 -141.09446)
		(end 280.636726 -140.54582)
		(stroke
			(width 0.2)
			(type default)
		)
		(layer "In3.Cu")
	)
	(gr_line
		(start 280.636726 -140.54582)
		(end 279.236678 -140.54582)
		(stroke
			(width 0.2)
			(type default)
		)
		(layer "In3.Cu")
	)
	(gr_arc
		(start 280.636726 -138.045698)
		(mid 281.187906 -137.494518)
		(end 280.636726 -136.943338)
		(stroke
			(width 0.2)
			(type default)
		)
		(layer "In3.Cu")
	)
	(gr_line
		(start 280.636726 -136.943338)
		(end 279.236932 -136.943338)
		(stroke
			(width 0.2)
			(type default)
		)
		(layer "In3.Cu")
	)
	(gr_arc
		(start 280.636726 -134.442962)
		(mid 281.185366 -133.894322)
		(end 280.636726 -133.345682)
		(stroke
			(width 0.2)
			(type default)
		)
		(layer "In3.Cu")
	)
	(gr_line
		(start 280.636726 -133.345682)
		(end 279.236678 -133.345682)
		(stroke
			(width 0.2)
			(type default)
		)
		(layer "In3.Cu")
	)
	(gr_line
		(start 282.83662 -145.243042)
		(end 284.236668 -145.243042)
		(stroke
			(width 0.2)
			(type default)
		)
		(layer "In3.Cu")
	)
	(gr_arc
		(start 282.83662 -144.145762)
		(mid 282.28798 -144.694402)
		(end 282.83662 -145.243042)
		(stroke
			(width 0.2)
			(type default)
		)
		(layer "In3.Cu")
	)
	(gr_arc
		(start 284.236668 -145.243042)
		(mid 284.785308 -144.694402)
		(end 284.236668 -144.145762)
		(stroke
			(width 0.2)
			(type default)
		)
		(layer "In3.Cu")
	)
	(gr_line
		(start 284.236668 -144.145762)
		(end 282.83662 -144.145762)
		(stroke
			(width 0.2)
			(type default)
		)
		(layer "In3.Cu")
	)
	(gr_line
		(start 285.436564 -237.44301)
		(end 286.836612 -237.44301)
		(stroke
			(width 0.2)
			(type default)
		)
		(layer "In3.Cu")
	)
	(gr_arc
		(start 285.436564 -236.34573)
		(mid 284.887924 -236.89437)
		(end 285.436564 -237.44301)
		(stroke
			(width 0.2)
			(type default)
		)
		(layer "In3.Cu")
	)
	(gr_line
		(start 285.436564 -233.843068)
		(end 286.836612 -233.843068)
		(stroke
			(width 0.2)
			(type default)
		)
		(layer "In3.Cu")
	)
	(gr_arc
		(start 285.436564 -232.745788)
		(mid 284.887924 -233.294428)
		(end 285.436564 -233.843068)
		(stroke
			(width 0.2)
			(type default)
		)
		(layer "In3.Cu")
	)
	(gr_line
		(start 285.436564 -230.243126)
		(end 286.836612 -230.243126)
		(stroke
			(width 0.2)
			(type default)
		)
		(layer "In3.Cu")
	)
	(gr_arc
		(start 285.436564 -229.145846)
		(mid 284.887924 -229.694486)
		(end 285.436564 -230.243126)
		(stroke
			(width 0.2)
			(type default)
		)
		(layer "In3.Cu")
	)
	(gr_line
		(start 285.436564 -226.643184)
		(end 286.836612 -226.643184)
		(stroke
			(width 0.2)
			(type default)
		)
		(layer "In3.Cu")
	)
	(gr_arc
		(start 285.436564 -225.545904)
		(mid 284.887924 -226.094544)
		(end 285.436564 -226.643184)
		(stroke
			(width 0.2)
			(type default)
		)
		(layer "In3.Cu")
	)
	(gr_line
		(start 285.436564 -223.042988)
		(end 286.836612 -223.042988)
		(stroke
			(width 0.2)
			(type default)
		)
		(layer "In3.Cu")
	)
	(gr_arc
		(start 285.436564 -221.945708)
		(mid 284.887924 -222.494348)
		(end 285.436564 -223.042988)
		(stroke
			(width 0.2)
			(type default)
		)
		(layer "In3.Cu")
	)
	(gr_line
		(start 285.436564 -219.443046)
		(end 286.836612 -219.443046)
		(stroke
			(width 0.2)
			(type default)
		)
		(layer "In3.Cu")
	)
	(gr_arc
		(start 285.436564 -218.345766)
		(mid 284.887924 -218.894406)
		(end 285.436564 -219.443046)
		(stroke
			(width 0.2)
			(type default)
		)
		(layer "In3.Cu")
	)
	(gr_line
		(start 285.436564 -215.843104)
		(end 286.836612 -215.843104)
		(stroke
			(width 0.2)
			(type default)
		)
		(layer "In3.Cu")
	)
	(gr_arc
		(start 285.436564 -214.745824)
		(mid 284.887924 -215.294464)
		(end 285.436564 -215.843104)
		(stroke
			(width 0.2)
			(type default)
		)
		(layer "In3.Cu")
	)
	(gr_line
		(start 285.436564 -212.243162)
		(end 286.836612 -212.243162)
		(stroke
			(width 0.2)
			(type default)
		)
		(layer "In3.Cu")
	)
	(gr_arc
		(start 285.436564 -211.145882)
		(mid 284.887924 -211.694522)
		(end 285.436564 -212.243162)
		(stroke
			(width 0.2)
			(type default)
		)
		(layer "In3.Cu")
	)
	(gr_line
		(start 285.436564 -208.64322)
		(end 286.836612 -208.64322)
		(stroke
			(width 0.2)
			(type default)
		)
		(layer "In3.Cu")
	)
	(gr_arc
		(start 285.436564 -207.54594)
		(mid 284.887924 -208.09458)
		(end 285.436564 -208.64322)
		(stroke
			(width 0.2)
			(type default)
		)
		(layer "In3.Cu")
	)
	(gr_line
		(start 285.436564 -205.043024)
		(end 286.836612 -205.043024)
		(stroke
			(width 0.2)
			(type default)
		)
		(layer "In3.Cu")
	)
	(gr_arc
		(start 285.436564 -203.945744)
		(mid 284.887924 -204.494384)
		(end 285.436564 -205.043024)
		(stroke
			(width 0.2)
			(type default)
		)
		(layer "In3.Cu")
	)
	(gr_line
		(start 285.436564 -201.443082)
		(end 286.836612 -201.443082)
		(stroke
			(width 0.2)
			(type default)
		)
		(layer "In3.Cu")
	)
	(gr_arc
		(start 285.436564 -200.345802)
		(mid 284.887924 -200.894442)
		(end 285.436564 -201.443082)
		(stroke
			(width 0.2)
			(type default)
		)
		(layer "In3.Cu")
	)
	(gr_line
		(start 285.436564 -197.84314)
		(end 286.836612 -197.84314)
		(stroke
			(width 0.2)
			(type default)
		)
		(layer "In3.Cu")
	)
	(gr_arc
		(start 285.436564 -196.74586)
		(mid 284.887924 -197.2945)
		(end 285.436564 -197.84314)
		(stroke
			(width 0.2)
			(type default)
		)
		(layer "In3.Cu")
	)
	(gr_line
		(start 285.436564 -194.243198)
		(end 286.836612 -194.243198)
		(stroke
			(width 0.2)
			(type default)
		)
		(layer "In3.Cu")
	)
	(gr_arc
		(start 285.436564 -193.145918)
		(mid 284.887924 -193.694558)
		(end 285.436564 -194.243198)
		(stroke
			(width 0.2)
			(type default)
		)
		(layer "In3.Cu")
	)
	(gr_line
		(start 285.436564 -190.643002)
		(end 286.836612 -190.643002)
		(stroke
			(width 0.2)
			(type default)
		)
		(layer "In3.Cu")
	)
	(gr_arc
		(start 285.436564 -189.545722)
		(mid 284.887924 -190.094362)
		(end 285.436564 -190.643002)
		(stroke
			(width 0.2)
			(type default)
		)
		(layer "In3.Cu")
	)
	(gr_line
		(start 285.436564 -187.04306)
		(end 286.836612 -187.04306)
		(stroke
			(width 0.2)
			(type default)
		)
		(layer "In3.Cu")
	)
	(gr_arc
		(start 285.436564 -185.94578)
		(mid 284.887924 -186.49442)
		(end 285.436564 -187.04306)
		(stroke
			(width 0.2)
			(type default)
		)
		(layer "In3.Cu")
	)
	(gr_line
		(start 285.436564 -183.443118)
		(end 286.836612 -183.443118)
		(stroke
			(width 0.2)
			(type default)
		)
		(layer "In3.Cu")
	)
	(gr_arc
		(start 285.436564 -182.345838)
		(mid 284.887924 -182.894478)
		(end 285.436564 -183.443118)
		(stroke
			(width 0.2)
			(type default)
		)
		(layer "In3.Cu")
	)
	(gr_line
		(start 285.436564 -179.843176)
		(end 286.836612 -179.843176)
		(stroke
			(width 0.2)
			(type default)
		)
		(layer "In3.Cu")
	)
	(gr_arc
		(start 285.436564 -178.745896)
		(mid 284.887924 -179.294536)
		(end 285.436564 -179.843176)
		(stroke
			(width 0.2)
			(type default)
		)
		(layer "In3.Cu")
	)
	(gr_line
		(start 285.436564 -176.243234)
		(end 286.836612 -176.243234)
		(stroke
			(width 0.2)
			(type default)
		)
		(layer "In3.Cu")
	)
	(gr_arc
		(start 285.436564 -175.145954)
		(mid 284.887924 -175.694594)
		(end 285.436564 -176.243234)
		(stroke
			(width 0.2)
			(type default)
		)
		(layer "In3.Cu")
	)
	(gr_line
		(start 285.436564 -143.442944)
		(end 286.836612 -143.442944)
		(stroke
			(width 0.2)
			(type default)
		)
		(layer "In3.Cu")
	)
	(gr_arc
		(start 285.436564 -142.345664)
		(mid 284.887924 -142.894304)
		(end 285.436564 -143.442944)
		(stroke
			(width 0.2)
			(type default)
		)
		(layer "In3.Cu")
	)
	(gr_line
		(start 285.436564 -139.843002)
		(end 286.836612 -139.843002)
		(stroke
			(width 0.2)
			(type default)
		)
		(layer "In3.Cu")
	)
	(gr_arc
		(start 285.436564 -138.745722)
		(mid 284.887924 -139.294362)
		(end 285.436564 -139.843002)
		(stroke
			(width 0.2)
			(type default)
		)
		(layer "In3.Cu")
	)
	(gr_line
		(start 285.436564 -136.24306)
		(end 286.836612 -136.24306)
		(stroke
			(width 0.2)
			(type default)
		)
		(layer "In3.Cu")
	)
	(gr_arc
		(start 285.436564 -135.14578)
		(mid 284.887924 -135.69442)
		(end 285.436564 -136.24306)
		(stroke
			(width 0.2)
			(type default)
		)
		(layer "In3.Cu")
	)
	(gr_line
		(start 285.436564 -132.643118)
		(end 286.836612 -132.643118)
		(stroke
			(width 0.2)
			(type default)
		)
		(layer "In3.Cu")
	)
	(gr_arc
		(start 285.436564 -131.545838)
		(mid 284.887924 -132.094478)
		(end 285.436564 -132.643118)
		(stroke
			(width 0.2)
			(type default)
		)
		(layer "In3.Cu")
	)
	(gr_line
		(start 286.436562 -239.243108)
		(end 287.83661 -239.243108)
		(stroke
			(width 0.2)
			(type default)
		)
		(layer "In3.Cu")
	)
	(gr_arc
		(start 286.436562 -238.145828)
		(mid 285.887922 -238.694468)
		(end 286.436562 -239.243108)
		(stroke
			(width 0.2)
			(type default)
		)
		(layer "In3.Cu")
	)
	(gr_line
		(start 286.436562 -235.643166)
		(end 287.83661 -235.643166)
		(stroke
			(width 0.2)
			(type default)
		)
		(layer "In3.Cu")
	)
	(gr_arc
		(start 286.436562 -234.545886)
		(mid 285.887922 -235.094526)
		(end 286.436562 -235.643166)
		(stroke
			(width 0.2)
			(type default)
		)
		(layer "In3.Cu")
	)
	(gr_line
		(start 286.436562 -232.043224)
		(end 287.83661 -232.043224)
		(stroke
			(width 0.2)
			(type default)
		)
		(layer "In3.Cu")
	)
	(gr_arc
		(start 286.436562 -230.945944)
		(mid 285.887922 -231.494584)
		(end 286.436562 -232.043224)
		(stroke
			(width 0.2)
			(type default)
		)
		(layer "In3.Cu")
	)
	(gr_line
		(start 286.436562 -228.443028)
		(end 287.83661 -228.443028)
		(stroke
			(width 0.2)
			(type default)
		)
		(layer "In3.Cu")
	)
	(gr_arc
		(start 286.436562 -227.345748)
		(mid 285.887922 -227.894388)
		(end 286.436562 -228.443028)
		(stroke
			(width 0.2)
			(type default)
		)
		(layer "In3.Cu")
	)
	(gr_line
		(start 286.436562 -224.906586)
		(end 287.83661 -224.906586)
		(stroke
			(width 0.2)
			(type default)
		)
		(layer "In3.Cu")
	)
	(gr_arc
		(start 286.436562 -223.682306)
		(mid 285.824422 -224.294446)
		(end 286.436562 -224.906586)
		(stroke
			(width 0.2)
			(type default)
		)
		(layer "In3.Cu")
	)
	(gr_line
		(start 286.436562 -221.243144)
		(end 287.83661 -221.243144)
		(stroke
			(width 0.2)
			(type default)
		)
		(layer "In3.Cu")
	)
	(gr_arc
		(start 286.436562 -220.145864)
		(mid 285.887922 -220.694504)
		(end 286.436562 -221.243144)
		(stroke
			(width 0.2)
			(type default)
		)
		(layer "In3.Cu")
	)
	(gr_line
		(start 286.436562 -217.643202)
		(end 287.83661 -217.643202)
		(stroke
			(width 0.2)
			(type default)
		)
		(layer "In3.Cu")
	)
	(gr_arc
		(start 286.436562 -216.545922)
		(mid 285.887922 -217.094562)
		(end 286.436562 -217.643202)
		(stroke
			(width 0.2)
			(type default)
		)
		(layer "In3.Cu")
	)
	(gr_line
		(start 286.436562 -214.043006)
		(end 287.83661 -214.043006)
		(stroke
			(width 0.2)
			(type default)
		)
		(layer "In3.Cu")
	)
	(gr_arc
		(start 286.436562 -212.945726)
		(mid 285.887922 -213.494366)
		(end 286.436562 -214.043006)
		(stroke
			(width 0.2)
			(type default)
		)
		(layer "In3.Cu")
	)
	(gr_line
		(start 286.436562 -210.443064)
		(end 287.83661 -210.443064)
		(stroke
			(width 0.2)
			(type default)
		)
		(layer "In3.Cu")
	)
	(gr_arc
		(start 286.436562 -209.345784)
		(mid 285.887922 -209.894424)
		(end 286.436562 -210.443064)
		(stroke
			(width 0.2)
			(type default)
		)
		(layer "In3.Cu")
	)
	(gr_line
		(start 286.436562 -206.843122)
		(end 287.83661 -206.843122)
		(stroke
			(width 0.2)
			(type default)
		)
		(layer "In3.Cu")
	)
	(gr_arc
		(start 286.436562 -205.745842)
		(mid 285.887922 -206.294482)
		(end 286.436562 -206.843122)
		(stroke
			(width 0.2)
			(type default)
		)
		(layer "In3.Cu")
	)
	(gr_line
		(start 286.436562 -203.24318)
		(end 287.83661 -203.24318)
		(stroke
			(width 0.2)
			(type default)
		)
		(layer "In3.Cu")
	)
	(gr_arc
		(start 286.436562 -202.1459)
		(mid 285.887922 -202.69454)
		(end 286.436562 -203.24318)
		(stroke
			(width 0.2)
			(type default)
		)
		(layer "In3.Cu")
	)
	(gr_line
		(start 286.436562 -199.642984)
		(end 287.83661 -199.642984)
		(stroke
			(width 0.2)
			(type default)
		)
		(layer "In3.Cu")
	)
	(gr_arc
		(start 286.436562 -198.545704)
		(mid 285.887922 -199.094344)
		(end 286.436562 -199.642984)
		(stroke
			(width 0.2)
			(type default)
		)
		(layer "In3.Cu")
	)
	(gr_line
		(start 286.436562 -196.043042)
		(end 287.83661 -196.043042)
		(stroke
			(width 0.2)
			(type default)
		)
		(layer "In3.Cu")
	)
	(gr_arc
		(start 286.436562 -194.945762)
		(mid 285.887922 -195.494402)
		(end 286.436562 -196.043042)
		(stroke
			(width 0.2)
			(type default)
		)
		(layer "In3.Cu")
	)
	(gr_line
		(start 286.436562 -192.4431)
		(end 287.83661 -192.4431)
		(stroke
			(width 0.2)
			(type default)
		)
		(layer "In3.Cu")
	)
	(gr_arc
		(start 286.436562 -191.34582)
		(mid 285.887922 -191.89446)
		(end 286.436562 -192.4431)
		(stroke
			(width 0.2)
			(type default)
		)
		(layer "In3.Cu")
	)
	(gr_line
		(start 286.436562 -188.843158)
		(end 287.83661 -188.843158)
		(stroke
			(width 0.2)
			(type default)
		)
		(layer "In3.Cu")
	)
	(gr_arc
		(start 286.436562 -187.745878)
		(mid 285.887922 -188.294518)
		(end 286.436562 -188.843158)
		(stroke
			(width 0.2)
			(type default)
		)
		(layer "In3.Cu")
	)
	(gr_line
		(start 286.436562 -185.243216)
		(end 287.83661 -185.243216)
		(stroke
			(width 0.2)
			(type default)
		)
		(layer "In3.Cu")
	)
	(gr_arc
		(start 286.436562 -184.145936)
		(mid 285.887922 -184.694576)
		(end 286.436562 -185.243216)
		(stroke
			(width 0.2)
			(type default)
		)
		(layer "In3.Cu")
	)
	(gr_line
		(start 286.436562 -181.64302)
		(end 287.83661 -181.64302)
		(stroke
			(width 0.2)
			(type default)
		)
		(layer "In3.Cu")
	)
	(gr_arc
		(start 286.436562 -180.54574)
		(mid 285.887922 -181.09438)
		(end 286.436562 -181.64302)
		(stroke
			(width 0.2)
			(type default)
		)
		(layer "In3.Cu")
	)
	(gr_line
		(start 286.436562 -178.043078)
		(end 287.83661 -178.043078)
		(stroke
			(width 0.2)
			(type default)
		)
		(layer "In3.Cu")
	)
	(gr_arc
		(start 286.436562 -176.945798)
		(mid 285.887922 -177.494438)
		(end 286.436562 -178.043078)
		(stroke
			(width 0.2)
			(type default)
		)
		(layer "In3.Cu")
	)
	(gr_line
		(start 286.436562 -145.243042)
		(end 287.83661 -145.243042)
		(stroke
			(width 0.2)
			(type default)
		)
		(layer "In3.Cu")
	)
	(gr_arc
		(start 286.436562 -144.145762)
		(mid 285.887922 -144.694402)
		(end 286.436562 -145.243042)
		(stroke
			(width 0.2)
			(type default)
		)
		(layer "In3.Cu")
	)
	(gr_line
		(start 286.436562 -141.6431)
		(end 287.83661 -141.6431)
		(stroke
			(width 0.2)
			(type default)
		)
		(layer "In3.Cu")
	)
	(gr_arc
		(start 286.436562 -140.54582)
		(mid 285.887922 -141.09446)
		(end 286.436562 -141.6431)
		(stroke
			(width 0.2)
			(type default)
		)
		(layer "In3.Cu")
	)
	(gr_line
		(start 286.436562 -138.043158)
		(end 287.83661 -138.043158)
		(stroke
			(width 0.2)
			(type default)
		)
		(layer "In3.Cu")
	)
	(gr_arc
		(start 286.436562 -136.945878)
		(mid 285.887922 -137.494518)
		(end 286.436562 -138.043158)
		(stroke
			(width 0.2)
			(type default)
		)
		(layer "In3.Cu")
	)
	(gr_line
		(start 286.436562 -134.442962)
		(end 287.83661 -134.442962)
		(stroke
			(width 0.2)
			(type default)
		)
		(layer "In3.Cu")
	)
	(gr_arc
		(start 286.436562 -133.345682)
		(mid 285.887922 -133.894322)
		(end 286.436562 -134.442962)
		(stroke
			(width 0.2)
			(type default)
		)
		(layer "In3.Cu")
	)
	(gr_line
		(start 286.436816 -223.682306)
		(end 286.436562 -223.682306)
		(stroke
			(width 0.2)
			(type default)
		)
		(layer "In3.Cu")
	)
	(gr_arc
		(start 286.836612 -237.44301)
		(mid 287.385252 -236.89437)
		(end 286.836612 -236.34573)
		(stroke
			(width 0.2)
			(type default)
		)
		(layer "In3.Cu")
	)
	(gr_line
		(start 286.836612 -236.34573)
		(end 285.436564 -236.34573)
		(stroke
			(width 0.2)
			(type default)
		)
		(layer "In3.Cu")
	)
	(gr_arc
		(start 286.836612 -233.843068)
		(mid 287.385252 -233.294428)
		(end 286.836612 -232.745788)
		(stroke
			(width 0.2)
			(type default)
		)
		(layer "In3.Cu")
	)
	(gr_line
		(start 286.836612 -232.745788)
		(end 285.436564 -232.745788)
		(stroke
			(width 0.2)
			(type default)
		)
		(layer "In3.Cu")
	)
	(gr_arc
		(start 286.836612 -230.243126)
		(mid 287.385252 -229.694486)
		(end 286.836612 -229.145846)
		(stroke
			(width 0.2)
			(type default)
		)
		(layer "In3.Cu")
	)
	(gr_line
		(start 286.836612 -229.145846)
		(end 285.436564 -229.145846)
		(stroke
			(width 0.2)
			(type default)
		)
		(layer "In3.Cu")
	)
	(gr_arc
		(start 286.836612 -226.643184)
		(mid 287.385252 -226.094544)
		(end 286.836612 -225.545904)
		(stroke
			(width 0.2)
			(type default)
		)
		(layer "In3.Cu")
	)
	(gr_line
		(start 286.836612 -225.545904)
		(end 285.436564 -225.545904)
		(stroke
			(width 0.2)
			(type default)
		)
		(layer "In3.Cu")
	)
	(gr_arc
		(start 286.836612 -223.042988)
		(mid 287.385252 -222.494348)
		(end 286.836612 -221.945708)
		(stroke
			(width 0.2)
			(type default)
		)
		(layer "In3.Cu")
	)
	(gr_line
		(start 286.836612 -221.945708)
		(end 285.436564 -221.945708)
		(stroke
			(width 0.2)
			(type default)
		)
		(layer "In3.Cu")
	)
	(gr_arc
		(start 286.836612 -219.443046)
		(mid 287.385252 -218.894406)
		(end 286.836612 -218.345766)
		(stroke
			(width 0.2)
			(type default)
		)
		(layer "In3.Cu")
	)
	(gr_line
		(start 286.836612 -218.345766)
		(end 285.436564 -218.345766)
		(stroke
			(width 0.2)
			(type default)
		)
		(layer "In3.Cu")
	)
	(gr_arc
		(start 286.836612 -215.843104)
		(mid 287.385252 -215.294464)
		(end 286.836612 -214.745824)
		(stroke
			(width 0.2)
			(type default)
		)
		(layer "In3.Cu")
	)
	(gr_line
		(start 286.836612 -214.745824)
		(end 285.436564 -214.745824)
		(stroke
			(width 0.2)
			(type default)
		)
		(layer "In3.Cu")
	)
	(gr_arc
		(start 286.836612 -212.243162)
		(mid 287.385252 -211.694522)
		(end 286.836612 -211.145882)
		(stroke
			(width 0.2)
			(type default)
		)
		(layer "In3.Cu")
	)
	(gr_line
		(start 286.836612 -211.145882)
		(end 285.436564 -211.145882)
		(stroke
			(width 0.2)
			(type default)
		)
		(layer "In3.Cu")
	)
	(gr_arc
		(start 286.836612 -208.64322)
		(mid 287.385252 -208.09458)
		(end 286.836612 -207.54594)
		(stroke
			(width 0.2)
			(type default)
		)
		(layer "In3.Cu")
	)
	(gr_line
		(start 286.836612 -207.54594)
		(end 285.436564 -207.54594)
		(stroke
			(width 0.2)
			(type default)
		)
		(layer "In3.Cu")
	)
	(gr_arc
		(start 286.836612 -205.043024)
		(mid 287.385252 -204.494384)
		(end 286.836612 -203.945744)
		(stroke
			(width 0.2)
			(type default)
		)
		(layer "In3.Cu")
	)
	(gr_line
		(start 286.836612 -203.945744)
		(end 285.436564 -203.945744)
		(stroke
			(width 0.2)
			(type default)
		)
		(layer "In3.Cu")
	)
	(gr_arc
		(start 286.836612 -201.443082)
		(mid 287.385252 -200.894442)
		(end 286.836612 -200.345802)
		(stroke
			(width 0.2)
			(type default)
		)
		(layer "In3.Cu")
	)
	(gr_line
		(start 286.836612 -200.345802)
		(end 285.436564 -200.345802)
		(stroke
			(width 0.2)
			(type default)
		)
		(layer "In3.Cu")
	)
	(gr_arc
		(start 286.836612 -197.84314)
		(mid 287.385252 -197.2945)
		(end 286.836612 -196.74586)
		(stroke
			(width 0.2)
			(type default)
		)
		(layer "In3.Cu")
	)
	(gr_line
		(start 286.836612 -196.74586)
		(end 285.436564 -196.74586)
		(stroke
			(width 0.2)
			(type default)
		)
		(layer "In3.Cu")
	)
	(gr_arc
		(start 286.836612 -194.243198)
		(mid 287.385252 -193.694558)
		(end 286.836612 -193.145918)
		(stroke
			(width 0.2)
			(type default)
		)
		(layer "In3.Cu")
	)
	(gr_line
		(start 286.836612 -193.145918)
		(end 285.436564 -193.145918)
		(stroke
			(width 0.2)
			(type default)
		)
		(layer "In3.Cu")
	)
	(gr_arc
		(start 286.836612 -190.643002)
		(mid 287.385252 -190.094362)
		(end 286.836612 -189.545722)
		(stroke
			(width 0.2)
			(type default)
		)
		(layer "In3.Cu")
	)
	(gr_line
		(start 286.836612 -189.545722)
		(end 285.436564 -189.545722)
		(stroke
			(width 0.2)
			(type default)
		)
		(layer "In3.Cu")
	)
	(gr_arc
		(start 286.836612 -187.04306)
		(mid 287.385252 -186.49442)
		(end 286.836612 -185.94578)
		(stroke
			(width 0.2)
			(type default)
		)
		(layer "In3.Cu")
	)
	(gr_line
		(start 286.836612 -185.94578)
		(end 285.436564 -185.94578)
		(stroke
			(width 0.2)
			(type default)
		)
		(layer "In3.Cu")
	)
	(gr_arc
		(start 286.836612 -183.443118)
		(mid 287.385252 -182.894478)
		(end 286.836612 -182.345838)
		(stroke
			(width 0.2)
			(type default)
		)
		(layer "In3.Cu")
	)
	(gr_line
		(start 286.836612 -182.345838)
		(end 285.436564 -182.345838)
		(stroke
			(width 0.2)
			(type default)
		)
		(layer "In3.Cu")
	)
	(gr_arc
		(start 286.836612 -179.843176)
		(mid 287.385252 -179.294536)
		(end 286.836612 -178.745896)
		(stroke
			(width 0.2)
			(type default)
		)
		(layer "In3.Cu")
	)
	(gr_line
		(start 286.836612 -178.745896)
		(end 285.436564 -178.745896)
		(stroke
			(width 0.2)
			(type default)
		)
		(layer "In3.Cu")
	)
	(gr_arc
		(start 286.836612 -176.243234)
		(mid 287.385252 -175.694594)
		(end 286.836612 -175.145954)
		(stroke
			(width 0.2)
			(type default)
		)
		(layer "In3.Cu")
	)
	(gr_line
		(start 286.836612 -175.145954)
		(end 285.436564 -175.145954)
		(stroke
			(width 0.2)
			(type default)
		)
		(layer "In3.Cu")
	)
	(gr_arc
		(start 286.836612 -143.442944)
		(mid 287.385252 -142.894304)
		(end 286.836612 -142.345664)
		(stroke
			(width 0.2)
			(type default)
		)
		(layer "In3.Cu")
	)
	(gr_line
		(start 286.836612 -142.345664)
		(end 285.436564 -142.345664)
		(stroke
			(width 0.2)
			(type default)
		)
		(layer "In3.Cu")
	)
	(gr_arc
		(start 286.836612 -139.843002)
		(mid 287.385252 -139.294362)
		(end 286.836612 -138.745722)
		(stroke
			(width 0.2)
			(type default)
		)
		(layer "In3.Cu")
	)
	(gr_line
		(start 286.836612 -138.745722)
		(end 285.436564 -138.745722)
		(stroke
			(width 0.2)
			(type default)
		)
		(layer "In3.Cu")
	)
	(gr_arc
		(start 286.836612 -136.24306)
		(mid 287.385252 -135.69442)
		(end 286.836612 -135.14578)
		(stroke
			(width 0.2)
			(type default)
		)
		(layer "In3.Cu")
	)
	(gr_line
		(start 286.836612 -135.14578)
		(end 285.436564 -135.14578)
		(stroke
			(width 0.2)
			(type default)
		)
		(layer "In3.Cu")
	)
	(gr_arc
		(start 286.836612 -132.643118)
		(mid 287.385252 -132.094478)
		(end 286.836612 -131.545838)
		(stroke
			(width 0.2)
			(type default)
		)
		(layer "In3.Cu")
	)
	(gr_line
		(start 286.836612 -131.545838)
		(end 285.436564 -131.545838)
		(stroke
			(width 0.2)
			(type default)
		)
		(layer "In3.Cu")
	)
	(gr_arc
		(start 287.83661 -239.243108)
		(mid 288.38525 -238.694468)
		(end 287.83661 -238.145828)
		(stroke
			(width 0.2)
			(type default)
		)
		(layer "In3.Cu")
	)
	(gr_line
		(start 287.83661 -238.145828)
		(end 286.436562 -238.145828)
		(stroke
			(width 0.2)
			(type default)
		)
		(layer "In3.Cu")
	)
	(gr_arc
		(start 287.83661 -235.643166)
		(mid 288.38525 -235.094526)
		(end 287.83661 -234.545886)
		(stroke
			(width 0.2)
			(type default)
		)
		(layer "In3.Cu")
	)
	(gr_line
		(start 287.83661 -234.545886)
		(end 286.436562 -234.545886)
		(stroke
			(width 0.2)
			(type default)
		)
		(layer "In3.Cu")
	)
	(gr_arc
		(start 287.83661 -232.043224)
		(mid 288.38525 -231.494584)
		(end 287.83661 -230.945944)
		(stroke
			(width 0.2)
			(type default)
		)
		(layer "In3.Cu")
	)
	(gr_line
		(start 287.83661 -230.945944)
		(end 286.436562 -230.945944)
		(stroke
			(width 0.2)
			(type default)
		)
		(layer "In3.Cu")
	)
	(gr_arc
		(start 287.83661 -228.443028)
		(mid 288.38525 -227.894388)
		(end 287.83661 -227.345748)
		(stroke
			(width 0.2)
			(type default)
		)
		(layer "In3.Cu")
	)
	(gr_line
		(start 287.83661 -227.345748)
		(end 286.436562 -227.345748)
		(stroke
			(width 0.2)
			(type default)
		)
		(layer "In3.Cu")
	)
	(gr_arc
		(start 287.83661 -224.906586)
		(mid 288.44875 -224.294446)
		(end 287.83661 -223.682306)
		(stroke
			(width 0.2)
			(type default)
		)
		(layer "In3.Cu")
	)
	(gr_line
		(start 287.83661 -223.682306)
		(end 286.436816 -223.682306)
		(stroke
			(width 0.2)
			(type default)
		)
		(layer "In3.Cu")
	)
	(gr_arc
		(start 287.83661 -221.243144)
		(mid 288.38525 -220.694504)
		(end 287.83661 -220.145864)
		(stroke
			(width 0.2)
			(type default)
		)
		(layer "In3.Cu")
	)
	(gr_line
		(start 287.83661 -220.145864)
		(end 286.436562 -220.145864)
		(stroke
			(width 0.2)
			(type default)
		)
		(layer "In3.Cu")
	)
	(gr_arc
		(start 287.83661 -217.643202)
		(mid 288.38525 -217.094562)
		(end 287.83661 -216.545922)
		(stroke
			(width 0.2)
			(type default)
		)
		(layer "In3.Cu")
	)
	(gr_line
		(start 287.83661 -216.545922)
		(end 286.436562 -216.545922)
		(stroke
			(width 0.2)
			(type default)
		)
		(layer "In3.Cu")
	)
	(gr_arc
		(start 287.83661 -214.043006)
		(mid 288.38525 -213.494366)
		(end 287.83661 -212.945726)
		(stroke
			(width 0.2)
			(type default)
		)
		(layer "In3.Cu")
	)
	(gr_line
		(start 287.83661 -212.945726)
		(end 286.436562 -212.945726)
		(stroke
			(width 0.2)
			(type default)
		)
		(layer "In3.Cu")
	)
	(gr_arc
		(start 287.83661 -210.443064)
		(mid 288.38525 -209.894424)
		(end 287.83661 -209.345784)
		(stroke
			(width 0.2)
			(type default)
		)
		(layer "In3.Cu")
	)
	(gr_line
		(start 287.83661 -209.345784)
		(end 286.436562 -209.345784)
		(stroke
			(width 0.2)
			(type default)
		)
		(layer "In3.Cu")
	)
	(gr_arc
		(start 287.83661 -206.843122)
		(mid 288.38525 -206.294482)
		(end 287.83661 -205.745842)
		(stroke
			(width 0.2)
			(type default)
		)
		(layer "In3.Cu")
	)
	(gr_line
		(start 287.83661 -205.745842)
		(end 286.436562 -205.745842)
		(stroke
			(width 0.2)
			(type default)
		)
		(layer "In3.Cu")
	)
	(gr_arc
		(start 287.83661 -203.24318)
		(mid 288.38525 -202.69454)
		(end 287.83661 -202.1459)
		(stroke
			(width 0.2)
			(type default)
		)
		(layer "In3.Cu")
	)
	(gr_line
		(start 287.83661 -202.1459)
		(end 286.436562 -202.1459)
		(stroke
			(width 0.2)
			(type default)
		)
		(layer "In3.Cu")
	)
	(gr_arc
		(start 287.83661 -199.642984)
		(mid 288.38525 -199.094344)
		(end 287.83661 -198.545704)
		(stroke
			(width 0.2)
			(type default)
		)
		(layer "In3.Cu")
	)
	(gr_line
		(start 287.83661 -198.545704)
		(end 286.436562 -198.545704)
		(stroke
			(width 0.2)
			(type default)
		)
		(layer "In3.Cu")
	)
	(gr_arc
		(start 287.83661 -196.043042)
		(mid 288.38525 -195.494402)
		(end 287.83661 -194.945762)
		(stroke
			(width 0.2)
			(type default)
		)
		(layer "In3.Cu")
	)
	(gr_line
		(start 287.83661 -194.945762)
		(end 286.436562 -194.945762)
		(stroke
			(width 0.2)
			(type default)
		)
		(layer "In3.Cu")
	)
	(gr_arc
		(start 287.83661 -192.4431)
		(mid 288.38525 -191.89446)
		(end 287.83661 -191.34582)
		(stroke
			(width 0.2)
			(type default)
		)
		(layer "In3.Cu")
	)
	(gr_line
		(start 287.83661 -191.34582)
		(end 286.436562 -191.34582)
		(stroke
			(width 0.2)
			(type default)
		)
		(layer "In3.Cu")
	)
	(gr_arc
		(start 287.83661 -188.843158)
		(mid 288.38525 -188.294518)
		(end 287.83661 -187.745878)
		(stroke
			(width 0.2)
			(type default)
		)
		(layer "In3.Cu")
	)
	(gr_line
		(start 287.83661 -187.745878)
		(end 286.436562 -187.745878)
		(stroke
			(width 0.2)
			(type default)
		)
		(layer "In3.Cu")
	)
	(gr_arc
		(start 287.83661 -185.243216)
		(mid 288.38525 -184.694576)
		(end 287.83661 -184.145936)
		(stroke
			(width 0.2)
			(type default)
		)
		(layer "In3.Cu")
	)
	(gr_line
		(start 287.83661 -184.145936)
		(end 286.436562 -184.145936)
		(stroke
			(width 0.2)
			(type default)
		)
		(layer "In3.Cu")
	)
	(gr_arc
		(start 287.83661 -181.64302)
		(mid 288.38525 -181.09438)
		(end 287.83661 -180.54574)
		(stroke
			(width 0.2)
			(type default)
		)
		(layer "In3.Cu")
	)
	(gr_line
		(start 287.83661 -180.54574)
		(end 286.436562 -180.54574)
		(stroke
			(width 0.2)
			(type default)
		)
		(layer "In3.Cu")
	)
	(gr_arc
		(start 287.83661 -178.043078)
		(mid 288.38525 -177.494438)
		(end 287.83661 -176.945798)
		(stroke
			(width 0.2)
			(type default)
		)
		(layer "In3.Cu")
	)
	(gr_line
		(start 287.83661 -176.945798)
		(end 286.436562 -176.945798)
		(stroke
			(width 0.2)
			(type default)
		)
		(layer "In3.Cu")
	)
	(gr_arc
		(start 287.83661 -145.243042)
		(mid 288.38525 -144.694402)
		(end 287.83661 -144.145762)
		(stroke
			(width 0.2)
			(type default)
		)
		(layer "In3.Cu")
	)
	(gr_line
		(start 287.83661 -144.145762)
		(end 286.436562 -144.145762)
		(stroke
			(width 0.2)
			(type default)
		)
		(layer "In3.Cu")
	)
	(gr_arc
		(start 287.83661 -141.6431)
		(mid 288.38525 -141.09446)
		(end 287.83661 -140.54582)
		(stroke
			(width 0.2)
			(type default)
		)
		(layer "In3.Cu")
	)
	(gr_line
		(start 287.83661 -140.54582)
		(end 286.436562 -140.54582)
		(stroke
			(width 0.2)
			(type default)
		)
		(layer "In3.Cu")
	)
	(gr_arc
		(start 287.83661 -138.043158)
		(mid 288.38525 -137.494518)
		(end 287.83661 -136.945878)
		(stroke
			(width 0.2)
			(type default)
		)
		(layer "In3.Cu")
	)
	(gr_line
		(start 287.83661 -136.945878)
		(end 286.436562 -136.945878)
		(stroke
			(width 0.2)
			(type default)
		)
		(layer "In3.Cu")
	)
	(gr_arc
		(start 287.83661 -134.442962)
		(mid 288.38525 -133.894322)
		(end 287.83661 -133.345682)
		(stroke
			(width 0.2)
			(type default)
		)
		(layer "In3.Cu")
	)
	(gr_line
		(start 287.83661 -133.345682)
		(end 286.436562 -133.345682)
		(stroke
			(width 0.2)
			(type default)
		)
		(layer "In3.Cu")
	)
	(gr_line
		(start 289.1028 -130.0988)
		(end 275.3868 -130.0988)
		(stroke
			(width 0.381)
			(type default)
		)
		(layer "In3.Cu")
	)
	(gr_line
		(start 289.4584 -174.1678)
		(end 276.5298 -174.1678)
		(stroke
			(width 0.381)
			(type default)
		)
		(layer "In3.Cu")
	)
	(gr_line
		(start 289.4838 -146.8374)
		(end 290.3728 -145.9484)
		(stroke
			(width 0.381)
			(type default)
		)
		(layer "In3.Cu")
	)
	(gr_line
		(start 289.8648 -240.3348)
		(end 290.9316 -239.268)
		(stroke
			(width 0.381)
			(type default)
		)
		(layer "In3.Cu")
	)
	(gr_line
		(start 290.3728 -145.9484)
		(end 290.3728 -131.3688)
		(stroke
			(width 0.381)
			(type default)
		)
		(layer "In3.Cu")
	)
	(gr_line
		(start 290.3728 -131.3688)
		(end 289.1028 -130.0988)
		(stroke
			(width 0.381)
			(type default)
		)
		(layer "In3.Cu")
	)
	(gr_line
		(start 290.9316 -239.268)
		(end 290.9316 -175.641)
		(stroke
			(width 0.381)
			(type default)
		)
		(layer "In3.Cu")
	)
	(gr_line
		(start 290.9316 -175.641)
		(end 289.4584 -174.1678)
		(stroke
			(width 0.381)
			(type default)
		)
		(layer "In3.Cu")
	)
	(gr_arc
		(start 306.649882 -385.99999)
		(mid 307.356987 -385.707097)
		(end 307.64988 -384.999992)
		(stroke
			(width 2.54)
			(type default)
		)
		(layer "In3.Cu")
	)
	(gr_line
		(start 307.64988 -384.999992)
		(end 307.64988 -383.29997)
		(stroke
			(width 2.54)
			(type default)
		)
		(layer "In3.Cu")
	)
	(gr_arc
		(start 308.649878 -382.299972)
		(mid 307.942776 -382.592871)
		(end 307.64988 -383.29997)
		(stroke
			(width 2.54)
			(type default)
		)
		(layer "In3.Cu")
	)
	(gr_line
		(start 308.649878 -382.299972)
		(end 315.149992 -382.299972)
		(stroke
			(width 2.54)
			(type default)
		)
		(layer "In3.Cu")
	)
	(gr_line
		(start 309.999888 -48.200056)
		(end 269.999968 -48.200056)
		(stroke
			(width 2.54)
			(type default)
		)
		(layer "In3.Cu")
	)
	(gr_arc
		(start 309.999888 -48.200056)
		(mid 310.706986 -47.907165)
		(end 310.999886 -47.200058)
		(stroke
			(width 2.54)
			(type default)
		)
		(layer "In3.Cu")
	)
	(gr_line
		(start 310.999886 -0.999998)
		(end 310.999886 -47.200058)
		(stroke
			(width 2.54)
			(type default)
		)
		(layer "In3.Cu")
	)
	(gr_arc
		(start 311.999884 0)
		(mid 311.292779 -0.292893)
		(end 310.999886 -0.999998)
		(stroke
			(width 2.54)
			(type default)
		)
		(layer "In3.Cu")
	)
	(gr_arc
		(start 316.14999 -384.999992)
		(mid 316.442883 -385.707097)
		(end 317.149988 -385.99999)
		(stroke
			(width 2.54)
			(type default)
		)
		(layer "In3.Cu")
	)
	(gr_arc
		(start 316.14999 -383.29997)
		(mid 315.857086 -382.592887)
		(end 315.149992 -382.299972)
		(stroke
			(width 2.54)
			(type default)
		)
		(layer "In3.Cu")
	)
	(gr_line
		(start 316.14999 -383.29997)
		(end 316.14999 -384.999992)
		(stroke
			(width 2.54)
			(type default)
		)
		(layer "In3.Cu")
	)
	(gr_line
		(start 317.149988 -385.99999)
		(end 362.700062 -385.99999)
		(stroke
			(width 2.54)
			(type default)
		)
		(layer "In3.Cu")
	)
	(gr_arc
		(start 318.91732 -245.45544)
		(mid 319.402333 -245.940834)
		(end 319.8876 -245.455694)
		(stroke
			(width 0.2)
			(type default)
		)
		(layer "In3.Cu")
	)
	(gr_line
		(start 318.91732 -244.312694)
		(end 318.91732 -245.45544)
		(stroke
			(width 0.2)
			(type default)
		)
		(layer "In3.Cu")
	)
	(gr_line
		(start 319.2145 -129.112264)
		(end 320.3575 -129.112264)
		(stroke
			(width 0.2)
			(type default)
		)
		(layer "In3.Cu")
	)
	(gr_line
		(start 319.2145 -14.11224)
		(end 320.3575 -14.11224)
		(stroke
			(width 0.2)
			(type default)
		)
		(layer "In3.Cu")
	)
	(gr_arc
		(start 319.214754 -128.141984)
		(mid 318.72936 -128.626997)
		(end 319.2145 -129.112264)
		(stroke
			(width 0.2)
			(type default)
		)
		(layer "In3.Cu")
	)
	(gr_arc
		(start 319.214754 -13.14196)
		(mid 318.72936 -13.626973)
		(end 319.2145 -14.11224)
		(stroke
			(width 0.2)
			(type default)
		)
		(layer "In3.Cu")
	)
	(gr_line
		(start 319.8876 -245.455694)
		(end 319.8876 -244.312694)
		(stroke
			(width 0.2)
			(type default)
		)
		(layer "In3.Cu")
	)
	(gr_arc
		(start 319.8876 -244.312694)
		(mid 319.40246 -243.827554)
		(end 318.91732 -244.312694)
		(stroke
			(width 0.2)
			(type default)
		)
		(layer "In3.Cu")
	)
	(gr_arc
		(start 320.3575 -129.112264)
		(mid 320.84264 -128.627124)
		(end 320.3575 -128.141984)
		(stroke
			(width 0.2)
			(type default)
		)
		(layer "In3.Cu")
	)
	(gr_line
		(start 320.3575 -128.141984)
		(end 319.214754 -128.141984)
		(stroke
			(width 0.2)
			(type default)
		)
		(layer "In3.Cu")
	)
	(gr_arc
		(start 320.3575 -14.11224)
		(mid 320.84264 -13.6271)
		(end 320.3575 -13.14196)
		(stroke
			(width 0.2)
			(type default)
		)
		(layer "In3.Cu")
	)
	(gr_line
		(start 320.3575 -13.14196)
		(end 319.214754 -13.14196)
		(stroke
			(width 0.2)
			(type default)
		)
		(layer "In3.Cu")
	)
	(gr_line
		(start 322.6816 -132.922264)
		(end 323.951346 -132.922264)
		(stroke
			(width 0.2)
			(type default)
		)
		(layer "In3.Cu")
	)
	(gr_arc
		(start 322.6816 -131.951984)
		(mid 322.19646 -132.437124)
		(end 322.6816 -132.922264)
		(stroke
			(width 0.2)
			(type default)
		)
		(layer "In3.Cu")
	)
	(gr_line
		(start 322.6816 -17.92224)
		(end 323.951346 -17.92224)
		(stroke
			(width 0.2)
			(type default)
		)
		(layer "In3.Cu")
	)
	(gr_arc
		(start 322.6816 -16.95196)
		(mid 322.19646 -17.4371)
		(end 322.6816 -17.92224)
		(stroke
			(width 0.2)
			(type default)
		)
		(layer "In3.Cu")
	)
	(gr_arc
		(start 323.10451 -249.385074)
		(mid 323.58965 -249.870214)
		(end 324.07479 -249.385074)
		(stroke
			(width 0.2)
			(type default)
		)
		(layer "In3.Cu")
	)
	(gr_line
		(start 323.10451 -248.115074)
		(end 323.10451 -249.385074)
		(stroke
			(width 0.2)
			(type default)
		)
		(layer "In3.Cu")
	)
	(gr_arc
		(start 323.951346 -132.922264)
		(mid 324.43674 -132.437251)
		(end 323.9516 -131.951984)
		(stroke
			(width 0.2)
			(type default)
		)
		(layer "In3.Cu")
	)
	(gr_arc
		(start 323.951346 -17.92224)
		(mid 324.43674 -17.437227)
		(end 323.9516 -16.95196)
		(stroke
			(width 0.2)
			(type default)
		)
		(layer "In3.Cu")
	)
	(gr_line
		(start 323.9516 -131.951984)
		(end 322.6816 -131.951984)
		(stroke
			(width 0.2)
			(type default)
		)
		(layer "In3.Cu")
	)
	(gr_line
		(start 323.9516 -16.95196)
		(end 322.6816 -16.95196)
		(stroke
			(width 0.2)
			(type default)
		)
		(layer "In3.Cu")
	)
	(gr_line
		(start 324.07479 -249.385074)
		(end 324.07479 -248.115328)
		(stroke
			(width 0.2)
			(type default)
		)
		(layer "In3.Cu")
	)
	(gr_arc
		(start 324.07479 -248.115328)
		(mid 323.589777 -247.629934)
		(end 323.10451 -248.115074)
		(stroke
			(width 0.2)
			(type default)
		)
		(layer "In3.Cu")
	)
	(gr_arc
		(start 350.457262 -245.46052)
		(mid 350.942275 -245.945914)
		(end 351.427542 -245.460774)
		(stroke
			(width 0.2)
			(type default)
		)
		(layer "In3.Cu")
	)
	(gr_line
		(start 350.457262 -244.317774)
		(end 350.457262 -245.46052)
		(stroke
			(width 0.2)
			(type default)
		)
		(layer "In3.Cu")
	)
	(gr_line
		(start 350.764602 -129.112264)
		(end 351.907602 -129.112264)
		(stroke
			(width 0.2)
			(type default)
		)
		(layer "In3.Cu")
	)
	(gr_line
		(start 350.764602 -14.11224)
		(end 351.907602 -14.11224)
		(stroke
			(width 0.2)
			(type default)
		)
		(layer "In3.Cu")
	)
	(gr_arc
		(start 350.764856 -128.141984)
		(mid 350.279462 -128.626997)
		(end 350.764602 -129.112264)
		(stroke
			(width 0.2)
			(type default)
		)
		(layer "In3.Cu")
	)
	(gr_arc
		(start 350.764856 -13.14196)
		(mid 350.279462 -13.626973)
		(end 350.764602 -14.11224)
		(stroke
			(width 0.2)
			(type default)
		)
		(layer "In3.Cu")
	)
	(gr_line
		(start 351.427542 -245.460774)
		(end 351.427542 -244.317774)
		(stroke
			(width 0.2)
			(type default)
		)
		(layer "In3.Cu")
	)
	(gr_arc
		(start 351.427542 -244.317774)
		(mid 350.942402 -243.832634)
		(end 350.457262 -244.317774)
		(stroke
			(width 0.2)
			(type default)
		)
		(layer "In3.Cu")
	)
	(gr_arc
		(start 351.907602 -129.112264)
		(mid 352.392742 -128.627124)
		(end 351.907602 -128.141984)
		(stroke
			(width 0.2)
			(type default)
		)
		(layer "In3.Cu")
	)
	(gr_line
		(start 351.907602 -128.141984)
		(end 350.764856 -128.141984)
		(stroke
			(width 0.2)
			(type default)
		)
		(layer "In3.Cu")
	)
	(gr_arc
		(start 351.907602 -14.11224)
		(mid 352.392742 -13.6271)
		(end 351.907602 -13.14196)
		(stroke
			(width 0.2)
			(type default)
		)
		(layer "In3.Cu")
	)
	(gr_line
		(start 351.907602 -13.14196)
		(end 350.764856 -13.14196)
		(stroke
			(width 0.2)
			(type default)
		)
		(layer "In3.Cu")
	)
	(gr_line
		(start 354.231702 -132.922264)
		(end 355.501702 -132.922264)
		(stroke
			(width 0.2)
			(type default)
		)
		(layer "In3.Cu")
	)
	(gr_line
		(start 354.231702 -17.92224)
		(end 355.501702 -17.92224)
		(stroke
			(width 0.2)
			(type default)
		)
		(layer "In3.Cu")
	)
	(gr_arc
		(start 354.231956 -131.951984)
		(mid 353.746562 -132.436997)
		(end 354.231702 -132.922264)
		(stroke
			(width 0.2)
			(type default)
		)
		(layer "In3.Cu")
	)
	(gr_arc
		(start 354.231956 -16.95196)
		(mid 353.746562 -17.436973)
		(end 354.231702 -17.92224)
		(stroke
			(width 0.2)
			(type default)
		)
		(layer "In3.Cu")
	)
	(gr_arc
		(start 354.654612 -249.385074)
		(mid 355.139752 -249.870214)
		(end 355.624892 -249.385074)
		(stroke
			(width 0.2)
			(type default)
		)
		(layer "In3.Cu")
	)
	(gr_line
		(start 354.654612 -248.115074)
		(end 354.654612 -249.385074)
		(stroke
			(width 0.2)
			(type default)
		)
		(layer "In3.Cu")
	)
	(gr_arc
		(start 355.501702 -132.922264)
		(mid 355.986842 -132.437124)
		(end 355.501702 -131.951984)
		(stroke
			(width 0.2)
			(type default)
		)
		(layer "In3.Cu")
	)
	(gr_line
		(start 355.501702 -131.951984)
		(end 354.231956 -131.951984)
		(stroke
			(width 0.2)
			(type default)
		)
		(layer "In3.Cu")
	)
	(gr_arc
		(start 355.501702 -17.92224)
		(mid 355.986842 -17.4371)
		(end 355.501702 -16.95196)
		(stroke
			(width 0.2)
			(type default)
		)
		(layer "In3.Cu")
	)
	(gr_line
		(start 355.501702 -16.95196)
		(end 354.231956 -16.95196)
		(stroke
			(width 0.2)
			(type default)
		)
		(layer "In3.Cu")
	)
	(gr_line
		(start 355.624892 -249.385074)
		(end 355.624892 -248.115328)
		(stroke
			(width 0.2)
			(type default)
		)
		(layer "In3.Cu")
	)
	(gr_arc
		(start 355.624892 -248.115328)
		(mid 355.139879 -247.629934)
		(end 354.654612 -248.115074)
		(stroke
			(width 0.2)
			(type default)
		)
		(layer "In3.Cu")
	)
	(gr_arc
		(start 362.700062 -385.99999)
		(mid 363.407167 -385.707097)
		(end 363.70006 -384.999992)
		(stroke
			(width 2.54)
			(type default)
		)
		(layer "In3.Cu")
	)
	(gr_line
		(start 363.70006 -384.999992)
		(end 363.70006 -381)
		(stroke
			(width 2.54)
			(type default)
		)
		(layer "In3.Cu")
	)
	(gr_arc
		(start 364.700058 -380.000002)
		(mid 363.99298 -380.292909)
		(end 363.70006 -381)
		(stroke
			(width 2.54)
			(type default)
		)
		(layer "In3.Cu")
	)
	(gr_line
		(start 364.700058 -380.000002)
		(end 416.699954 -380.000002)
		(stroke
			(width 2.54)
			(type default)
		)
		(layer "In3.Cu")
	)
	(gr_arc
		(start 382.00711 -245.44528)
		(mid 382.492123 -245.930674)
		(end 382.97739 -245.445534)
		(stroke
			(width 0.2)
			(type default)
		)
		(layer "In3.Cu")
	)
	(gr_line
		(start 382.00711 -244.302534)
		(end 382.00711 -245.44528)
		(stroke
			(width 0.2)
			(type default)
		)
		(layer "In3.Cu")
	)
	(gr_line
		(start 382.31445 -129.112264)
		(end 383.45745 -129.112264)
		(stroke
			(width 0.2)
			(type default)
		)
		(layer "In3.Cu")
	)
	(gr_line
		(start 382.31445 -14.11224)
		(end 383.45745 -14.11224)
		(stroke
			(width 0.2)
			(type default)
		)
		(layer "In3.Cu")
	)
	(gr_arc
		(start 382.314704 -128.141984)
		(mid 381.82931 -128.626997)
		(end 382.31445 -129.112264)
		(stroke
			(width 0.2)
			(type default)
		)
		(layer "In3.Cu")
	)
	(gr_arc
		(start 382.314704 -13.14196)
		(mid 381.82931 -13.626973)
		(end 382.31445 -14.11224)
		(stroke
			(width 0.2)
			(type default)
		)
		(layer "In3.Cu")
	)
	(gr_line
		(start 382.97739 -245.445534)
		(end 382.97739 -244.302534)
		(stroke
			(width 0.2)
			(type default)
		)
		(layer "In3.Cu")
	)
	(gr_arc
		(start 382.97739 -244.302534)
		(mid 382.49225 -243.817394)
		(end 382.00711 -244.302534)
		(stroke
			(width 0.2)
			(type default)
		)
		(layer "In3.Cu")
	)
	(gr_arc
		(start 383.45745 -129.112264)
		(mid 383.94259 -128.627124)
		(end 383.45745 -128.141984)
		(stroke
			(width 0.2)
			(type default)
		)
		(layer "In3.Cu")
	)
	(gr_line
		(start 383.45745 -128.141984)
		(end 382.314704 -128.141984)
		(stroke
			(width 0.2)
			(type default)
		)
		(layer "In3.Cu")
	)
	(gr_arc
		(start 383.45745 -14.11224)
		(mid 383.94259 -13.6271)
		(end 383.45745 -13.14196)
		(stroke
			(width 0.2)
			(type default)
		)
		(layer "In3.Cu")
	)
	(gr_line
		(start 383.45745 -13.14196)
		(end 382.314704 -13.14196)
		(stroke
			(width 0.2)
			(type default)
		)
		(layer "In3.Cu")
	)
	(gr_line
		(start 385.78155 -132.922264)
		(end 387.051296 -132.922264)
		(stroke
			(width 0.2)
			(type default)
		)
		(layer "In3.Cu")
	)
	(gr_arc
		(start 385.78155 -131.951984)
		(mid 385.29641 -132.437124)
		(end 385.78155 -132.922264)
		(stroke
			(width 0.2)
			(type default)
		)
		(layer "In3.Cu")
	)
	(gr_line
		(start 385.78155 -17.92224)
		(end 387.051296 -17.92224)
		(stroke
			(width 0.2)
			(type default)
		)
		(layer "In3.Cu")
	)
	(gr_arc
		(start 385.78155 -16.95196)
		(mid 385.29641 -17.4371)
		(end 385.78155 -17.92224)
		(stroke
			(width 0.2)
			(type default)
		)
		(layer "In3.Cu")
	)
	(gr_arc
		(start 386.20446 -249.385074)
		(mid 386.6896 -249.870214)
		(end 387.17474 -249.385074)
		(stroke
			(width 0.2)
			(type default)
		)
		(layer "In3.Cu")
	)
	(gr_line
		(start 386.20446 -248.115074)
		(end 386.20446 -249.385074)
		(stroke
			(width 0.2)
			(type default)
		)
		(layer "In3.Cu")
	)
	(gr_arc
		(start 387.051296 -132.922264)
		(mid 387.53669 -132.437251)
		(end 387.05155 -131.951984)
		(stroke
			(width 0.2)
			(type default)
		)
		(layer "In3.Cu")
	)
	(gr_arc
		(start 387.051296 -17.92224)
		(mid 387.53669 -17.437227)
		(end 387.05155 -16.95196)
		(stroke
			(width 0.2)
			(type default)
		)
		(layer "In3.Cu")
	)
	(gr_line
		(start 387.05155 -131.951984)
		(end 385.78155 -131.951984)
		(stroke
			(width 0.2)
			(type default)
		)
		(layer "In3.Cu")
	)
	(gr_line
		(start 387.05155 -16.95196)
		(end 385.78155 -16.95196)
		(stroke
			(width 0.2)
			(type default)
		)
		(layer "In3.Cu")
	)
	(gr_line
		(start 387.17474 -249.385074)
		(end 387.17474 -248.115328)
		(stroke
			(width 0.2)
			(type default)
		)
		(layer "In3.Cu")
	)
	(gr_arc
		(start 387.17474 -248.115328)
		(mid 386.689727 -247.629934)
		(end 386.20446 -248.115074)
		(stroke
			(width 0.2)
			(type default)
		)
		(layer "In3.Cu")
	)
	(gr_arc
		(start 413.557212 -245.58752)
		(mid 414.042225 -246.072914)
		(end 414.527492 -245.587774)
		(stroke
			(width 0.2)
			(type default)
		)
		(layer "In3.Cu")
	)
	(gr_line
		(start 413.557212 -244.444774)
		(end 413.557212 -245.58752)
		(stroke
			(width 0.2)
			(type default)
		)
		(layer "In3.Cu")
	)
	(gr_line
		(start 413.864552 -129.112264)
		(end 415.007552 -129.112264)
		(stroke
			(width 0.2)
			(type default)
		)
		(layer "In3.Cu")
	)
	(gr_line
		(start 413.864552 -14.11224)
		(end 415.007552 -14.11224)
		(stroke
			(width 0.2)
			(type default)
		)
		(layer "In3.Cu")
	)
	(gr_arc
		(start 413.864806 -128.141984)
		(mid 413.379412 -128.626997)
		(end 413.864552 -129.112264)
		(stroke
			(width 0.2)
			(type default)
		)
		(layer "In3.Cu")
	)
	(gr_arc
		(start 413.864806 -13.14196)
		(mid 413.379412 -13.626973)
		(end 413.864552 -14.11224)
		(stroke
			(width 0.2)
			(type default)
		)
		(layer "In3.Cu")
	)
	(gr_line
		(start 414.527492 -245.587774)
		(end 414.527492 -244.444774)
		(stroke
			(width 0.2)
			(type default)
		)
		(layer "In3.Cu")
	)
	(gr_arc
		(start 414.527492 -244.444774)
		(mid 414.042352 -243.959634)
		(end 413.557212 -244.444774)
		(stroke
			(width 0.2)
			(type default)
		)
		(layer "In3.Cu")
	)
	(gr_arc
		(start 415.007552 -129.112264)
		(mid 415.492692 -128.627124)
		(end 415.007552 -128.141984)
		(stroke
			(width 0.2)
			(type default)
		)
		(layer "In3.Cu")
	)
	(gr_line
		(start 415.007552 -128.141984)
		(end 413.864806 -128.141984)
		(stroke
			(width 0.2)
			(type default)
		)
		(layer "In3.Cu")
	)
	(gr_arc
		(start 415.007552 -14.11224)
		(mid 415.492692 -13.6271)
		(end 415.007552 -13.14196)
		(stroke
			(width 0.2)
			(type default)
		)
		(layer "In3.Cu")
	)
	(gr_line
		(start 415.007552 -13.14196)
		(end 413.864806 -13.14196)
		(stroke
			(width 0.2)
			(type default)
		)
		(layer "In3.Cu")
	)
	(gr_line
		(start 417.331652 -132.922264)
		(end 418.601652 -132.922264)
		(stroke
			(width 0.2)
			(type default)
		)
		(layer "In3.Cu")
	)
	(gr_line
		(start 417.331652 -17.92224)
		(end 418.601652 -17.92224)
		(stroke
			(width 0.2)
			(type default)
		)
		(layer "In3.Cu")
	)
	(gr_arc
		(start 417.331906 -131.951984)
		(mid 416.846512 -132.436997)
		(end 417.331652 -132.922264)
		(stroke
			(width 0.2)
			(type default)
		)
		(layer "In3.Cu")
	)
	(gr_arc
		(start 417.331906 -16.95196)
		(mid 416.846512 -17.436973)
		(end 417.331652 -17.92224)
		(stroke
			(width 0.2)
			(type default)
		)
		(layer "In3.Cu")
	)
	(gr_arc
		(start 417.699952 -384.999992)
		(mid 417.992845 -385.707097)
		(end 418.69995 -385.99999)
		(stroke
			(width 2.54)
			(type default)
		)
		(layer "In3.Cu")
	)
	(gr_arc
		(start 417.699952 -381)
		(mid 417.407057 -380.292911)
		(end 416.699954 -380.000002)
		(stroke
			(width 2.54)
			(type default)
		)
		(layer "In3.Cu")
	)
	(gr_line
		(start 417.699952 -381)
		(end 417.699952 -384.999992)
		(stroke
			(width 2.54)
			(type default)
		)
		(layer "In3.Cu")
	)
	(gr_arc
		(start 417.754562 -249.385074)
		(mid 418.239702 -249.870214)
		(end 418.724842 -249.385074)
		(stroke
			(width 0.2)
			(type default)
		)
		(layer "In3.Cu")
	)
	(gr_line
		(start 417.754562 -248.115074)
		(end 417.754562 -249.385074)
		(stroke
			(width 0.2)
			(type default)
		)
		(layer "In3.Cu")
	)
	(gr_arc
		(start 418.601652 -132.922264)
		(mid 419.086792 -132.437124)
		(end 418.601652 -131.951984)
		(stroke
			(width 0.2)
			(type default)
		)
		(layer "In3.Cu")
	)
	(gr_line
		(start 418.601652 -131.951984)
		(end 417.331906 -131.951984)
		(stroke
			(width 0.2)
			(type default)
		)
		(layer "In3.Cu")
	)
	(gr_arc
		(start 418.601652 -17.92224)
		(mid 419.086792 -17.4371)
		(end 418.601652 -16.95196)
		(stroke
			(width 0.2)
			(type default)
		)
		(layer "In3.Cu")
	)
	(gr_line
		(start 418.601652 -16.95196)
		(end 417.331906 -16.95196)
		(stroke
			(width 0.2)
			(type default)
		)
		(layer "In3.Cu")
	)
	(gr_line
		(start 418.69995 -385.99999)
		(end 464.250024 -385.99999)
		(stroke
			(width 2.54)
			(type default)
		)
		(layer "In3.Cu")
	)
	(gr_line
		(start 418.724842 -249.385074)
		(end 418.724842 -248.115328)
		(stroke
			(width 0.2)
			(type default)
		)
		(layer "In3.Cu")
	)
	(gr_arc
		(start 418.724842 -248.115328)
		(mid 418.239829 -247.629934)
		(end 417.754562 -248.115074)
		(stroke
			(width 0.2)
			(type default)
		)
		(layer "In3.Cu")
	)
	(gr_arc
		(start 445.11722 -245.45544)
		(mid 445.602233 -245.940834)
		(end 446.0875 -245.455694)
		(stroke
			(width 0.2)
			(type default)
		)
		(layer "In3.Cu")
	)
	(gr_line
		(start 445.11722 -244.312694)
		(end 445.11722 -245.45544)
		(stroke
			(width 0.2)
			(type default)
		)
		(layer "In3.Cu")
	)
	(gr_line
		(start 445.4144 -129.112264)
		(end 446.5574 -129.112264)
		(stroke
			(width 0.2)
			(type default)
		)
		(layer "In3.Cu")
	)
	(gr_line
		(start 445.4144 -14.11224)
		(end 446.5574 -14.11224)
		(stroke
			(width 0.2)
			(type default)
		)
		(layer "In3.Cu")
	)
	(gr_arc
		(start 445.414654 -128.141984)
		(mid 444.92926 -128.626997)
		(end 445.4144 -129.112264)
		(stroke
			(width 0.2)
			(type default)
		)
		(layer "In3.Cu")
	)
	(gr_arc
		(start 445.414654 -13.14196)
		(mid 444.92926 -13.626973)
		(end 445.4144 -14.11224)
		(stroke
			(width 0.2)
			(type default)
		)
		(layer "In3.Cu")
	)
	(gr_line
		(start 446.0875 -245.455694)
		(end 446.0875 -244.312694)
		(stroke
			(width 0.2)
			(type default)
		)
		(layer "In3.Cu")
	)
	(gr_arc
		(start 446.0875 -244.312694)
		(mid 445.60236 -243.827554)
		(end 445.11722 -244.312694)
		(stroke
			(width 0.2)
			(type default)
		)
		(layer "In3.Cu")
	)
	(gr_arc
		(start 446.5574 -129.112264)
		(mid 447.04254 -128.627124)
		(end 446.5574 -128.141984)
		(stroke
			(width 0.2)
			(type default)
		)
		(layer "In3.Cu")
	)
	(gr_line
		(start 446.5574 -128.141984)
		(end 445.414654 -128.141984)
		(stroke
			(width 0.2)
			(type default)
		)
		(layer "In3.Cu")
	)
	(gr_arc
		(start 446.5574 -14.11224)
		(mid 447.04254 -13.6271)
		(end 446.5574 -13.14196)
		(stroke
			(width 0.2)
			(type default)
		)
		(layer "In3.Cu")
	)
	(gr_line
		(start 446.5574 -13.14196)
		(end 445.414654 -13.14196)
		(stroke
			(width 0.2)
			(type default)
		)
		(layer "In3.Cu")
	)
	(gr_line
		(start 448.8815 -132.922264)
		(end 450.151246 -132.922264)
		(stroke
			(width 0.2)
			(type default)
		)
		(layer "In3.Cu")
	)
	(gr_arc
		(start 448.8815 -131.951984)
		(mid 448.39636 -132.437124)
		(end 448.8815 -132.922264)
		(stroke
			(width 0.2)
			(type default)
		)
		(layer "In3.Cu")
	)
	(gr_line
		(start 448.8815 -17.92224)
		(end 450.151246 -17.92224)
		(stroke
			(width 0.2)
			(type default)
		)
		(layer "In3.Cu")
	)
	(gr_arc
		(start 448.8815 -16.95196)
		(mid 448.39636 -17.4371)
		(end 448.8815 -17.92224)
		(stroke
			(width 0.2)
			(type default)
		)
		(layer "In3.Cu")
	)
	(gr_arc
		(start 449.30441 -249.385074)
		(mid 449.78955 -249.870214)
		(end 450.27469 -249.385074)
		(stroke
			(width 0.2)
			(type default)
		)
		(layer "In3.Cu")
	)
	(gr_line
		(start 449.30441 -248.115074)
		(end 449.30441 -249.385074)
		(stroke
			(width 0.2)
			(type default)
		)
		(layer "In3.Cu")
	)
	(gr_arc
		(start 450.151246 -132.922264)
		(mid 450.63664 -132.437251)
		(end 450.1515 -131.951984)
		(stroke
			(width 0.2)
			(type default)
		)
		(layer "In3.Cu")
	)
	(gr_arc
		(start 450.151246 -17.92224)
		(mid 450.63664 -17.437227)
		(end 450.1515 -16.95196)
		(stroke
			(width 0.2)
			(type default)
		)
		(layer "In3.Cu")
	)
	(gr_line
		(start 450.1515 -131.951984)
		(end 448.8815 -131.951984)
		(stroke
			(width 0.2)
			(type default)
		)
		(layer "In3.Cu")
	)
	(gr_line
		(start 450.1515 -16.95196)
		(end 448.8815 -16.95196)
		(stroke
			(width 0.2)
			(type default)
		)
		(layer "In3.Cu")
	)
	(gr_line
		(start 450.27469 -249.385074)
		(end 450.27469 -248.115328)
		(stroke
			(width 0.2)
			(type default)
		)
		(layer "In3.Cu")
	)
	(gr_arc
		(start 450.27469 -248.115328)
		(mid 449.789677 -247.629934)
		(end 449.30441 -248.115074)
		(stroke
			(width 0.2)
			(type default)
		)
		(layer "In3.Cu")
	)
	(gr_arc
		(start 464.250024 -385.99999)
		(mid 464.957129 -385.707097)
		(end 465.250022 -384.999992)
		(stroke
			(width 2.54)
			(type default)
		)
		(layer "In3.Cu")
	)
	(gr_line
		(start 465.250022 -384.999992)
		(end 465.250022 -383.29997)
		(stroke
			(width 2.54)
			(type default)
		)
		(layer "In3.Cu")
	)
	(gr_arc
		(start 466.25002 -382.299972)
		(mid 465.542891 -382.592856)
		(end 465.250022 -383.29997)
		(stroke
			(width 2.54)
			(type default)
		)
		(layer "In3.Cu")
	)
	(gr_line
		(start 466.25002 -382.299972)
		(end 472.74988 -382.299972)
		(stroke
			(width 2.54)
			(type default)
		)
		(layer "In3.Cu")
	)
	(gr_arc
		(start 473.749878 -384.999992)
		(mid 474.042771 -385.707097)
		(end 474.749876 -385.99999)
		(stroke
			(width 2.54)
			(type default)
		)
		(layer "In3.Cu")
	)
	(gr_arc
		(start 473.749878 -383.29997)
		(mid 473.456974 -382.592891)
		(end 472.74988 -382.299972)
		(stroke
			(width 2.54)
			(type default)
		)
		(layer "In3.Cu")
	)
	(gr_line
		(start 473.749878 -383.29997)
		(end 473.749878 -384.999992)
		(stroke
			(width 2.54)
			(type default)
		)
		(layer "In3.Cu")
	)
	(gr_line
		(start 474.749876 -385.99999)
		(end 487.449876 -385.99999)
		(stroke
			(width 2.54)
			(type default)
		)
		(layer "In3.Cu")
	)
	(gr_arc
		(start 476.667322 -245.45544)
		(mid 477.152335 -245.940834)
		(end 477.637602 -245.455694)
		(stroke
			(width 0.2)
			(type default)
		)
		(layer "In3.Cu")
	)
	(gr_line
		(start 476.667322 -244.312694)
		(end 476.667322 -245.45544)
		(stroke
			(width 0.2)
			(type default)
		)
		(layer "In3.Cu")
	)
	(gr_line
		(start 476.964502 -129.112264)
		(end 478.107502 -129.112264)
		(stroke
			(width 0.2)
			(type default)
		)
		(layer "In3.Cu")
	)
	(gr_line
		(start 476.964502 -14.11224)
		(end 478.107502 -14.11224)
		(stroke
			(width 0.2)
			(type default)
		)
		(layer "In3.Cu")
	)
	(gr_arc
		(start 476.964756 -128.141984)
		(mid 476.479362 -128.626997)
		(end 476.964502 -129.112264)
		(stroke
			(width 0.2)
			(type default)
		)
		(layer "In3.Cu")
	)
	(gr_arc
		(start 476.964756 -13.14196)
		(mid 476.479362 -13.626973)
		(end 476.964502 -14.11224)
		(stroke
			(width 0.2)
			(type default)
		)
		(layer "In3.Cu")
	)
	(gr_line
		(start 477.637602 -245.455694)
		(end 477.637602 -244.312694)
		(stroke
			(width 0.2)
			(type default)
		)
		(layer "In3.Cu")
	)
	(gr_arc
		(start 477.637602 -244.312694)
		(mid 477.152462 -243.827554)
		(end 476.667322 -244.312694)
		(stroke
			(width 0.2)
			(type default)
		)
		(layer "In3.Cu")
	)
	(gr_arc
		(start 478.107502 -129.112264)
		(mid 478.592642 -128.627124)
		(end 478.107502 -128.141984)
		(stroke
			(width 0.2)
			(type default)
		)
		(layer "In3.Cu")
	)
	(gr_line
		(start 478.107502 -128.141984)
		(end 476.964756 -128.141984)
		(stroke
			(width 0.2)
			(type default)
		)
		(layer "In3.Cu")
	)
	(gr_arc
		(start 478.107502 -14.11224)
		(mid 478.592642 -13.6271)
		(end 478.107502 -13.14196)
		(stroke
			(width 0.2)
			(type default)
		)
		(layer "In3.Cu")
	)
	(gr_line
		(start 478.107502 -13.14196)
		(end 476.964756 -13.14196)
		(stroke
			(width 0.2)
			(type default)
		)
		(layer "In3.Cu")
	)
	(gr_line
		(start 480.431602 -132.922264)
		(end 481.701602 -132.922264)
		(stroke
			(width 0.2)
			(type default)
		)
		(layer "In3.Cu")
	)
	(gr_line
		(start 480.431602 -17.92224)
		(end 481.701602 -17.92224)
		(stroke
			(width 0.2)
			(type default)
		)
		(layer "In3.Cu")
	)
	(gr_arc
		(start 480.431856 -131.951984)
		(mid 479.946462 -132.436997)
		(end 480.431602 -132.922264)
		(stroke
			(width 0.2)
			(type default)
		)
		(layer "In3.Cu")
	)
	(gr_arc
		(start 480.431856 -16.95196)
		(mid 479.946462 -17.436973)
		(end 480.431602 -17.92224)
		(stroke
			(width 0.2)
			(type default)
		)
		(layer "In3.Cu")
	)
	(gr_arc
		(start 480.854512 -249.385074)
		(mid 481.339652 -249.870214)
		(end 481.824792 -249.385074)
		(stroke
			(width 0.2)
			(type default)
		)
		(layer "In3.Cu")
	)
	(gr_line
		(start 480.854512 -248.115074)
		(end 480.854512 -249.385074)
		(stroke
			(width 0.2)
			(type default)
		)
		(layer "In3.Cu")
	)
	(gr_arc
		(start 481.701602 -132.922264)
		(mid 482.186742 -132.437124)
		(end 481.701602 -131.951984)
		(stroke
			(width 0.2)
			(type default)
		)
		(layer "In3.Cu")
	)
	(gr_line
		(start 481.701602 -131.951984)
		(end 480.431856 -131.951984)
		(stroke
			(width 0.2)
			(type default)
		)
		(layer "In3.Cu")
	)
	(gr_arc
		(start 481.701602 -17.92224)
		(mid 482.186742 -17.4371)
		(end 481.701602 -16.95196)
		(stroke
			(width 0.2)
			(type default)
		)
		(layer "In3.Cu")
	)
	(gr_line
		(start 481.701602 -16.95196)
		(end 480.431856 -16.95196)
		(stroke
			(width 0.2)
			(type default)
		)
		(layer "In3.Cu")
	)
	(gr_line
		(start 481.824792 -249.385074)
		(end 481.824792 -248.115328)
		(stroke
			(width 0.2)
			(type default)
		)
		(layer "In3.Cu")
	)
	(gr_arc
		(start 481.824792 -248.115328)
		(mid 481.339779 -247.629934)
		(end 480.854512 -248.115074)
		(stroke
			(width 0.2)
			(type default)
		)
		(layer "In3.Cu")
	)
	(gr_arc
		(start 487.449876 -385.99999)
		(mid 488.156981 -385.707097)
		(end 488.449874 -384.999992)
		(stroke
			(width 2.54)
			(type default)
		)
		(layer "In3.Cu")
	)
	(gr_line
		(start 488.449874 -384.999992)
		(end 488.449874 -372.000018)
		(stroke
			(width 2.54)
			(type default)
		)
		(layer "In3.Cu")
	)
	(gr_arc
		(start 489.450126 -371.00002)
		(mid 488.742881 -371.292834)
		(end 488.449874 -372.000018)
		(stroke
			(width 2.54)
			(type default)
		)
		(layer "In3.Cu")
	)
	(gr_line
		(start 489.450126 -371.00002)
		(end 490.450124 -371.00002)
		(stroke
			(width 2.54)
			(type default)
		)
		(layer "In3.Cu")
	)
	(gr_arc
		(start 490.450124 -371.00002)
		(mid 491.157229 -370.707127)
		(end 491.450122 -370.000022)
		(stroke
			(width 2.54)
			(type default)
		)
		(layer "In3.Cu")
	)
	(gr_line
		(start 490.450124 0)
		(end 311.999884 0)
		(stroke
			(width 2.54)
			(type default)
		)
		(layer "In3.Cu")
	)
	(gr_line
		(start 491.450122 -370.000022)
		(end 491.450122 -0.999998)
		(stroke
			(width 2.54)
			(type default)
		)
		(layer "In3.Cu")
	)
	(gr_arc
		(start 491.450122 -0.999998)
		(mid 491.157229 -0.292893)
		(end 490.450124 0)
		(stroke
			(width 2.54)
			(type default)
		)
		(layer "In3.Cu")
	)
	(gr_arc
		(start 0 -370.000022)
		(mid 0.292893 -370.707127)
		(end 0.999998 -371.00002)
		(stroke
			(width 2.54)
			(type default)
		)
		(layer "In4.Cu")
	)
	(gr_line
		(start 0 -0.999998)
		(end 0 -370.000022)
		(stroke
			(width 2.54)
			(type default)
		)
		(layer "In4.Cu")
	)
	(gr_line
		(start 0.999998 -371.00002)
		(end 1.999996 -371.00002)
		(stroke
			(width 2.54)
			(type default)
		)
		(layer "In4.Cu")
	)
	(gr_arc
		(start 0.999998 0)
		(mid 0.292893 -0.292893)
		(end 0 -0.999998)
		(stroke
			(width 2.54)
			(type default)
		)
		(layer "In4.Cu")
	)
	(gr_arc
		(start 2.999994 -384.999992)
		(mid 3.292887 -385.707097)
		(end 3.999992 -385.99999)
		(stroke
			(width 2.54)
			(type default)
		)
		(layer "In4.Cu")
	)
	(gr_arc
		(start 2.999994 -372.000018)
		(mid 2.707101 -371.292912)
		(end 1.999996 -371.00002)
		(stroke
			(width 2.54)
			(type default)
		)
		(layer "In4.Cu")
	)
	(gr_line
		(start 2.999994 -372.000018)
		(end 2.999994 -384.999992)
		(stroke
			(width 2.54)
			(type default)
		)
		(layer "In4.Cu")
	)
	(gr_line
		(start 3.999992 -385.99999)
		(end 15.249906 -385.99999)
		(stroke
			(width 2.54)
			(type default)
		)
		(layer "In4.Cu")
	)
	(gr_arc
		(start 15.249906 -385.99999)
		(mid 15.957011 -385.707097)
		(end 16.249904 -384.999992)
		(stroke
			(width 2.54)
			(type default)
		)
		(layer "In4.Cu")
	)
	(gr_line
		(start 15.748 -229.108)
		(end 17.526 -230.886)
		(stroke
			(width 0.381)
			(type default)
		)
		(layer "In4.Cu")
	)
	(gr_line
		(start 15.748 -146.304)
		(end 15.748 -229.108)
		(stroke
			(width 0.381)
			(type default)
		)
		(layer "In4.Cu")
	)
	(gr_line
		(start 16.249904 -384.999992)
		(end 16.249904 -383.29997)
		(stroke
			(width 2.54)
			(type default)
		)
		(layer "In4.Cu")
	)
	(gr_arc
		(start 17.249902 -382.299972)
		(mid 16.542795 -382.592864)
		(end 16.249904 -383.29997)
		(stroke
			(width 2.54)
			(type default)
		)
		(layer "In4.Cu")
	)
	(gr_line
		(start 17.249902 -382.299972)
		(end 23.750016 -382.299972)
		(stroke
			(width 2.54)
			(type default)
		)
		(layer "In4.Cu")
	)
	(gr_line
		(start 17.526 -252.476)
		(end 19.431 -254.381)
		(stroke
			(width 0.381)
			(type default)
		)
		(layer "In4.Cu")
	)
	(gr_line
		(start 17.526 -230.886)
		(end 17.526 -252.476)
		(stroke
			(width 0.381)
			(type default)
		)
		(layer "In4.Cu")
	)
	(gr_line
		(start 17.526 -100.9396)
		(end 25.5524 -108.966)
		(stroke
			(width 0.381)
			(type default)
		)
		(layer "In4.Cu")
	)
	(gr_line
		(start 17.526 -21.971)
		(end 17.526 -100.9396)
		(stroke
			(width 0.381)
			(type default)
		)
		(layer "In4.Cu")
	)
	(gr_line
		(start 17.653 -144.399)
		(end 15.748 -146.304)
		(stroke
			(width 0.381)
			(type default)
		)
		(layer "In4.Cu")
	)
	(gr_line
		(start 17.653 -136.017)
		(end 17.653 -144.399)
		(stroke
			(width 0.381)
			(type default)
		)
		(layer "In4.Cu")
	)
	(gr_line
		(start 19.05 -134.62)
		(end 17.653 -136.017)
		(stroke
			(width 0.381)
			(type default)
		)
		(layer "In4.Cu")
	)
	(gr_line
		(start 19.431 -254.381)
		(end 181.229 -254.381)
		(stroke
			(width 0.381)
			(type default)
		)
		(layer "In4.Cu")
	)
	(gr_line
		(start 20.574 -18.923)
		(end 17.526 -21.971)
		(stroke
			(width 0.381)
			(type default)
		)
		(layer "In4.Cu")
	)
	(gr_arc
		(start 24.750014 -384.999992)
		(mid 25.042907 -385.707097)
		(end 25.750012 -385.99999)
		(stroke
			(width 2.54)
			(type default)
		)
		(layer "In4.Cu")
	)
	(gr_arc
		(start 24.750014 -383.29997)
		(mid 24.457112 -382.592878)
		(end 23.750016 -382.299972)
		(stroke
			(width 2.54)
			(type default)
		)
		(layer "In4.Cu")
	)
	(gr_line
		(start 24.750014 -383.29997)
		(end 24.750014 -384.999992)
		(stroke
			(width 2.54)
			(type default)
		)
		(layer "In4.Cu")
	)
	(gr_line
		(start 25.5524 -108.966)
		(end 52.2478 -108.966)
		(stroke
			(width 0.381)
			(type default)
		)
		(layer "In4.Cu")
	)
	(gr_line
		(start 25.750012 -385.99999)
		(end 71.300086 -385.99999)
		(stroke
			(width 2.54)
			(type default)
		)
		(layer "In4.Cu")
	)
	(gr_line
		(start 27.94 -134.62)
		(end 19.05 -134.62)
		(stroke
			(width 0.381)
			(type default)
		)
		(layer "In4.Cu")
	)
	(gr_line
		(start 28.702 -18.923)
		(end 20.574 -18.923)
		(stroke
			(width 0.381)
			(type default)
		)
		(layer "In4.Cu")
	)
	(gr_line
		(start 31.242 -131.318)
		(end 27.94 -134.62)
		(stroke
			(width 0.381)
			(type default)
		)
		(layer "In4.Cu")
	)
	(gr_line
		(start 31.242 -16.383)
		(end 28.702 -18.923)
		(stroke
			(width 0.381)
			(type default)
		)
		(layer "In4.Cu")
	)
	(gr_arc
		(start 32.023812 -249.385074)
		(mid 32.508952 -249.870214)
		(end 32.994092 -249.385074)
		(stroke
			(width 0.2)
			(type default)
		)
		(layer "In4.Cu")
	)
	(gr_line
		(start 32.023812 -248.115074)
		(end 32.023812 -249.385074)
		(stroke
			(width 0.2)
			(type default)
		)
		(layer "In4.Cu")
	)
	(gr_arc
		(start 32.023812 -134.384796)
		(mid 32.508825 -134.87019)
		(end 32.994092 -134.38505)
		(stroke
			(width 0.2)
			(type default)
		)
		(layer "In4.Cu")
	)
	(gr_line
		(start 32.023812 -133.11505)
		(end 32.023812 -134.384796)
		(stroke
			(width 0.2)
			(type default)
		)
		(layer "In4.Cu")
	)
	(gr_arc
		(start 32.023812 -19.385026)
		(mid 32.508952 -19.870166)
		(end 32.994092 -19.385026)
		(stroke
			(width 0.2)
			(type default)
		)
		(layer "In4.Cu")
	)
	(gr_line
		(start 32.023812 -18.115026)
		(end 32.023812 -19.385026)
		(stroke
			(width 0.2)
			(type default)
		)
		(layer "In4.Cu")
	)
	(gr_line
		(start 32.994092 -249.385074)
		(end 32.994092 -248.115328)
		(stroke
			(width 0.2)
			(type default)
		)
		(layer "In4.Cu")
	)
	(gr_arc
		(start 32.994092 -248.115328)
		(mid 32.509079 -247.629934)
		(end 32.023812 -248.115074)
		(stroke
			(width 0.2)
			(type default)
		)
		(layer "In4.Cu")
	)
	(gr_line
		(start 32.994092 -134.38505)
		(end 32.994092 -133.11505)
		(stroke
			(width 0.2)
			(type default)
		)
		(layer "In4.Cu")
	)
	(gr_arc
		(start 32.994092 -133.11505)
		(mid 32.508952 -132.62991)
		(end 32.023812 -133.11505)
		(stroke
			(width 0.2)
			(type default)
		)
		(layer "In4.Cu")
	)
	(gr_line
		(start 32.994092 -19.385026)
		(end 32.994092 -18.11528)
		(stroke
			(width 0.2)
			(type default)
		)
		(layer "In4.Cu")
	)
	(gr_arc
		(start 32.994092 -18.11528)
		(mid 32.509079 -17.629886)
		(end 32.023812 -18.115026)
		(stroke
			(width 0.2)
			(type default)
		)
		(layer "In4.Cu")
	)
	(gr_line
		(start 33.147 -131.318)
		(end 31.242 -131.318)
		(stroke
			(width 0.381)
			(type default)
		)
		(layer "In4.Cu")
	)
	(gr_line
		(start 33.147 -16.383)
		(end 31.242 -16.383)
		(stroke
			(width 0.381)
			(type default)
		)
		(layer "In4.Cu")
	)
	(gr_line
		(start 33.401 -132.334)
		(end 33.401 -131.572)
		(stroke
			(width 0.381)
			(type default)
		)
		(layer "In4.Cu")
	)
	(gr_line
		(start 33.401 -131.572)
		(end 33.147 -131.318)
		(stroke
			(width 0.381)
			(type default)
		)
		(layer "In4.Cu")
	)
	(gr_line
		(start 33.401 -17.272)
		(end 33.401 -16.637)
		(stroke
			(width 0.381)
			(type default)
		)
		(layer "In4.Cu")
	)
	(gr_line
		(start 33.401 -16.637)
		(end 33.147 -16.383)
		(stroke
			(width 0.381)
			(type default)
		)
		(layer "In4.Cu")
	)
	(gr_line
		(start 33.782 -132.715)
		(end 33.401 -132.334)
		(stroke
			(width 0.381)
			(type default)
		)
		(layer "In4.Cu")
	)
	(gr_line
		(start 33.782 -17.653)
		(end 33.401 -17.272)
		(stroke
			(width 0.381)
			(type default)
		)
		(layer "In4.Cu")
	)
	(gr_arc
		(start 33.800542 -245.56212)
		(mid 34.285555 -246.047514)
		(end 34.770822 -245.562374)
		(stroke
			(width 0.2)
			(type default)
		)
		(layer "In4.Cu")
	)
	(gr_line
		(start 33.800542 -244.419374)
		(end 33.800542 -245.56212)
		(stroke
			(width 0.2)
			(type default)
		)
		(layer "In4.Cu")
	)
	(gr_arc
		(start 33.800542 -130.56235)
		(mid 34.285682 -131.04749)
		(end 34.770822 -130.56235)
		(stroke
			(width 0.2)
			(type default)
		)
		(layer "In4.Cu")
	)
	(gr_line
		(start 33.800542 -129.41935)
		(end 33.800542 -130.56235)
		(stroke
			(width 0.2)
			(type default)
		)
		(layer "In4.Cu")
	)
	(gr_arc
		(start 33.800542 -15.562326)
		(mid 34.285682 -16.047466)
		(end 34.770822 -15.562326)
		(stroke
			(width 0.2)
			(type default)
		)
		(layer "In4.Cu")
	)
	(gr_line
		(start 33.800542 -14.419326)
		(end 33.800542 -15.562326)
		(stroke
			(width 0.2)
			(type default)
		)
		(layer "In4.Cu")
	)
	(gr_line
		(start 34.770822 -245.562374)
		(end 34.770822 -244.419374)
		(stroke
			(width 0.2)
			(type default)
		)
		(layer "In4.Cu")
	)
	(gr_arc
		(start 34.770822 -244.419374)
		(mid 34.285682 -243.934234)
		(end 33.800542 -244.419374)
		(stroke
			(width 0.2)
			(type default)
		)
		(layer "In4.Cu")
	)
	(gr_line
		(start 34.770822 -130.56235)
		(end 34.770822 -129.419604)
		(stroke
			(width 0.2)
			(type default)
		)
		(layer "In4.Cu")
	)
	(gr_arc
		(start 34.770822 -129.419604)
		(mid 34.285809 -128.93421)
		(end 33.800542 -129.41935)
		(stroke
			(width 0.2)
			(type default)
		)
		(layer "In4.Cu")
	)
	(gr_line
		(start 34.770822 -15.562326)
		(end 34.770822 -14.41958)
		(stroke
			(width 0.2)
			(type default)
		)
		(layer "In4.Cu")
	)
	(gr_arc
		(start 34.770822 -14.41958)
		(mid 34.285809 -13.934186)
		(end 33.800542 -14.419326)
		(stroke
			(width 0.2)
			(type default)
		)
		(layer "In4.Cu")
	)
	(gr_line
		(start 37.211 -17.653)
		(end 33.782 -17.653)
		(stroke
			(width 0.381)
			(type default)
		)
		(layer "In4.Cu")
	)
	(gr_line
		(start 37.846 -132.715)
		(end 33.782 -132.715)
		(stroke
			(width 0.381)
			(type default)
		)
		(layer "In4.Cu")
	)
	(gr_line
		(start 41.148 -21.59)
		(end 37.211 -17.653)
		(stroke
			(width 0.381)
			(type default)
		)
		(layer "In4.Cu")
	)
	(gr_line
		(start 41.3004 -136.1694)
		(end 37.846 -132.715)
		(stroke
			(width 0.381)
			(type default)
		)
		(layer "In4.Cu")
	)
	(gr_line
		(start 49.3776 -136.1694)
		(end 41.3004 -136.1694)
		(stroke
			(width 0.381)
			(type default)
		)
		(layer "In4.Cu")
	)
	(gr_line
		(start 51.816 -133.731)
		(end 49.3776 -136.1694)
		(stroke
			(width 0.381)
			(type default)
		)
		(layer "In4.Cu")
	)
	(gr_line
		(start 52.2478 -108.966)
		(end 59.5122 -116.2304)
		(stroke
			(width 0.381)
			(type default)
		)
		(layer "In4.Cu")
	)
	(gr_circle
		(center 59.399932 -372.599966)
		(end 60.812172 -372.599966)
		(stroke
			(width 0.2)
			(type default)
		)
		(fill no)
		(layer "In4.Cu")
	)
	(gr_circle
		(center 59.399932 -367.09985)
		(end 60.812172 -367.09985)
		(stroke
			(width 0.2)
			(type default)
		)
		(fill no)
		(layer "In4.Cu")
	)
	(gr_line
		(start 59.5122 -116.2304)
		(end 62.505336 -116.2304)
		(stroke
			(width 0.381)
			(type default)
		)
		(layer "In4.Cu")
	)
	(gr_line
		(start 60.325 -133.731)
		(end 51.816 -133.731)
		(stroke
			(width 0.381)
			(type default)
		)
		(layer "In4.Cu")
	)
	(gr_line
		(start 61.595 -21.59)
		(end 41.148 -21.59)
		(stroke
			(width 0.381)
			(type default)
		)
		(layer "In4.Cu")
	)
	(gr_line
		(start 62.505336 -116.2304)
		(end 63.41999 -117.145054)
		(stroke
			(width 0.381)
			(type default)
		)
		(layer "In4.Cu")
	)
	(gr_line
		(start 62.738 -131.318)
		(end 60.325 -133.731)
		(stroke
			(width 0.381)
			(type default)
		)
		(layer "In4.Cu")
	)
	(gr_line
		(start 62.865 -20.32)
		(end 61.595 -21.59)
		(stroke
			(width 0.381)
			(type default)
		)
		(layer "In4.Cu")
	)
	(gr_line
		(start 62.865 -16.764)
		(end 62.865 -20.32)
		(stroke
			(width 0.381)
			(type default)
		)
		(layer "In4.Cu")
	)
	(gr_line
		(start 63.41999 -117.145054)
		(end 68.243704 -117.145054)
		(stroke
			(width 0.381)
			(type default)
		)
		(layer "In4.Cu")
	)
	(gr_line
		(start 63.5 -16.129)
		(end 62.865 -16.764)
		(stroke
			(width 0.381)
			(type default)
		)
		(layer "In4.Cu")
	)
	(gr_arc
		(start 63.57366 -249.385074)
		(mid 64.0588 -249.870214)
		(end 64.54394 -249.385074)
		(stroke
			(width 0.2)
			(type default)
		)
		(layer "In4.Cu")
	)
	(gr_line
		(start 63.57366 -248.115074)
		(end 63.57366 -249.385074)
		(stroke
			(width 0.2)
			(type default)
		)
		(layer "In4.Cu")
	)
	(gr_arc
		(start 63.57366 -134.384796)
		(mid 64.058673 -134.87019)
		(end 64.54394 -134.38505)
		(stroke
			(width 0.2)
			(type default)
		)
		(layer "In4.Cu")
	)
	(gr_line
		(start 63.57366 -133.11505)
		(end 63.57366 -134.384796)
		(stroke
			(width 0.2)
			(type default)
		)
		(layer "In4.Cu")
	)
	(gr_arc
		(start 63.57366 -19.385026)
		(mid 64.0588 -19.870166)
		(end 64.54394 -19.385026)
		(stroke
			(width 0.2)
			(type default)
		)
		(layer "In4.Cu")
	)
	(gr_line
		(start 63.57366 -18.115026)
		(end 63.57366 -19.385026)
		(stroke
			(width 0.2)
			(type default)
		)
		(layer "In4.Cu")
	)
	(gr_line
		(start 64.516 -16.129)
		(end 63.5 -16.129)
		(stroke
			(width 0.381)
			(type default)
		)
		(layer "In4.Cu")
	)
	(gr_line
		(start 64.54394 -249.385074)
		(end 64.54394 -248.115328)
		(stroke
			(width 0.2)
			(type default)
		)
		(layer "In4.Cu")
	)
	(gr_arc
		(start 64.54394 -248.115328)
		(mid 64.058927 -247.629934)
		(end 63.57366 -248.115074)
		(stroke
			(width 0.2)
			(type default)
		)
		(layer "In4.Cu")
	)
	(gr_line
		(start 64.54394 -134.38505)
		(end 64.54394 -133.11505)
		(stroke
			(width 0.2)
			(type default)
		)
		(layer "In4.Cu")
	)
	(gr_arc
		(start 64.54394 -133.11505)
		(mid 64.0588 -132.62991)
		(end 63.57366 -133.11505)
		(stroke
			(width 0.2)
			(type default)
		)
		(layer "In4.Cu")
	)
	(gr_line
		(start 64.54394 -19.385026)
		(end 64.54394 -18.11528)
		(stroke
			(width 0.2)
			(type default)
		)
		(layer "In4.Cu")
	)
	(gr_arc
		(start 64.54394 -18.11528)
		(mid 64.058927 -17.629886)
		(end 63.57366 -18.115026)
		(stroke
			(width 0.2)
			(type default)
		)
		(layer "In4.Cu")
	)
	(gr_line
		(start 64.643 -131.318)
		(end 62.738 -131.318)
		(stroke
			(width 0.381)
			(type default)
		)
		(layer "In4.Cu")
	)
	(gr_line
		(start 64.897 -132.08)
		(end 64.897 -131.572)
		(stroke
			(width 0.381)
			(type default)
		)
		(layer "In4.Cu")
	)
	(gr_line
		(start 64.897 -131.572)
		(end 64.643 -131.318)
		(stroke
			(width 0.381)
			(type default)
		)
		(layer "In4.Cu")
	)
	(gr_line
		(start 64.897 -17.399)
		(end 64.897 -16.51)
		(stroke
			(width 0.381)
			(type default)
		)
		(layer "In4.Cu")
	)
	(gr_line
		(start 64.897 -16.51)
		(end 64.516 -16.129)
		(stroke
			(width 0.381)
			(type default)
		)
		(layer "In4.Cu")
	)
	(gr_line
		(start 65.278 -17.78)
		(end 64.897 -17.399)
		(stroke
			(width 0.381)
			(type default)
		)
		(layer "In4.Cu")
	)
	(gr_arc
		(start 65.35039 -245.56212)
		(mid 65.835403 -246.047514)
		(end 66.32067 -245.562374)
		(stroke
			(width 0.2)
			(type default)
		)
		(layer "In4.Cu")
	)
	(gr_line
		(start 65.35039 -244.419374)
		(end 65.35039 -245.56212)
		(stroke
			(width 0.2)
			(type default)
		)
		(layer "In4.Cu")
	)
	(gr_arc
		(start 65.35039 -130.56235)
		(mid 65.83553 -131.04749)
		(end 66.32067 -130.56235)
		(stroke
			(width 0.2)
			(type default)
		)
		(layer "In4.Cu")
	)
	(gr_line
		(start 65.35039 -129.41935)
		(end 65.35039 -130.56235)
		(stroke
			(width 0.2)
			(type default)
		)
		(layer "In4.Cu")
	)
	(gr_arc
		(start 65.35039 -15.562326)
		(mid 65.83553 -16.047466)
		(end 66.32067 -15.562326)
		(stroke
			(width 0.2)
			(type default)
		)
		(layer "In4.Cu")
	)
	(gr_line
		(start 65.35039 -14.419326)
		(end 65.35039 -15.562326)
		(stroke
			(width 0.2)
			(type default)
		)
		(layer "In4.Cu")
	)
	(gr_line
		(start 65.405 -132.588)
		(end 64.897 -132.08)
		(stroke
			(width 0.381)
			(type default)
		)
		(layer "In4.Cu")
	)
	(gr_line
		(start 66.32067 -245.562374)
		(end 66.32067 -244.419374)
		(stroke
			(width 0.2)
			(type default)
		)
		(layer "In4.Cu")
	)
	(gr_arc
		(start 66.32067 -244.419374)
		(mid 65.83553 -243.934234)
		(end 65.35039 -244.419374)
		(stroke
			(width 0.2)
			(type default)
		)
		(layer "In4.Cu")
	)
	(gr_line
		(start 66.32067 -130.56235)
		(end 66.32067 -129.419604)
		(stroke
			(width 0.2)
			(type default)
		)
		(layer "In4.Cu")
	)
	(gr_arc
		(start 66.32067 -129.419604)
		(mid 65.835657 -128.93421)
		(end 65.35039 -129.41935)
		(stroke
			(width 0.2)
			(type default)
		)
		(layer "In4.Cu")
	)
	(gr_line
		(start 66.32067 -15.562326)
		(end 66.32067 -14.41958)
		(stroke
			(width 0.2)
			(type default)
		)
		(layer "In4.Cu")
	)
	(gr_arc
		(start 66.32067 -14.41958)
		(mid 65.835657 -13.934186)
		(end 65.35039 -14.419326)
		(stroke
			(width 0.2)
			(type default)
		)
		(layer "In4.Cu")
	)
	(gr_line
		(start 68.243704 -117.145054)
		(end 69.158358 -116.2304)
		(stroke
			(width 0.381)
			(type default)
		)
		(layer "In4.Cu")
	)
	(gr_line
		(start 69.158358 -116.2304)
		(end 108.4834 -116.2304)
		(stroke
			(width 0.381)
			(type default)
		)
		(layer "In4.Cu")
	)
	(gr_line
		(start 70.612 -17.78)
		(end 65.278 -17.78)
		(stroke
			(width 0.381)
			(type default)
		)
		(layer "In4.Cu")
	)
	(gr_arc
		(start 71.300086 -385.99999)
		(mid 72.007191 -385.707097)
		(end 72.300084 -384.999992)
		(stroke
			(width 2.54)
			(type default)
		)
		(layer "In4.Cu")
	)
	(gr_line
		(start 72.300084 -384.999992)
		(end 72.300084 -381)
		(stroke
			(width 2.54)
			(type default)
		)
		(layer "In4.Cu")
	)
	(gr_line
		(start 73.279 -132.588)
		(end 65.405 -132.588)
		(stroke
			(width 0.381)
			(type default)
		)
		(layer "In4.Cu")
	)
	(gr_arc
		(start 73.300082 -380.000002)
		(mid 72.592988 -380.292901)
		(end 72.300084 -381)
		(stroke
			(width 2.54)
			(type default)
		)
		(layer "In4.Cu")
	)
	(gr_line
		(start 73.300082 -380.000002)
		(end 125.299978 -380.000002)
		(stroke
			(width 2.54)
			(type default)
		)
		(layer "In4.Cu")
	)
	(gr_line
		(start 74.422 -21.59)
		(end 70.612 -17.78)
		(stroke
			(width 0.381)
			(type default)
		)
		(layer "In4.Cu")
	)
	(gr_line
		(start 78.2574 -137.5664)
		(end 73.279 -132.588)
		(stroke
			(width 0.381)
			(type default)
		)
		(layer "In4.Cu")
	)
	(gr_line
		(start 79.9846 -137.5664)
		(end 78.2574 -137.5664)
		(stroke
			(width 0.381)
			(type default)
		)
		(layer "In4.Cu")
	)
	(gr_line
		(start 80.899 -21.59)
		(end 74.422 -21.59)
		(stroke
			(width 0.381)
			(type default)
		)
		(layer "In4.Cu")
	)
	(gr_line
		(start 83.312 -134.239)
		(end 79.9846 -137.5664)
		(stroke
			(width 0.381)
			(type default)
		)
		(layer "In4.Cu")
	)
	(gr_line
		(start 83.566 -18.923)
		(end 80.899 -21.59)
		(stroke
			(width 0.381)
			(type default)
		)
		(layer "In4.Cu")
	)
	(gr_line
		(start 87.63 -134.239)
		(end 83.312 -134.239)
		(stroke
			(width 0.381)
			(type default)
		)
		(layer "In4.Cu")
	)
	(gr_line
		(start 88.773 -209.9818)
		(end 88.773 -135.382)
		(stroke
			(width 0.381)
			(type default)
		)
		(layer "In4.Cu")
	)
	(gr_line
		(start 88.773 -135.382)
		(end 87.63 -134.239)
		(stroke
			(width 0.381)
			(type default)
		)
		(layer "In4.Cu")
	)
	(gr_line
		(start 91.567 -18.923)
		(end 83.566 -18.923)
		(stroke
			(width 0.381)
			(type default)
		)
		(layer "In4.Cu")
	)
	(gr_line
		(start 92.202 -213.4108)
		(end 88.773 -209.9818)
		(stroke
			(width 0.381)
			(type default)
		)
		(layer "In4.Cu")
	)
	(gr_line
		(start 94.361 -16.129)
		(end 91.567 -18.923)
		(stroke
			(width 0.381)
			(type default)
		)
		(layer "In4.Cu")
	)
	(gr_arc
		(start 95.123762 -249.385074)
		(mid 95.608902 -249.870214)
		(end 96.094042 -249.385074)
		(stroke
			(width 0.2)
			(type default)
		)
		(layer "In4.Cu")
	)
	(gr_line
		(start 95.123762 -248.115074)
		(end 95.123762 -249.385074)
		(stroke
			(width 0.2)
			(type default)
		)
		(layer "In4.Cu")
	)
	(gr_arc
		(start 95.123762 -134.384796)
		(mid 95.608775 -134.87019)
		(end 96.094042 -134.38505)
		(stroke
			(width 0.2)
			(type default)
		)
		(layer "In4.Cu")
	)
	(gr_line
		(start 95.123762 -133.11505)
		(end 95.123762 -134.384796)
		(stroke
			(width 0.2)
			(type default)
		)
		(layer "In4.Cu")
	)
	(gr_arc
		(start 95.123762 -19.385026)
		(mid 95.608902 -19.870166)
		(end 96.094042 -19.385026)
		(stroke
			(width 0.2)
			(type default)
		)
		(layer "In4.Cu")
	)
	(gr_line
		(start 95.123762 -18.115026)
		(end 95.123762 -19.385026)
		(stroke
			(width 0.2)
			(type default)
		)
		(layer "In4.Cu")
	)
	(gr_line
		(start 96.094042 -249.385074)
		(end 96.094042 -248.115328)
		(stroke
			(width 0.2)
			(type default)
		)
		(layer "In4.Cu")
	)
	(gr_arc
		(start 96.094042 -248.115328)
		(mid 95.609029 -247.629934)
		(end 95.123762 -248.115074)
		(stroke
			(width 0.2)
			(type default)
		)
		(layer "In4.Cu")
	)
	(gr_line
		(start 96.094042 -134.38505)
		(end 96.094042 -133.11505)
		(stroke
			(width 0.2)
			(type default)
		)
		(layer "In4.Cu")
	)
	(gr_arc
		(start 96.094042 -133.11505)
		(mid 95.608902 -132.62991)
		(end 95.123762 -133.11505)
		(stroke
			(width 0.2)
			(type default)
		)
		(layer "In4.Cu")
	)
	(gr_line
		(start 96.094042 -19.385026)
		(end 96.094042 -18.11528)
		(stroke
			(width 0.2)
			(type default)
		)
		(layer "In4.Cu")
	)
	(gr_arc
		(start 96.094042 -18.11528)
		(mid 95.609029 -17.629886)
		(end 95.123762 -18.115026)
		(stroke
			(width 0.2)
			(type default)
		)
		(layer "In4.Cu")
	)
	(gr_line
		(start 96.139 -16.129)
		(end 94.361 -16.129)
		(stroke
			(width 0.381)
			(type default)
		)
		(layer "In4.Cu")
	)
	(gr_line
		(start 96.52 -17.145)
		(end 96.52 -16.51)
		(stroke
			(width 0.381)
			(type default)
		)
		(layer "In4.Cu")
	)
	(gr_line
		(start 96.52 -16.51)
		(end 96.139 -16.129)
		(stroke
			(width 0.381)
			(type default)
		)
		(layer "In4.Cu")
	)
	(gr_arc
		(start 96.900492 -245.56212)
		(mid 97.385505 -246.047514)
		(end 97.870772 -245.562374)
		(stroke
			(width 0.2)
			(type default)
		)
		(layer "In4.Cu")
	)
	(gr_line
		(start 96.900492 -244.419374)
		(end 96.900492 -245.56212)
		(stroke
			(width 0.2)
			(type default)
		)
		(layer "In4.Cu")
	)
	(gr_arc
		(start 96.900492 -130.56235)
		(mid 97.385632 -131.04749)
		(end 97.870772 -130.56235)
		(stroke
			(width 0.2)
			(type default)
		)
		(layer "In4.Cu")
	)
	(gr_line
		(start 96.900492 -129.41935)
		(end 96.900492 -130.56235)
		(stroke
			(width 0.2)
			(type default)
		)
		(layer "In4.Cu")
	)
	(gr_arc
		(start 96.900492 -15.562326)
		(mid 97.385632 -16.047466)
		(end 97.870772 -15.562326)
		(stroke
			(width 0.2)
			(type default)
		)
		(layer "In4.Cu")
	)
	(gr_line
		(start 96.900492 -14.419326)
		(end 96.900492 -15.562326)
		(stroke
			(width 0.2)
			(type default)
		)
		(layer "In4.Cu")
	)
	(gr_line
		(start 97.028 -17.653)
		(end 96.52 -17.145)
		(stroke
			(width 0.381)
			(type default)
		)
		(layer "In4.Cu")
	)
	(gr_line
		(start 97.870772 -245.562374)
		(end 97.870772 -244.419374)
		(stroke
			(width 0.2)
			(type default)
		)
		(layer "In4.Cu")
	)
	(gr_arc
		(start 97.870772 -244.419374)
		(mid 97.385632 -243.934234)
		(end 96.900492 -244.419374)
		(stroke
			(width 0.2)
			(type default)
		)
		(layer "In4.Cu")
	)
	(gr_line
		(start 97.870772 -130.56235)
		(end 97.870772 -129.419604)
		(stroke
			(width 0.2)
			(type default)
		)
		(layer "In4.Cu")
	)
	(gr_arc
		(start 97.870772 -129.419604)
		(mid 97.385759 -128.93421)
		(end 96.900492 -129.41935)
		(stroke
			(width 0.2)
			(type default)
		)
		(layer "In4.Cu")
	)
	(gr_line
		(start 97.870772 -15.562326)
		(end 97.870772 -14.41958)
		(stroke
			(width 0.2)
			(type default)
		)
		(layer "In4.Cu")
	)
	(gr_arc
		(start 97.870772 -14.41958)
		(mid 97.385759 -13.934186)
		(end 96.900492 -14.419326)
		(stroke
			(width 0.2)
			(type default)
		)
		(layer "In4.Cu")
	)
	(gr_line
		(start 97.917 -17.653)
		(end 97.028 -17.653)
		(stroke
			(width 0.381)
			(type default)
		)
		(layer "In4.Cu")
	)
	(gr_line
		(start 101.4984 -21.2344)
		(end 97.917 -17.653)
		(stroke
			(width 0.381)
			(type default)
		)
		(layer "In4.Cu")
	)
	(gr_line
		(start 102.743 -346.202)
		(end 103.632 -347.091)
		(stroke
			(width 0.381)
			(type default)
		)
		(layer "In4.Cu")
	)
	(gr_line
		(start 102.743 -332.613)
		(end 102.743 -346.202)
		(stroke
			(width 0.381)
			(type default)
		)
		(layer "In4.Cu")
	)
	(gr_line
		(start 103.632 -364.269782)
		(end 104.043988 -364.68177)
		(stroke
			(width 0.381)
			(type default)
		)
		(layer "In4.Cu")
	)
	(gr_line
		(start 103.632 -347.091)
		(end 103.632 -364.269782)
		(stroke
			(width 0.381)
			(type default)
		)
		(layer "In4.Cu")
	)
	(gr_line
		(start 104.043988 -364.68177)
		(end 109.290612 -364.68177)
		(stroke
			(width 0.381)
			(type default)
		)
		(layer "In4.Cu")
	)
	(gr_line
		(start 104.146604 -331.209396)
		(end 102.743 -332.613)
		(stroke
			(width 0.381)
			(type default)
		)
		(layer "In4.Cu")
	)
	(gr_line
		(start 108.4834 -116.2304)
		(end 112.141 -119.888)
		(stroke
			(width 0.381)
			(type default)
		)
		(layer "In4.Cu")
	)
	(gr_line
		(start 109.290612 -364.68177)
		(end 112.207802 -361.76458)
		(stroke
			(width 0.381)
			(type default)
		)
		(layer "In4.Cu")
	)
	(gr_line
		(start 111.6076 -21.2344)
		(end 101.4984 -21.2344)
		(stroke
			(width 0.381)
			(type default)
		)
		(layer "In4.Cu")
	)
	(gr_line
		(start 112.141 -137.668)
		(end 113.919 -139.446)
		(stroke
			(width 0.381)
			(type default)
		)
		(layer "In4.Cu")
	)
	(gr_line
		(start 112.141 -119.888)
		(end 112.141 -137.668)
		(stroke
			(width 0.381)
			(type default)
		)
		(layer "In4.Cu")
	)
	(gr_line
		(start 112.207802 -361.76458)
		(end 123.074938 -361.76458)
		(stroke
			(width 0.381)
			(type default)
		)
		(layer "In4.Cu")
	)
	(gr_line
		(start 113.919 -139.446)
		(end 124.079 -139.446)
		(stroke
			(width 0.381)
			(type default)
		)
		(layer "In4.Cu")
	)
	(gr_line
		(start 113.919 -18.923)
		(end 111.6076 -21.2344)
		(stroke
			(width 0.381)
			(type default)
		)
		(layer "In4.Cu")
	)
	(gr_line
		(start 123.074938 -361.76458)
		(end 126.445518 -358.394)
		(stroke
			(width 0.381)
			(type default)
		)
		(layer "In4.Cu")
	)
	(gr_line
		(start 123.317 -18.923)
		(end 113.919 -18.923)
		(stroke
			(width 0.381)
			(type default)
		)
		(layer "In4.Cu")
	)
	(gr_line
		(start 124.079 -139.446)
		(end 125.73 -137.795)
		(stroke
			(width 0.381)
			(type default)
		)
		(layer "In4.Cu")
	)
	(gr_line
		(start 125.73 -137.795)
		(end 125.73 -131.699)
		(stroke
			(width 0.381)
			(type default)
		)
		(layer "In4.Cu")
	)
	(gr_line
		(start 125.73 -131.699)
		(end 126.365 -131.064)
		(stroke
			(width 0.381)
			(type default)
		)
		(layer "In4.Cu")
	)
	(gr_line
		(start 125.984 -16.256)
		(end 123.317 -18.923)
		(stroke
			(width 0.381)
			(type default)
		)
		(layer "In4.Cu")
	)
	(gr_arc
		(start 126.299976 -384.999992)
		(mid 126.592869 -385.707097)
		(end 127.299974 -385.99999)
		(stroke
			(width 2.54)
			(type default)
		)
		(layer "In4.Cu")
	)
	(gr_arc
		(start 126.299976 -381)
		(mid 126.007082 -380.292902)
		(end 125.299978 -380.000002)
		(stroke
			(width 2.54)
			(type default)
		)
		(layer "In4.Cu")
	)
	(gr_line
		(start 126.299976 -381)
		(end 126.299976 -384.999992)
		(stroke
			(width 2.54)
			(type default)
		)
		(layer "In4.Cu")
	)
	(gr_line
		(start 126.365 -131.064)
		(end 127.508 -131.064)
		(stroke
			(width 0.381)
			(type default)
		)
		(layer "In4.Cu")
	)
	(gr_line
		(start 126.445518 -358.394)
		(end 160.782 -358.394)
		(stroke
			(width 0.381)
			(type default)
		)
		(layer "In4.Cu")
	)
	(gr_arc
		(start 126.67361 -249.385074)
		(mid 127.15875 -249.870214)
		(end 127.64389 -249.385074)
		(stroke
			(width 0.2)
			(type default)
		)
		(layer "In4.Cu")
	)
	(gr_line
		(start 126.67361 -248.115074)
		(end 126.67361 -249.385074)
		(stroke
			(width 0.2)
			(type default)
		)
		(layer "In4.Cu")
	)
	(gr_arc
		(start 126.67361 -134.384796)
		(mid 127.158623 -134.87019)
		(end 127.64389 -134.38505)
		(stroke
			(width 0.2)
			(type default)
		)
		(layer "In4.Cu")
	)
	(gr_line
		(start 126.67361 -133.11505)
		(end 126.67361 -134.384796)
		(stroke
			(width 0.2)
			(type default)
		)
		(layer "In4.Cu")
	)
	(gr_arc
		(start 126.67361 -19.385026)
		(mid 127.15875 -19.870166)
		(end 127.64389 -19.385026)
		(stroke
			(width 0.2)
			(type default)
		)
		(layer "In4.Cu")
	)
	(gr_line
		(start 126.67361 -18.115026)
		(end 126.67361 -19.385026)
		(stroke
			(width 0.2)
			(type default)
		)
		(layer "In4.Cu")
	)
	(gr_line
		(start 127.299974 -385.99999)
		(end 172.850048 -385.99999)
		(stroke
			(width 2.54)
			(type default)
		)
		(layer "In4.Cu")
	)
	(gr_line
		(start 127.508 -131.064)
		(end 128.016 -131.572)
		(stroke
			(width 0.381)
			(type default)
		)
		(layer "In4.Cu")
	)
	(gr_line
		(start 127.64389 -249.385074)
		(end 127.64389 -248.115328)
		(stroke
			(width 0.2)
			(type default)
		)
		(layer "In4.Cu")
	)
	(gr_arc
		(start 127.64389 -248.115328)
		(mid 127.158877 -247.629934)
		(end 126.67361 -248.115074)
		(stroke
			(width 0.2)
			(type default)
		)
		(layer "In4.Cu")
	)
	(gr_line
		(start 127.64389 -134.38505)
		(end 127.64389 -133.11505)
		(stroke
			(width 0.2)
			(type default)
		)
		(layer "In4.Cu")
	)
	(gr_arc
		(start 127.64389 -133.11505)
		(mid 127.15875 -132.62991)
		(end 126.67361 -133.11505)
		(stroke
			(width 0.2)
			(type default)
		)
		(layer "In4.Cu")
	)
	(gr_line
		(start 127.64389 -19.385026)
		(end 127.64389 -18.11528)
		(stroke
			(width 0.2)
			(type default)
		)
		(layer "In4.Cu")
	)
	(gr_arc
		(start 127.64389 -18.11528)
		(mid 127.158877 -17.629886)
		(end 126.67361 -18.115026)
		(stroke
			(width 0.2)
			(type default)
		)
		(layer "In4.Cu")
	)
	(gr_line
		(start 127.762 -16.256)
		(end 125.984 -16.256)
		(stroke
			(width 0.381)
			(type default)
		)
		(layer "In4.Cu")
	)
	(gr_line
		(start 128.016 -132.207)
		(end 128.524 -132.715)
		(stroke
			(width 0.381)
			(type default)
		)
		(layer "In4.Cu")
	)
	(gr_line
		(start 128.016 -131.572)
		(end 128.016 -132.207)
		(stroke
			(width 0.381)
			(type default)
		)
		(layer "In4.Cu")
	)
	(gr_line
		(start 128.016 -17.399)
		(end 128.016 -16.51)
		(stroke
			(width 0.381)
			(type default)
		)
		(layer "In4.Cu")
	)
	(gr_line
		(start 128.016 -16.51)
		(end 127.762 -16.256)
		(stroke
			(width 0.381)
			(type default)
		)
		(layer "In4.Cu")
	)
	(gr_line
		(start 128.397 -17.78)
		(end 128.016 -17.399)
		(stroke
			(width 0.381)
			(type default)
		)
		(layer "In4.Cu")
	)
	(gr_arc
		(start 128.45034 -245.56212)
		(mid 128.935353 -246.047514)
		(end 129.42062 -245.562374)
		(stroke
			(width 0.2)
			(type default)
		)
		(layer "In4.Cu")
	)
	(gr_line
		(start 128.45034 -244.419374)
		(end 128.45034 -245.56212)
		(stroke
			(width 0.2)
			(type default)
		)
		(layer "In4.Cu")
	)
	(gr_arc
		(start 128.45034 -130.56235)
		(mid 128.93548 -131.04749)
		(end 129.42062 -130.56235)
		(stroke
			(width 0.2)
			(type default)
		)
		(layer "In4.Cu")
	)
	(gr_line
		(start 128.45034 -129.41935)
		(end 128.45034 -130.56235)
		(stroke
			(width 0.2)
			(type default)
		)
		(layer "In4.Cu")
	)
	(gr_arc
		(start 128.45034 -15.562326)
		(mid 128.93548 -16.047466)
		(end 129.42062 -15.562326)
		(stroke
			(width 0.2)
			(type default)
		)
		(layer "In4.Cu")
	)
	(gr_line
		(start 128.45034 -14.419326)
		(end 128.45034 -15.562326)
		(stroke
			(width 0.2)
			(type default)
		)
		(layer "In4.Cu")
	)
	(gr_line
		(start 128.524 -132.715)
		(end 134.493 -132.715)
		(stroke
			(width 0.381)
			(type default)
		)
		(layer "In4.Cu")
	)
	(gr_line
		(start 129.42062 -245.562374)
		(end 129.42062 -244.419374)
		(stroke
			(width 0.2)
			(type default)
		)
		(layer "In4.Cu")
	)
	(gr_arc
		(start 129.42062 -244.419374)
		(mid 128.93548 -243.934234)
		(end 128.45034 -244.419374)
		(stroke
			(width 0.2)
			(type default)
		)
		(layer "In4.Cu")
	)
	(gr_line
		(start 129.42062 -130.56235)
		(end 129.42062 -129.419604)
		(stroke
			(width 0.2)
			(type default)
		)
		(layer "In4.Cu")
	)
	(gr_arc
		(start 129.42062 -129.419604)
		(mid 128.935607 -128.93421)
		(end 128.45034 -129.41935)
		(stroke
			(width 0.2)
			(type default)
		)
		(layer "In4.Cu")
	)
	(gr_line
		(start 129.42062 -15.562326)
		(end 129.42062 -14.41958)
		(stroke
			(width 0.2)
			(type default)
		)
		(layer "In4.Cu")
	)
	(gr_arc
		(start 129.42062 -14.41958)
		(mid 128.935607 -13.934186)
		(end 128.45034 -14.419326)
		(stroke
			(width 0.2)
			(type default)
		)
		(layer "In4.Cu")
	)
	(gr_line
		(start 131.318 -17.78)
		(end 128.397 -17.78)
		(stroke
			(width 0.381)
			(type default)
		)
		(layer "In4.Cu")
	)
	(gr_line
		(start 134.493 -132.715)
		(end 141.224 -139.446)
		(stroke
			(width 0.381)
			(type default)
		)
		(layer "In4.Cu")
	)
	(gr_line
		(start 134.7978 -21.2598)
		(end 131.318 -17.78)
		(stroke
			(width 0.381)
			(type default)
		)
		(layer "In4.Cu")
	)
	(gr_line
		(start 141.224 -139.446)
		(end 155.829 -139.446)
		(stroke
			(width 0.381)
			(type default)
		)
		(layer "In4.Cu")
	)
	(gr_line
		(start 144.2212 -21.2598)
		(end 134.7978 -21.2598)
		(stroke
			(width 0.381)
			(type default)
		)
		(layer "In4.Cu")
	)
	(gr_line
		(start 146.558 -18.923)
		(end 144.2212 -21.2598)
		(stroke
			(width 0.381)
			(type default)
		)
		(layer "In4.Cu")
	)
	(gr_line
		(start 151.263604 -331.209396)
		(end 104.146604 -331.209396)
		(stroke
			(width 0.381)
			(type default)
		)
		(layer "In4.Cu")
	)
	(gr_line
		(start 151.638 -330.835)
		(end 151.263604 -331.209396)
		(stroke
			(width 0.381)
			(type default)
		)
		(layer "In4.Cu")
	)
	(gr_line
		(start 151.638 -327.66)
		(end 151.638 -330.835)
		(stroke
			(width 0.381)
			(type default)
		)
		(layer "In4.Cu")
	)
	(gr_line
		(start 152.273 -327.025)
		(end 151.638 -327.66)
		(stroke
			(width 0.381)
			(type default)
		)
		(layer "In4.Cu")
	)
	(gr_line
		(start 155.321 -18.923)
		(end 146.558 -18.923)
		(stroke
			(width 0.381)
			(type default)
		)
		(layer "In4.Cu")
	)
	(gr_line
		(start 155.829 -139.446)
		(end 157.353 -137.922)
		(stroke
			(width 0.381)
			(type default)
		)
		(layer "In4.Cu")
	)
	(gr_circle
		(center 155.999942 -372.599966)
		(end 157.412182 -372.599966)
		(stroke
			(width 0.2)
			(type default)
		)
		(fill no)
		(layer "In4.Cu")
	)
	(gr_circle
		(center 155.999942 -367.09985)
		(end 157.412182 -367.09985)
		(stroke
			(width 0.2)
			(type default)
		)
		(fill no)
		(layer "In4.Cu")
	)
	(gr_line
		(start 157.353 -327.025)
		(end 152.273 -327.025)
		(stroke
			(width 0.381)
			(type default)
		)
		(layer "In4.Cu")
	)
	(gr_line
		(start 157.353 -137.922)
		(end 157.353 -131.699)
		(stroke
			(width 0.381)
			(type default)
		)
		(layer "In4.Cu")
	)
	(gr_line
		(start 157.353 -131.699)
		(end 158.115 -130.937)
		(stroke
			(width 0.381)
			(type default)
		)
		(layer "In4.Cu")
	)
	(gr_line
		(start 157.607 -328.549)
		(end 157.607 -327.279)
		(stroke
			(width 0.381)
			(type default)
		)
		(layer "In4.Cu")
	)
	(gr_line
		(start 157.607 -327.279)
		(end 157.353 -327.025)
		(stroke
			(width 0.381)
			(type default)
		)
		(layer "In4.Cu")
	)
	(gr_line
		(start 157.988 -328.93)
		(end 157.607 -328.549)
		(stroke
			(width 0.381)
			(type default)
		)
		(layer "In4.Cu")
	)
	(gr_line
		(start 157.988 -16.256)
		(end 155.321 -18.923)
		(stroke
			(width 0.381)
			(type default)
		)
		(layer "In4.Cu")
	)
	(gr_line
		(start 158.115 -130.937)
		(end 159.131 -130.937)
		(stroke
			(width 0.381)
			(type default)
		)
		(layer "In4.Cu")
	)
	(gr_arc
		(start 158.223712 -249.38482)
		(mid 158.708725 -249.870214)
		(end 159.193992 -249.385074)
		(stroke
			(width 0.2)
			(type default)
		)
		(layer "In4.Cu")
	)
	(gr_line
		(start 158.223712 -248.115074)
		(end 158.223712 -249.38482)
		(stroke
			(width 0.2)
			(type default)
		)
		(layer "In4.Cu")
	)
	(gr_arc
		(start 158.223712 -134.384796)
		(mid 158.708725 -134.87019)
		(end 159.193992 -134.38505)
		(stroke
			(width 0.2)
			(type default)
		)
		(layer "In4.Cu")
	)
	(gr_line
		(start 158.223712 -133.11505)
		(end 158.223712 -134.384796)
		(stroke
			(width 0.2)
			(type default)
		)
		(layer "In4.Cu")
	)
	(gr_arc
		(start 158.223712 -19.385026)
		(mid 158.708852 -19.870166)
		(end 159.193992 -19.385026)
		(stroke
			(width 0.2)
			(type default)
		)
		(layer "In4.Cu")
	)
	(gr_line
		(start 158.223712 -18.115026)
		(end 158.223712 -19.385026)
		(stroke
			(width 0.2)
			(type default)
		)
		(layer "In4.Cu")
	)
	(gr_line
		(start 159.131 -130.937)
		(end 159.639 -131.445)
		(stroke
			(width 0.381)
			(type default)
		)
		(layer "In4.Cu")
	)
	(gr_line
		(start 159.193992 -249.385074)
		(end 159.193992 -248.115074)
		(stroke
			(width 0.2)
			(type default)
		)
		(layer "In4.Cu")
	)
	(gr_arc
		(start 159.193992 -248.115074)
		(mid 158.708852 -247.629934)
		(end 158.223712 -248.115074)
		(stroke
			(width 0.2)
			(type default)
		)
		(layer "In4.Cu")
	)
	(gr_line
		(start 159.193992 -134.38505)
		(end 159.193992 -133.11505)
		(stroke
			(width 0.2)
			(type default)
		)
		(layer "In4.Cu")
	)
	(gr_arc
		(start 159.193992 -133.11505)
		(mid 158.708852 -132.62991)
		(end 158.223712 -133.11505)
		(stroke
			(width 0.2)
			(type default)
		)
		(layer "In4.Cu")
	)
	(gr_line
		(start 159.193992 -19.385026)
		(end 159.193992 -18.11528)
		(stroke
			(width 0.2)
			(type default)
		)
		(layer "In4.Cu")
	)
	(gr_arc
		(start 159.193992 -18.11528)
		(mid 158.708979 -17.629886)
		(end 158.223712 -18.115026)
		(stroke
			(width 0.2)
			(type default)
		)
		(layer "In4.Cu")
	)
	(gr_line
		(start 159.385 -16.256)
		(end 157.988 -16.256)
		(stroke
			(width 0.381)
			(type default)
		)
		(layer "In4.Cu")
	)
	(gr_line
		(start 159.639 -132.461)
		(end 159.766 -132.588)
		(stroke
			(width 0.381)
			(type default)
		)
		(layer "In4.Cu")
	)
	(gr_line
		(start 159.639 -131.445)
		(end 159.639 -132.461)
		(stroke
			(width 0.381)
			(type default)
		)
		(layer "In4.Cu")
	)
	(gr_line
		(start 159.639 -17.145)
		(end 159.639 -16.51)
		(stroke
			(width 0.381)
			(type default)
		)
		(layer "In4.Cu")
	)
	(gr_line
		(start 159.639 -16.51)
		(end 159.385 -16.256)
		(stroke
			(width 0.381)
			(type default)
		)
		(layer "In4.Cu")
	)
	(gr_line
		(start 159.766 -132.588)
		(end 168.402 -132.588)
		(stroke
			(width 0.381)
			(type default)
		)
		(layer "In4.Cu")
	)
	(gr_arc
		(start 160.000442 -245.56212)
		(mid 160.485455 -246.047514)
		(end 160.970722 -245.562374)
		(stroke
			(width 0.2)
			(type default)
		)
		(layer "In4.Cu")
	)
	(gr_line
		(start 160.000442 -244.419374)
		(end 160.000442 -245.56212)
		(stroke
			(width 0.2)
			(type default)
		)
		(layer "In4.Cu")
	)
	(gr_arc
		(start 160.000442 -130.56235)
		(mid 160.485582 -131.04749)
		(end 160.970722 -130.56235)
		(stroke
			(width 0.2)
			(type default)
		)
		(layer "In4.Cu")
	)
	(gr_line
		(start 160.000442 -129.41935)
		(end 160.000442 -130.56235)
		(stroke
			(width 0.2)
			(type default)
		)
		(layer "In4.Cu")
	)
	(gr_arc
		(start 160.000442 -15.562326)
		(mid 160.485582 -16.047466)
		(end 160.970722 -15.562326)
		(stroke
			(width 0.2)
			(type default)
		)
		(layer "In4.Cu")
	)
	(gr_line
		(start 160.000442 -14.419326)
		(end 160.000442 -15.562326)
		(stroke
			(width 0.2)
			(type default)
		)
		(layer "In4.Cu")
	)
	(gr_line
		(start 160.274 -17.78)
		(end 159.639 -17.145)
		(stroke
			(width 0.381)
			(type default)
		)
		(layer "In4.Cu")
	)
	(gr_line
		(start 160.782 -358.394)
		(end 160.782 -328.93)
		(stroke
			(width 0.381)
			(type default)
		)
		(layer "In4.Cu")
	)
	(gr_line
		(start 160.782 -328.93)
		(end 157.988 -328.93)
		(stroke
			(width 0.381)
			(type default)
		)
		(layer "In4.Cu")
	)
	(gr_line
		(start 160.970722 -245.562374)
		(end 160.970722 -244.419374)
		(stroke
			(width 0.2)
			(type default)
		)
		(layer "In4.Cu")
	)
	(gr_arc
		(start 160.970722 -244.419374)
		(mid 160.485582 -243.934234)
		(end 160.000442 -244.419374)
		(stroke
			(width 0.2)
			(type default)
		)
		(layer "In4.Cu")
	)
	(gr_line
		(start 160.970722 -130.56235)
		(end 160.970722 -129.419604)
		(stroke
			(width 0.2)
			(type default)
		)
		(layer "In4.Cu")
	)
	(gr_arc
		(start 160.970722 -129.419604)
		(mid 160.485709 -128.93421)
		(end 160.000442 -129.41935)
		(stroke
			(width 0.2)
			(type default)
		)
		(layer "In4.Cu")
	)
	(gr_line
		(start 160.970722 -15.562326)
		(end 160.970722 -14.41958)
		(stroke
			(width 0.2)
			(type default)
		)
		(layer "In4.Cu")
	)
	(gr_arc
		(start 160.970722 -14.41958)
		(mid 160.485709 -13.934186)
		(end 160.000442 -14.419326)
		(stroke
			(width 0.2)
			(type default)
		)
		(layer "In4.Cu")
	)
	(gr_line
		(start 161.671 -17.78)
		(end 160.274 -17.78)
		(stroke
			(width 0.381)
			(type default)
		)
		(layer "In4.Cu")
	)
	(gr_line
		(start 165.481 -21.59)
		(end 161.671 -17.78)
		(stroke
			(width 0.381)
			(type default)
		)
		(layer "In4.Cu")
	)
	(gr_line
		(start 166.2049 -358.394)
		(end 204.632814 -358.394)
		(stroke
			(width 0.381)
			(type default)
		)
		(layer "In4.Cu")
	)
	(gr_line
		(start 166.2049 -328.93)
		(end 166.2049 -358.394)
		(stroke
			(width 0.381)
			(type default)
		)
		(layer "In4.Cu")
	)
	(gr_line
		(start 168.402 -132.588)
		(end 175.26 -139.446)
		(stroke
			(width 0.381)
			(type default)
		)
		(layer "In4.Cu")
	)
	(gr_arc
		(start 172.850048 -385.99999)
		(mid 173.557153 -385.707097)
		(end 173.850046 -384.999992)
		(stroke
			(width 2.54)
			(type default)
		)
		(layer "In4.Cu")
	)
	(gr_line
		(start 173.850046 -384.999992)
		(end 173.850046 -383.29997)
		(stroke
			(width 2.54)
			(type default)
		)
		(layer "In4.Cu")
	)
	(gr_arc
		(start 174.850044 -382.299972)
		(mid 174.1429 -382.592847)
		(end 173.850046 -383.29997)
		(stroke
			(width 2.54)
			(type default)
		)
		(layer "In4.Cu")
	)
	(gr_line
		(start 174.850044 -382.299972)
		(end 181.349904 -382.299972)
		(stroke
			(width 2.54)
			(type default)
		)
		(layer "In4.Cu")
	)
	(gr_line
		(start 175.26 -139.446)
		(end 180.975 -139.446)
		(stroke
			(width 0.381)
			(type default)
		)
		(layer "In4.Cu")
	)
	(gr_line
		(start 178.6382 -213.4108)
		(end 92.202 -213.4108)
		(stroke
			(width 0.381)
			(type default)
		)
		(layer "In4.Cu")
	)
	(gr_line
		(start 180.975 -139.446)
		(end 183.134 -137.287)
		(stroke
			(width 0.381)
			(type default)
		)
		(layer "In4.Cu")
	)
	(gr_line
		(start 181.229 -254.381)
		(end 182.88 -252.73)
		(stroke
			(width 0.381)
			(type default)
		)
		(layer "In4.Cu")
	)
	(gr_line
		(start 181.737 -21.59)
		(end 165.481 -21.59)
		(stroke
			(width 0.381)
			(type default)
		)
		(layer "In4.Cu")
	)
	(gr_arc
		(start 182.349902 -384.999992)
		(mid 182.642795 -385.707097)
		(end 183.3499 -385.99999)
		(stroke
			(width 2.54)
			(type default)
		)
		(layer "In4.Cu")
	)
	(gr_arc
		(start 182.349902 -383.29997)
		(mid 182.056999 -382.592883)
		(end 181.349904 -382.299972)
		(stroke
			(width 2.54)
			(type default)
		)
		(layer "In4.Cu")
	)
	(gr_line
		(start 182.349902 -383.29997)
		(end 182.349902 -384.999992)
		(stroke
			(width 2.54)
			(type default)
		)
		(layer "In4.Cu")
	)
	(gr_line
		(start 182.88 -252.73)
		(end 182.88 -217.6526)
		(stroke
			(width 0.381)
			(type default)
		)
		(layer "In4.Cu")
	)
	(gr_line
		(start 182.88 -217.6526)
		(end 178.6382 -213.4108)
		(stroke
			(width 0.381)
			(type default)
		)
		(layer "In4.Cu")
	)
	(gr_line
		(start 183.134 -137.287)
		(end 183.134 -91.7448)
		(stroke
			(width 0.381)
			(type default)
		)
		(layer "In4.Cu")
	)
	(gr_line
		(start 183.134 -91.7448)
		(end 187.1472 -87.7316)
		(stroke
			(width 0.381)
			(type default)
		)
		(layer "In4.Cu")
	)
	(gr_line
		(start 183.134 -78.2828)
		(end 183.134 -22.987)
		(stroke
			(width 0.381)
			(type default)
		)
		(layer "In4.Cu")
	)
	(gr_line
		(start 183.134 -22.987)
		(end 181.737 -21.59)
		(stroke
			(width 0.381)
			(type default)
		)
		(layer "In4.Cu")
	)
	(gr_line
		(start 183.3499 -385.99999)
		(end 197.000114 -385.99999)
		(stroke
			(width 2.54)
			(type default)
		)
		(layer "In4.Cu")
	)
	(gr_line
		(start 186.0042 -81.153)
		(end 183.134 -78.2828)
		(stroke
			(width 0.381)
			(type default)
		)
		(layer "In4.Cu")
	)
	(gr_line
		(start 187.1472 -87.7316)
		(end 192.3796 -87.7316)
		(stroke
			(width 0.381)
			(type default)
		)
		(layer "In4.Cu")
	)
	(gr_arc
		(start 189.773814 -249.385074)
		(mid 190.258954 -249.870214)
		(end 190.744094 -249.385074)
		(stroke
			(width 0.2)
			(type default)
		)
		(layer "In4.Cu")
	)
	(gr_line
		(start 189.773814 -248.115074)
		(end 189.773814 -249.385074)
		(stroke
			(width 0.2)
			(type default)
		)
		(layer "In4.Cu")
	)
	(gr_arc
		(start 189.773814 -134.38505)
		(mid 190.258954 -134.87019)
		(end 190.744094 -134.38505)
		(stroke
			(width 0.2)
			(type default)
		)
		(layer "In4.Cu")
	)
	(gr_line
		(start 189.773814 -133.11505)
		(end 189.773814 -134.38505)
		(stroke
			(width 0.2)
			(type default)
		)
		(layer "In4.Cu")
	)
	(gr_arc
		(start 189.773814 -19.385026)
		(mid 190.258954 -19.870166)
		(end 190.744094 -19.385026)
		(stroke
			(width 0.2)
			(type default)
		)
		(layer "In4.Cu")
	)
	(gr_line
		(start 189.773814 -18.115026)
		(end 189.773814 -19.385026)
		(stroke
			(width 0.2)
			(type default)
		)
		(layer "In4.Cu")
	)
	(gr_line
		(start 190.744094 -249.385074)
		(end 190.744094 -248.115328)
		(stroke
			(width 0.2)
			(type default)
		)
		(layer "In4.Cu")
	)
	(gr_arc
		(start 190.744094 -248.115328)
		(mid 190.259081 -247.629934)
		(end 189.773814 -248.115074)
		(stroke
			(width 0.2)
			(type default)
		)
		(layer "In4.Cu")
	)
	(gr_line
		(start 190.744094 -134.38505)
		(end 190.744094 -133.115304)
		(stroke
			(width 0.2)
			(type default)
		)
		(layer "In4.Cu")
	)
	(gr_arc
		(start 190.744094 -133.115304)
		(mid 190.259081 -132.62991)
		(end 189.773814 -133.11505)
		(stroke
			(width 0.2)
			(type default)
		)
		(layer "In4.Cu")
	)
	(gr_line
		(start 190.744094 -19.385026)
		(end 190.744094 -18.11528)
		(stroke
			(width 0.2)
			(type default)
		)
		(layer "In4.Cu")
	)
	(gr_arc
		(start 190.744094 -18.11528)
		(mid 190.259081 -17.629886)
		(end 189.773814 -18.115026)
		(stroke
			(width 0.2)
			(type default)
		)
		(layer "In4.Cu")
	)
	(gr_arc
		(start 191.550544 -245.56212)
		(mid 192.035557 -246.047514)
		(end 192.520824 -245.562374)
		(stroke
			(width 0.2)
			(type default)
		)
		(layer "In4.Cu")
	)
	(gr_line
		(start 191.550544 -244.419374)
		(end 191.550544 -245.56212)
		(stroke
			(width 0.2)
			(type default)
		)
		(layer "In4.Cu")
	)
	(gr_arc
		(start 191.550544 -130.56235)
		(mid 192.035684 -131.04749)
		(end 192.520824 -130.56235)
		(stroke
			(width 0.2)
			(type default)
		)
		(layer "In4.Cu")
	)
	(gr_line
		(start 191.550544 -129.41935)
		(end 191.550544 -130.56235)
		(stroke
			(width 0.2)
			(type default)
		)
		(layer "In4.Cu")
	)
	(gr_arc
		(start 191.550544 -15.562326)
		(mid 192.035684 -16.047466)
		(end 192.520824 -15.562326)
		(stroke
			(width 0.2)
			(type default)
		)
		(layer "In4.Cu")
	)
	(gr_line
		(start 191.550544 -14.419326)
		(end 191.550544 -15.562326)
		(stroke
			(width 0.2)
			(type default)
		)
		(layer "In4.Cu")
	)
	(gr_line
		(start 192.3796 -87.7316)
		(end 193.3956 -88.7476)
		(stroke
			(width 0.381)
			(type default)
		)
		(layer "In4.Cu")
	)
	(gr_line
		(start 192.520824 -245.562374)
		(end 192.520824 -244.419374)
		(stroke
			(width 0.2)
			(type default)
		)
		(layer "In4.Cu")
	)
	(gr_arc
		(start 192.520824 -244.419374)
		(mid 192.035684 -243.934234)
		(end 191.550544 -244.419374)
		(stroke
			(width 0.2)
			(type default)
		)
		(layer "In4.Cu")
	)
	(gr_line
		(start 192.520824 -130.56235)
		(end 192.520824 -129.419604)
		(stroke
			(width 0.2)
			(type default)
		)
		(layer "In4.Cu")
	)
	(gr_arc
		(start 192.520824 -129.419604)
		(mid 192.035811 -128.93421)
		(end 191.550544 -129.41935)
		(stroke
			(width 0.2)
			(type default)
		)
		(layer "In4.Cu")
	)
	(gr_line
		(start 192.520824 -15.562326)
		(end 192.520824 -14.41958)
		(stroke
			(width 0.2)
			(type default)
		)
		(layer "In4.Cu")
	)
	(gr_arc
		(start 192.520824 -14.41958)
		(mid 192.035811 -13.934186)
		(end 191.550544 -14.419326)
		(stroke
			(width 0.2)
			(type default)
		)
		(layer "In4.Cu")
	)
	(gr_line
		(start 193.3956 -88.7476)
		(end 229.7684 -88.7476)
		(stroke
			(width 0.381)
			(type default)
		)
		(layer "In4.Cu")
	)
	(gr_line
		(start 193.81089 -310.87822)
		(end 193.81089 -124.718572)
		(stroke
			(width 0.381)
			(type default)
		)
		(layer "In4.Cu")
	)
	(gr_line
		(start 193.81089 -124.718572)
		(end 198.974202 -119.55526)
		(stroke
			(width 0.381)
			(type default)
		)
		(layer "In4.Cu")
	)
	(gr_arc
		(start 197.000114 -385.99999)
		(mid 197.707219 -385.707097)
		(end 198.000112 -384.999992)
		(stroke
			(width 2.54)
			(type default)
		)
		(layer "In4.Cu")
	)
	(gr_line
		(start 198.000112 -384.999992)
		(end 198.000112 -381)
		(stroke
			(width 2.54)
			(type default)
		)
		(layer "In4.Cu")
	)
	(gr_line
		(start 198.000112 0)
		(end 0.999998 0)
		(stroke
			(width 2.54)
			(type default)
		)
		(layer "In4.Cu")
	)
	(gr_line
		(start 198.974202 -119.55526)
		(end 198.974202 -105.405428)
		(stroke
			(width 0.381)
			(type default)
		)
		(layer "In4.Cu")
	)
	(gr_line
		(start 198.974202 -105.405428)
		(end 210.93684 -93.44279)
		(stroke
			(width 0.381)
			(type default)
		)
		(layer "In4.Cu")
	)
	(gr_arc
		(start 199.00011 -380.000002)
		(mid 198.292998 -380.292891)
		(end 198.000112 -381)
		(stroke
			(width 2.54)
			(type default)
		)
		(layer "In4.Cu")
	)
	(gr_line
		(start 199.00011 -380.000002)
		(end 251.000006 -380.000002)
		(stroke
			(width 2.54)
			(type default)
		)
		(layer "In4.Cu")
	)
	(gr_line
		(start 199.00011 -47.200058)
		(end 199.00011 -0.999998)
		(stroke
			(width 2.54)
			(type default)
		)
		(layer "In4.Cu")
	)
	(gr_arc
		(start 199.00011 -47.200058)
		(mid 199.292988 -47.907188)
		(end 200.000108 -48.200056)
		(stroke
			(width 2.54)
			(type default)
		)
		(layer "In4.Cu")
	)
	(gr_arc
		(start 199.00011 -0.999998)
		(mid 198.707217 -0.292893)
		(end 198.000112 0)
		(stroke
			(width 2.54)
			(type default)
		)
		(layer "In4.Cu")
	)
	(gr_line
		(start 204.2033 -358.3813)
		(end 204.5843 -358.7623)
		(stroke
			(width 0.381)
			(type default)
		)
		(layer "In4.Cu")
	)
	(gr_line
		(start 204.2287 -328.93)
		(end 204.6351 -328.5236)
		(stroke
			(width 0.381)
			(type default)
		)
		(layer "In4.Cu")
	)
	(gr_line
		(start 204.6097 -329.311)
		(end 204.2287 -328.93)
		(stroke
			(width 0.381)
			(type default)
		)
		(layer "In4.Cu")
	)
	(gr_line
		(start 204.632814 -328.93)
		(end 166.2049 -328.93)
		(stroke
			(width 0.381)
			(type default)
		)
		(layer "In4.Cu")
	)
	(gr_line
		(start 204.6351 -363.762544)
		(end 204.6351 -321.70243)
		(stroke
			(width 0.381)
			(type default)
		)
		(layer "In4.Cu")
	)
	(gr_line
		(start 204.6351 -357.9495)
		(end 204.2033 -358.3813)
		(stroke
			(width 0.381)
			(type default)
		)
		(layer "In4.Cu")
	)
	(gr_line
		(start 204.6351 -321.70243)
		(end 193.81089 -310.87822)
		(stroke
			(width 0.381)
			(type default)
		)
		(layer "In4.Cu")
	)
	(gr_line
		(start 205.438756 -364.5662)
		(end 204.6351 -363.762544)
		(stroke
			(width 0.381)
			(type default)
		)
		(layer "In4.Cu")
	)
	(gr_line
		(start 206.000096 -48.200056)
		(end 200.000108 -48.200056)
		(stroke
			(width 2.54)
			(type default)
		)
		(layer "In4.Cu")
	)
	(gr_line
		(start 207.000094 -61.999876)
		(end 207.000094 -49.200054)
		(stroke
			(width 2.54)
			(type default)
		)
		(layer "In4.Cu")
	)
	(gr_arc
		(start 207.000094 -61.999876)
		(mid 207.292978 -62.707)
		(end 208.000092 -62.999874)
		(stroke
			(width 2.54)
			(type default)
		)
		(layer "In4.Cu")
	)
	(gr_arc
		(start 207.000094 -49.200054)
		(mid 206.707201 -48.492949)
		(end 206.000096 -48.200056)
		(stroke
			(width 2.54)
			(type default)
		)
		(layer "In4.Cu")
	)
	(gr_arc
		(start 209.451448 -78.999842)
		(mid 210.000088 -79.548482)
		(end 210.548728 -78.999842)
		(stroke
			(width 0.2)
			(type default)
		)
		(layer "In4.Cu")
	)
	(gr_line
		(start 209.451448 -77.600048)
		(end 209.451448 -78.999842)
		(stroke
			(width 0.2)
			(type default)
		)
		(layer "In4.Cu")
	)
	(gr_arc
		(start 209.451448 -75.399646)
		(mid 209.999961 -75.94854)
		(end 210.548728 -75.3999)
		(stroke
			(width 0.2)
			(type default)
		)
		(layer "In4.Cu")
	)
	(gr_line
		(start 209.451448 -73.999852)
		(end 209.451448 -75.399646)
		(stroke
			(width 0.2)
			(type default)
		)
		(layer "In4.Cu")
	)
	(gr_arc
		(start 209.451448 -71.799704)
		(mid 209.999961 -72.348598)
		(end 210.548728 -71.799958)
		(stroke
			(width 0.2)
			(type default)
		)
		(layer "In4.Cu")
	)
	(gr_line
		(start 209.451448 -70.39991)
		(end 209.451448 -71.799704)
		(stroke
			(width 0.2)
			(type default)
		)
		(layer "In4.Cu")
	)
	(gr_line
		(start 210.548728 -78.999842)
		(end 210.548728 -77.600302)
		(stroke
			(width 0.2)
			(type default)
		)
		(layer "In4.Cu")
	)
	(gr_arc
		(start 210.548728 -77.600302)
		(mid 210.000215 -77.051408)
		(end 209.451448 -77.600048)
		(stroke
			(width 0.2)
			(type default)
		)
		(layer "In4.Cu")
	)
	(gr_line
		(start 210.548728 -75.3999)
		(end 210.548728 -73.999852)
		(stroke
			(width 0.2)
			(type default)
		)
		(layer "In4.Cu")
	)
	(gr_arc
		(start 210.548728 -73.999852)
		(mid 210.000088 -73.451212)
		(end 209.451448 -73.999852)
		(stroke
			(width 0.2)
			(type default)
		)
		(layer "In4.Cu")
	)
	(gr_line
		(start 210.548728 -71.799958)
		(end 210.548728 -70.39991)
		(stroke
			(width 0.2)
			(type default)
		)
		(layer "In4.Cu")
	)
	(gr_arc
		(start 210.548728 -70.39991)
		(mid 210.000088 -69.85127)
		(end 209.451448 -70.39991)
		(stroke
			(width 0.2)
			(type default)
		)
		(layer "In4.Cu")
	)
	(gr_line
		(start 210.93684 -93.44279)
		(end 240.13541 -93.44279)
		(stroke
			(width 0.381)
			(type default)
		)
		(layer "In4.Cu")
	)
	(gr_arc
		(start 211.251546 -77.799692)
		(mid 211.800059 -78.348586)
		(end 212.348826 -77.799946)
		(stroke
			(width 0.2)
			(type default)
		)
		(layer "In4.Cu")
	)
	(gr_line
		(start 211.251546 -76.399898)
		(end 211.251546 -77.799692)
		(stroke
			(width 0.2)
			(type default)
		)
		(layer "In4.Cu")
	)
	(gr_arc
		(start 211.251546 -66.999612)
		(mid 211.800059 -67.548506)
		(end 212.348826 -66.999866)
		(stroke
			(width 0.2)
			(type default)
		)
		(layer "In4.Cu")
	)
	(gr_line
		(start 211.251546 -65.600072)
		(end 211.251546 -66.999612)
		(stroke
			(width 0.2)
			(type default)
		)
		(layer "In4.Cu")
	)
	(gr_line
		(start 212.348826 -77.799946)
		(end 212.348826 -76.399898)
		(stroke
			(width 0.2)
			(type default)
		)
		(layer "In4.Cu")
	)
	(gr_arc
		(start 212.348826 -76.399898)
		(mid 211.800186 -75.851258)
		(end 211.251546 -76.399898)
		(stroke
			(width 0.2)
			(type default)
		)
		(layer "In4.Cu")
	)
	(gr_line
		(start 212.348826 -66.999866)
		(end 212.348826 -65.600072)
		(stroke
			(width 0.2)
			(type default)
		)
		(layer "In4.Cu")
	)
	(gr_arc
		(start 212.348826 -65.600072)
		(mid 211.800186 -65.051432)
		(end 211.251546 -65.600072)
		(stroke
			(width 0.2)
			(type default)
		)
		(layer "In4.Cu")
	)
	(gr_arc
		(start 213.05139 -78.999842)
		(mid 213.60003 -79.548482)
		(end 214.14867 -78.999842)
		(stroke
			(width 0.2)
			(type default)
		)
		(layer "In4.Cu")
	)
	(gr_line
		(start 213.05139 -77.600048)
		(end 213.05139 -78.999842)
		(stroke
			(width 0.2)
			(type default)
		)
		(layer "In4.Cu")
	)
	(gr_arc
		(start 213.05139 -71.799704)
		(mid 213.599903 -72.348598)
		(end 214.14867 -71.799958)
		(stroke
			(width 0.2)
			(type default)
		)
		(layer "In4.Cu")
	)
	(gr_line
		(start 213.05139 -70.39991)
		(end 213.05139 -71.799704)
		(stroke
			(width 0.2)
			(type default)
		)
		(layer "In4.Cu")
	)
	(gr_line
		(start 214.14867 -78.999842)
		(end 214.14867 -77.600302)
		(stroke
			(width 0.2)
			(type default)
		)
		(layer "In4.Cu")
	)
	(gr_arc
		(start 214.14867 -77.600302)
		(mid 213.600157 -77.051408)
		(end 213.05139 -77.600048)
		(stroke
			(width 0.2)
			(type default)
		)
		(layer "In4.Cu")
	)
	(gr_line
		(start 214.14867 -71.799958)
		(end 214.14867 -70.39991)
		(stroke
			(width 0.2)
			(type default)
		)
		(layer "In4.Cu")
	)
	(gr_arc
		(start 214.14867 -70.39991)
		(mid 213.60003 -69.85127)
		(end 213.05139 -70.39991)
		(stroke
			(width 0.2)
			(type default)
		)
		(layer "In4.Cu")
	)
	(gr_arc
		(start 214.851488 -77.799692)
		(mid 215.400001 -78.348586)
		(end 215.948768 -77.799946)
		(stroke
			(width 0.2)
			(type default)
		)
		(layer "In4.Cu")
	)
	(gr_line
		(start 214.851488 -76.399898)
		(end 214.851488 -77.799692)
		(stroke
			(width 0.2)
			(type default)
		)
		(layer "In4.Cu")
	)
	(gr_arc
		(start 214.851488 -66.999612)
		(mid 215.400001 -67.548506)
		(end 215.948768 -66.999866)
		(stroke
			(width 0.2)
			(type default)
		)
		(layer "In4.Cu")
	)
	(gr_line
		(start 214.851488 -65.600072)
		(end 214.851488 -66.999612)
		(stroke
			(width 0.2)
			(type default)
		)
		(layer "In4.Cu")
	)
	(gr_line
		(start 215.948768 -77.799946)
		(end 215.948768 -76.399898)
		(stroke
			(width 0.2)
			(type default)
		)
		(layer "In4.Cu")
	)
	(gr_arc
		(start 215.948768 -76.399898)
		(mid 215.400128 -75.851258)
		(end 214.851488 -76.399898)
		(stroke
			(width 0.2)
			(type default)
		)
		(layer "In4.Cu")
	)
	(gr_line
		(start 215.948768 -66.999866)
		(end 215.948768 -65.600072)
		(stroke
			(width 0.2)
			(type default)
		)
		(layer "In4.Cu")
	)
	(gr_arc
		(start 215.948768 -65.600072)
		(mid 215.400128 -65.051432)
		(end 214.851488 -65.600072)
		(stroke
			(width 0.2)
			(type default)
		)
		(layer "In4.Cu")
	)
	(gr_arc
		(start 216.651332 -78.999842)
		(mid 217.199972 -79.548482)
		(end 217.748612 -78.999842)
		(stroke
			(width 0.2)
			(type default)
		)
		(layer "In4.Cu")
	)
	(gr_line
		(start 216.651332 -77.600048)
		(end 216.651332 -78.999842)
		(stroke
			(width 0.2)
			(type default)
		)
		(layer "In4.Cu")
	)
	(gr_arc
		(start 216.651332 -71.799704)
		(mid 217.199845 -72.348598)
		(end 217.748612 -71.799958)
		(stroke
			(width 0.2)
			(type default)
		)
		(layer "In4.Cu")
	)
	(gr_line
		(start 216.651332 -70.39991)
		(end 216.651332 -71.799704)
		(stroke
			(width 0.2)
			(type default)
		)
		(layer "In4.Cu")
	)
	(gr_line
		(start 217.748612 -78.999842)
		(end 217.748612 -77.600302)
		(stroke
			(width 0.2)
			(type default)
		)
		(layer "In4.Cu")
	)
	(gr_arc
		(start 217.748612 -77.600302)
		(mid 217.200099 -77.051408)
		(end 216.651332 -77.600048)
		(stroke
			(width 0.2)
			(type default)
		)
		(layer "In4.Cu")
	)
	(gr_line
		(start 217.748612 -71.799958)
		(end 217.748612 -70.39991)
		(stroke
			(width 0.2)
			(type default)
		)
		(layer "In4.Cu")
	)
	(gr_arc
		(start 217.748612 -70.39991)
		(mid 217.199972 -69.85127)
		(end 216.651332 -70.39991)
		(stroke
			(width 0.2)
			(type default)
		)
		(layer "In4.Cu")
	)
	(gr_arc
		(start 218.45143 -77.799692)
		(mid 218.999943 -78.348586)
		(end 219.54871 -77.799946)
		(stroke
			(width 0.2)
			(type default)
		)
		(layer "In4.Cu")
	)
	(gr_line
		(start 218.45143 -76.399898)
		(end 218.45143 -77.799692)
		(stroke
			(width 0.2)
			(type default)
		)
		(layer "In4.Cu")
	)
	(gr_arc
		(start 218.45143 -66.999612)
		(mid 218.999943 -67.548506)
		(end 219.54871 -66.999866)
		(stroke
			(width 0.2)
			(type default)
		)
		(layer "In4.Cu")
	)
	(gr_line
		(start 218.45143 -65.600072)
		(end 218.45143 -66.999612)
		(stroke
			(width 0.2)
			(type default)
		)
		(layer "In4.Cu")
	)
	(gr_line
		(start 219.54871 -77.799946)
		(end 219.54871 -76.399898)
		(stroke
			(width 0.2)
			(type default)
		)
		(layer "In4.Cu")
	)
	(gr_arc
		(start 219.54871 -76.399898)
		(mid 219.00007 -75.851258)
		(end 218.45143 -76.399898)
		(stroke
			(width 0.2)
			(type default)
		)
		(layer "In4.Cu")
	)
	(gr_line
		(start 219.54871 -66.999866)
		(end 219.54871 -65.600072)
		(stroke
			(width 0.2)
			(type default)
		)
		(layer "In4.Cu")
	)
	(gr_arc
		(start 219.54871 -65.600072)
		(mid 219.00007 -65.051432)
		(end 218.45143 -65.600072)
		(stroke
			(width 0.2)
			(type default)
		)
		(layer "In4.Cu")
	)
	(gr_arc
		(start 220.251528 -78.999842)
		(mid 220.800168 -79.548482)
		(end 221.348808 -78.999842)
		(stroke
			(width 0.2)
			(type default)
		)
		(layer "In4.Cu")
	)
	(gr_line
		(start 220.251528 -77.600048)
		(end 220.251528 -78.999842)
		(stroke
			(width 0.2)
			(type default)
		)
		(layer "In4.Cu")
	)
	(gr_arc
		(start 220.251528 -71.799704)
		(mid 220.800041 -72.348598)
		(end 221.348808 -71.799958)
		(stroke
			(width 0.2)
			(type default)
		)
		(layer "In4.Cu")
	)
	(gr_line
		(start 220.251528 -70.39991)
		(end 220.251528 -71.799704)
		(stroke
			(width 0.2)
			(type default)
		)
		(layer "In4.Cu")
	)
	(gr_line
		(start 221.348808 -78.999842)
		(end 221.348808 -77.600302)
		(stroke
			(width 0.2)
			(type default)
		)
		(layer "In4.Cu")
	)
	(gr_arc
		(start 221.348808 -77.600302)
		(mid 220.800295 -77.051408)
		(end 220.251528 -77.600048)
		(stroke
			(width 0.2)
			(type default)
		)
		(layer "In4.Cu")
	)
	(gr_line
		(start 221.348808 -71.799958)
		(end 221.348808 -70.39991)
		(stroke
			(width 0.2)
			(type default)
		)
		(layer "In4.Cu")
	)
	(gr_arc
		(start 221.348808 -70.39991)
		(mid 220.800168 -69.85127)
		(end 220.251528 -70.39991)
		(stroke
			(width 0.2)
			(type default)
		)
		(layer "In4.Cu")
	)
	(gr_arc
		(start 222.051372 -77.799692)
		(mid 222.599885 -78.348586)
		(end 223.148652 -77.799946)
		(stroke
			(width 0.2)
			(type default)
		)
		(layer "In4.Cu")
	)
	(gr_line
		(start 222.051372 -76.399898)
		(end 222.051372 -77.799692)
		(stroke
			(width 0.2)
			(type default)
		)
		(layer "In4.Cu")
	)
	(gr_arc
		(start 222.051372 -66.999866)
		(mid 222.600012 -67.548506)
		(end 223.148652 -66.999866)
		(stroke
			(width 0.2)
			(type default)
		)
		(layer "In4.Cu")
	)
	(gr_line
		(start 222.051372 -65.600072)
		(end 222.051372 -66.999866)
		(stroke
			(width 0.2)
			(type default)
		)
		(layer "In4.Cu")
	)
	(gr_line
		(start 223.148652 -77.799946)
		(end 223.148652 -76.399898)
		(stroke
			(width 0.2)
			(type default)
		)
		(layer "In4.Cu")
	)
	(gr_arc
		(start 223.148652 -76.399898)
		(mid 222.600012 -75.851258)
		(end 222.051372 -76.399898)
		(stroke
			(width 0.2)
			(type default)
		)
		(layer "In4.Cu")
	)
	(gr_line
		(start 223.148652 -66.999866)
		(end 223.148652 -65.600326)
		(stroke
			(width 0.2)
			(type default)
		)
		(layer "In4.Cu")
	)
	(gr_arc
		(start 223.148652 -65.600326)
		(mid 222.600139 -65.051432)
		(end 222.051372 -65.600072)
		(stroke
			(width 0.2)
			(type default)
		)
		(layer "In4.Cu")
	)
	(gr_line
		(start 223.2152 -81.153)
		(end 186.0042 -81.153)
		(stroke
			(width 0.381)
			(type default)
		)
		(layer "In4.Cu")
	)
	(gr_line
		(start 224.1296 -80.2386)
		(end 223.2152 -81.153)
		(stroke
			(width 0.381)
			(type default)
		)
		(layer "In4.Cu")
	)
	(gr_line
		(start 224.1296 -78.0796)
		(end 224.1296 -80.2386)
		(stroke
			(width 0.381)
			(type default)
		)
		(layer "In4.Cu")
	)
	(gr_line
		(start 225.1456 -77.0636)
		(end 224.1296 -78.0796)
		(stroke
			(width 0.381)
			(type default)
		)
		(layer "In4.Cu")
	)
	(gr_line
		(start 227.8888 -364.5662)
		(end 205.438756 -364.5662)
		(stroke
			(width 0.381)
			(type default)
		)
		(layer "In4.Cu")
	)
	(gr_line
		(start 229.7684 -88.7476)
		(end 233.9848 -84.5312)
		(stroke
			(width 0.381)
			(type default)
		)
		(layer "In4.Cu")
	)
	(gr_line
		(start 232.6894 -77.0636)
		(end 225.1456 -77.0636)
		(stroke
			(width 0.381)
			(type default)
		)
		(layer "In4.Cu")
	)
	(gr_line
		(start 233.9848 -84.5312)
		(end 233.9848 -78.359)
		(stroke
			(width 0.381)
			(type default)
		)
		(layer "In4.Cu")
	)
	(gr_line
		(start 233.9848 -78.359)
		(end 232.6894 -77.0636)
		(stroke
			(width 0.381)
			(type default)
		)
		(layer "In4.Cu")
	)
	(gr_line
		(start 240.13541 -93.44279)
		(end 252.4506 -81.1276)
		(stroke
			(width 0.381)
			(type default)
		)
		(layer "In4.Cu")
	)
	(gr_line
		(start 245.618 -346.837)
		(end 227.8888 -364.5662)
		(stroke
			(width 0.381)
			(type default)
		)
		(layer "In4.Cu")
	)
	(gr_line
		(start 245.618 -326.644)
		(end 245.618 -346.837)
		(stroke
			(width 0.381)
			(type default)
		)
		(layer "In4.Cu")
	)
	(gr_line
		(start 247.523 -324.739)
		(end 245.618 -326.644)
		(stroke
			(width 0.381)
			(type default)
		)
		(layer "In4.Cu")
	)
	(gr_arc
		(start 252.000004 -384.999992)
		(mid 252.292897 -385.707097)
		(end 253.000002 -385.99999)
		(stroke
			(width 2.54)
			(type default)
		)
		(layer "In4.Cu")
	)
	(gr_arc
		(start 252.000004 -381)
		(mid 251.707112 -380.292893)
		(end 251.000006 -380.000002)
		(stroke
			(width 2.54)
			(type default)
		)
		(layer "In4.Cu")
	)
	(gr_line
		(start 252.000004 -381)
		(end 252.000004 -384.999992)
		(stroke
			(width 2.54)
			(type default)
		)
		(layer "In4.Cu")
	)
	(gr_line
		(start 252.4506 -81.1276)
		(end 252.4506 -62.999874)
		(stroke
			(width 0.381)
			(type default)
		)
		(layer "In4.Cu")
	)
	(gr_line
		(start 252.4506 -62.999874)
		(end 208.000092 -62.999874)
		(stroke
			(width 2.54)
			(type default)
		)
		(layer "In4.Cu")
	)
	(gr_line
		(start 253.000002 -385.99999)
		(end 269.035784 -385.99999)
		(stroke
			(width 2.54)
			(type default)
		)
		(layer "In4.Cu")
	)
	(gr_line
		(start 267.999972 -62.999874)
		(end 252.4506 -62.999874)
		(stroke
			(width 2.54)
			(type default)
		)
		(layer "In4.Cu")
	)
	(gr_arc
		(start 267.999972 -62.999874)
		(mid 268.707087 -62.70699)
		(end 268.99997 -61.999876)
		(stroke
			(width 2.54)
			(type default)
		)
		(layer "In4.Cu")
	)
	(gr_line
		(start 268.99997 -63.00597)
		(end 271.523714 -65.529714)
		(stroke
			(width 0.381)
			(type default)
		)
		(layer "In4.Cu")
	)
	(gr_line
		(start 268.99997 -49.200054)
		(end 268.99997 -61.999876)
		(stroke
			(width 2.54)
			(type default)
		)
		(layer "In4.Cu")
	)
	(gr_arc
		(start 269.035784 -385.99999)
		(mid 269.418467 -385.92387)
		(end 269.74292 -385.707128)
		(stroke
			(width 2.54)
			(type default)
		)
		(layer "In4.Cu")
	)
	(gr_line
		(start 269.74292 -385.707128)
		(end 272.15719 -383.292858)
		(stroke
			(width 2.54)
			(type default)
		)
		(layer "In4.Cu")
	)
	(gr_arc
		(start 269.999968 -48.200056)
		(mid 269.292863 -48.492949)
		(end 268.99997 -49.200054)
		(stroke
			(width 2.54)
			(type default)
		)
		(layer "In4.Cu")
	)
	(gr_line
		(start 271.523714 -65.529714)
		(end 306.382674 -65.529714)
		(stroke
			(width 0.381)
			(type default)
		)
		(layer "In4.Cu")
	)
	(gr_arc
		(start 272.15719 -383.292858)
		(mid 272.373972 -382.968421)
		(end 272.450052 -382.585722)
		(stroke
			(width 2.54)
			(type default)
		)
		(layer "In4.Cu")
	)
	(gr_line
		(start 272.450052 -382.585722)
		(end 272.450052 -361.00004)
		(stroke
			(width 2.54)
			(type default)
		)
		(layer "In4.Cu")
	)
	(gr_arc
		(start 273.45005 -360.000042)
		(mid 272.742991 -360.292955)
		(end 272.450052 -361.00004)
		(stroke
			(width 2.54)
			(type default)
		)
		(layer "In4.Cu")
	)
	(gr_line
		(start 273.45005 -360.000042)
		(end 275.75002 -360.000042)
		(stroke
			(width 2.54)
			(type default)
		)
		(layer "In4.Cu")
	)
	(gr_line
		(start 274.7264 -145.6436)
		(end 275.9202 -146.8374)
		(stroke
			(width 0.381)
			(type default)
		)
		(layer "In4.Cu")
	)
	(gr_line
		(start 274.7264 -130.7592)
		(end 274.7264 -145.6436)
		(stroke
			(width 0.381)
			(type default)
		)
		(layer "In4.Cu")
	)
	(gr_line
		(start 275.2344 -239.13973)
		(end 276.42947 -240.3348)
		(stroke
			(width 0.381)
			(type default)
		)
		(layer "In4.Cu")
	)
	(gr_line
		(start 275.2344 -175.4632)
		(end 275.2344 -239.13973)
		(stroke
			(width 0.381)
			(type default)
		)
		(layer "In4.Cu")
	)
	(gr_line
		(start 275.3868 -130.0988)
		(end 274.7264 -130.7592)
		(stroke
			(width 0.381)
			(type default)
		)
		(layer "In4.Cu")
	)
	(gr_line
		(start 275.9202 -146.8374)
		(end 289.4838 -146.8374)
		(stroke
			(width 0.381)
			(type default)
		)
		(layer "In4.Cu")
	)
	(gr_line
		(start 276.42947 -240.3348)
		(end 289.8648 -240.3348)
		(stroke
			(width 0.381)
			(type default)
		)
		(layer "In4.Cu")
	)
	(gr_line
		(start 276.5298 -174.1678)
		(end 275.2344 -175.4632)
		(stroke
			(width 0.381)
			(type default)
		)
		(layer "In4.Cu")
	)
	(gr_arc
		(start 276.750018 -382.585722)
		(mid 276.826138 -382.968405)
		(end 277.04288 -383.292858)
		(stroke
			(width 2.54)
			(type default)
		)
		(layer "In4.Cu")
	)
	(gr_arc
		(start 276.750018 -361.00004)
		(mid 276.457141 -360.292902)
		(end 275.75002 -360.000042)
		(stroke
			(width 2.54)
			(type default)
		)
		(layer "In4.Cu")
	)
	(gr_line
		(start 276.750018 -361.00004)
		(end 276.750018 -382.585722)
		(stroke
			(width 2.54)
			(type default)
		)
		(layer "In4.Cu")
	)
	(gr_line
		(start 277.04288 -383.292858)
		(end 279.45715 -385.707128)
		(stroke
			(width 2.54)
			(type default)
		)
		(layer "In4.Cu")
	)
	(gr_line
		(start 278.23668 -237.44301)
		(end 279.636728 -237.44301)
		(stroke
			(width 0.2)
			(type default)
		)
		(layer "In4.Cu")
	)
	(gr_arc
		(start 278.23668 -236.34573)
		(mid 277.68804 -236.89437)
		(end 278.23668 -237.44301)
		(stroke
			(width 0.2)
			(type default)
		)
		(layer "In4.Cu")
	)
	(gr_line
		(start 278.23668 -233.843068)
		(end 279.636728 -233.843068)
		(stroke
			(width 0.2)
			(type default)
		)
		(layer "In4.Cu")
	)
	(gr_arc
		(start 278.23668 -232.745788)
		(mid 277.68804 -233.294428)
		(end 278.23668 -233.843068)
		(stroke
			(width 0.2)
			(type default)
		)
		(layer "In4.Cu")
	)
	(gr_line
		(start 278.23668 -230.243126)
		(end 279.636728 -230.243126)
		(stroke
			(width 0.2)
			(type default)
		)
		(layer "In4.Cu")
	)
	(gr_arc
		(start 278.23668 -229.145846)
		(mid 277.68804 -229.694486)
		(end 278.23668 -230.243126)
		(stroke
			(width 0.2)
			(type default)
		)
		(layer "In4.Cu")
	)
	(gr_line
		(start 278.23668 -226.643184)
		(end 279.636728 -226.643184)
		(stroke
			(width 0.2)
			(type default)
		)
		(layer "In4.Cu")
	)
	(gr_arc
		(start 278.23668 -225.545904)
		(mid 277.68804 -226.094544)
		(end 278.23668 -226.643184)
		(stroke
			(width 0.2)
			(type default)
		)
		(layer "In4.Cu")
	)
	(gr_line
		(start 278.23668 -223.042988)
		(end 279.636728 -223.042988)
		(stroke
			(width 0.2)
			(type default)
		)
		(layer "In4.Cu")
	)
	(gr_arc
		(start 278.23668 -221.945708)
		(mid 277.68804 -222.494348)
		(end 278.23668 -223.042988)
		(stroke
			(width 0.2)
			(type default)
		)
		(layer "In4.Cu")
	)
	(gr_line
		(start 278.23668 -219.443046)
		(end 279.636728 -219.443046)
		(stroke
			(width 0.2)
			(type default)
		)
		(layer "In4.Cu")
	)
	(gr_arc
		(start 278.23668 -218.345766)
		(mid 277.68804 -218.894406)
		(end 278.23668 -219.443046)
		(stroke
			(width 0.2)
			(type default)
		)
		(layer "In4.Cu")
	)
	(gr_line
		(start 278.23668 -215.843104)
		(end 279.636728 -215.843104)
		(stroke
			(width 0.2)
			(type default)
		)
		(layer "In4.Cu")
	)
	(gr_arc
		(start 278.23668 -214.745824)
		(mid 277.68804 -215.294464)
		(end 278.23668 -215.843104)
		(stroke
			(width 0.2)
			(type default)
		)
		(layer "In4.Cu")
	)
	(gr_line
		(start 278.23668 -212.243162)
		(end 279.636728 -212.243162)
		(stroke
			(width 0.2)
			(type default)
		)
		(layer "In4.Cu")
	)
	(gr_arc
		(start 278.23668 -211.145882)
		(mid 277.68804 -211.694522)
		(end 278.23668 -212.243162)
		(stroke
			(width 0.2)
			(type default)
		)
		(layer "In4.Cu")
	)
	(gr_line
		(start 278.23668 -208.64322)
		(end 279.636728 -208.64322)
		(stroke
			(width 0.2)
			(type default)
		)
		(layer "In4.Cu")
	)
	(gr_arc
		(start 278.23668 -207.54594)
		(mid 277.68804 -208.09458)
		(end 278.23668 -208.64322)
		(stroke
			(width 0.2)
			(type default)
		)
		(layer "In4.Cu")
	)
	(gr_line
		(start 278.23668 -205.043024)
		(end 279.636728 -205.043024)
		(stroke
			(width 0.2)
			(type default)
		)
		(layer "In4.Cu")
	)
	(gr_arc
		(start 278.23668 -203.945744)
		(mid 277.68804 -204.494384)
		(end 278.23668 -205.043024)
		(stroke
			(width 0.2)
			(type default)
		)
		(layer "In4.Cu")
	)
	(gr_line
		(start 278.23668 -201.443082)
		(end 279.636728 -201.443082)
		(stroke
			(width 0.2)
			(type default)
		)
		(layer "In4.Cu")
	)
	(gr_arc
		(start 278.23668 -200.345802)
		(mid 277.68804 -200.894442)
		(end 278.23668 -201.443082)
		(stroke
			(width 0.2)
			(type default)
		)
		(layer "In4.Cu")
	)
	(gr_line
		(start 278.23668 -197.84314)
		(end 279.636728 -197.84314)
		(stroke
			(width 0.2)
			(type default)
		)
		(layer "In4.Cu")
	)
	(gr_arc
		(start 278.23668 -196.74586)
		(mid 277.68804 -197.2945)
		(end 278.23668 -197.84314)
		(stroke
			(width 0.2)
			(type default)
		)
		(layer "In4.Cu")
	)
	(gr_line
		(start 278.23668 -194.243198)
		(end 279.636728 -194.243198)
		(stroke
			(width 0.2)
			(type default)
		)
		(layer "In4.Cu")
	)
	(gr_arc
		(start 278.23668 -193.145918)
		(mid 277.68804 -193.694558)
		(end 278.23668 -194.243198)
		(stroke
			(width 0.2)
			(type default)
		)
		(layer "In4.Cu")
	)
	(gr_line
		(start 278.23668 -190.643002)
		(end 279.636728 -190.643002)
		(stroke
			(width 0.2)
			(type default)
		)
		(layer "In4.Cu")
	)
	(gr_arc
		(start 278.23668 -189.545722)
		(mid 277.68804 -190.094362)
		(end 278.23668 -190.643002)
		(stroke
			(width 0.2)
			(type default)
		)
		(layer "In4.Cu")
	)
	(gr_line
		(start 278.23668 -187.04306)
		(end 279.636728 -187.04306)
		(stroke
			(width 0.2)
			(type default)
		)
		(layer "In4.Cu")
	)
	(gr_arc
		(start 278.23668 -185.94578)
		(mid 277.68804 -186.49442)
		(end 278.23668 -187.04306)
		(stroke
			(width 0.2)
			(type default)
		)
		(layer "In4.Cu")
	)
	(gr_line
		(start 278.23668 -183.443118)
		(end 279.636728 -183.443118)
		(stroke
			(width 0.2)
			(type default)
		)
		(layer "In4.Cu")
	)
	(gr_arc
		(start 278.23668 -182.345838)
		(mid 277.68804 -182.894478)
		(end 278.23668 -183.443118)
		(stroke
			(width 0.2)
			(type default)
		)
		(layer "In4.Cu")
	)
	(gr_line
		(start 278.23668 -179.843176)
		(end 279.636728 -179.843176)
		(stroke
			(width 0.2)
			(type default)
		)
		(layer "In4.Cu")
	)
	(gr_arc
		(start 278.23668 -178.745896)
		(mid 277.68804 -179.294536)
		(end 278.23668 -179.843176)
		(stroke
			(width 0.2)
			(type default)
		)
		(layer "In4.Cu")
	)
	(gr_line
		(start 278.23668 -176.243234)
		(end 279.636728 -176.243234)
		(stroke
			(width 0.2)
			(type default)
		)
		(layer "In4.Cu")
	)
	(gr_arc
		(start 278.23668 -175.145954)
		(mid 277.68804 -175.694594)
		(end 278.23668 -176.243234)
		(stroke
			(width 0.2)
			(type default)
		)
		(layer "In4.Cu")
	)
	(gr_line
		(start 278.23668 -143.442944)
		(end 279.636728 -143.442944)
		(stroke
			(width 0.2)
			(type default)
		)
		(layer "In4.Cu")
	)
	(gr_arc
		(start 278.23668 -142.345664)
		(mid 277.68804 -142.894304)
		(end 278.23668 -143.442944)
		(stroke
			(width 0.2)
			(type default)
		)
		(layer "In4.Cu")
	)
	(gr_line
		(start 278.23668 -139.843002)
		(end 279.636728 -139.843002)
		(stroke
			(width 0.2)
			(type default)
		)
		(layer "In4.Cu")
	)
	(gr_arc
		(start 278.23668 -138.745722)
		(mid 277.68804 -139.294362)
		(end 278.23668 -139.843002)
		(stroke
			(width 0.2)
			(type default)
		)
		(layer "In4.Cu")
	)
	(gr_line
		(start 278.23668 -136.24306)
		(end 279.636728 -136.24306)
		(stroke
			(width 0.2)
			(type default)
		)
		(layer "In4.Cu")
	)
	(gr_arc
		(start 278.23668 -135.14578)
		(mid 277.68804 -135.69442)
		(end 278.23668 -136.24306)
		(stroke
			(width 0.2)
			(type default)
		)
		(layer "In4.Cu")
	)
	(gr_line
		(start 278.23668 -132.643118)
		(end 279.636728 -132.643118)
		(stroke
			(width 0.2)
			(type default)
		)
		(layer "In4.Cu")
	)
	(gr_arc
		(start 278.23668 -131.545838)
		(mid 277.68804 -132.094478)
		(end 278.23668 -132.643118)
		(stroke
			(width 0.2)
			(type default)
		)
		(layer "In4.Cu")
	)
	(gr_line
		(start 279.236678 -239.243108)
		(end 280.636726 -239.243108)
		(stroke
			(width 0.2)
			(type default)
		)
		(layer "In4.Cu")
	)
	(gr_arc
		(start 279.236678 -238.145828)
		(mid 278.688038 -238.694468)
		(end 279.236678 -239.243108)
		(stroke
			(width 0.2)
			(type default)
		)
		(layer "In4.Cu")
	)
	(gr_line
		(start 279.236678 -235.643166)
		(end 280.636726 -235.643166)
		(stroke
			(width 0.2)
			(type default)
		)
		(layer "In4.Cu")
	)
	(gr_arc
		(start 279.236678 -234.545886)
		(mid 278.688038 -235.094526)
		(end 279.236678 -235.643166)
		(stroke
			(width 0.2)
			(type default)
		)
		(layer "In4.Cu")
	)
	(gr_line
		(start 279.236678 -232.043224)
		(end 280.636726 -232.043224)
		(stroke
			(width 0.2)
			(type default)
		)
		(layer "In4.Cu")
	)
	(gr_arc
		(start 279.236678 -230.945944)
		(mid 278.688038 -231.494584)
		(end 279.236678 -232.043224)
		(stroke
			(width 0.2)
			(type default)
		)
		(layer "In4.Cu")
	)
	(gr_line
		(start 279.236678 -228.443028)
		(end 280.636726 -228.443028)
		(stroke
			(width 0.2)
			(type default)
		)
		(layer "In4.Cu")
	)
	(gr_arc
		(start 279.236678 -227.345748)
		(mid 278.688038 -227.894388)
		(end 279.236678 -228.443028)
		(stroke
			(width 0.2)
			(type default)
		)
		(layer "In4.Cu")
	)
	(gr_line
		(start 279.236678 -224.843086)
		(end 280.636726 -224.843086)
		(stroke
			(width 0.2)
			(type default)
		)
		(layer "In4.Cu")
	)
	(gr_arc
		(start 279.236678 -223.745806)
		(mid 278.688038 -224.294446)
		(end 279.236678 -224.843086)
		(stroke
			(width 0.2)
			(type default)
		)
		(layer "In4.Cu")
	)
	(gr_line
		(start 279.236678 -221.243144)
		(end 280.636726 -221.243144)
		(stroke
			(width 0.2)
			(type default)
		)
		(layer "In4.Cu")
	)
	(gr_arc
		(start 279.236678 -220.145864)
		(mid 278.688038 -220.694504)
		(end 279.236678 -221.243144)
		(stroke
			(width 0.2)
			(type default)
		)
		(layer "In4.Cu")
	)
	(gr_line
		(start 279.236678 -217.643202)
		(end 280.636726 -217.643202)
		(stroke
			(width 0.2)
			(type default)
		)
		(layer "In4.Cu")
	)
	(gr_arc
		(start 279.236678 -216.545922)
		(mid 278.688038 -217.094562)
		(end 279.236678 -217.643202)
		(stroke
			(width 0.2)
			(type default)
		)
		(layer "In4.Cu")
	)
	(gr_line
		(start 279.236678 -214.043006)
		(end 280.636726 -214.043006)
		(stroke
			(width 0.2)
			(type default)
		)
		(layer "In4.Cu")
	)
	(gr_arc
		(start 279.236678 -212.945726)
		(mid 278.688038 -213.494366)
		(end 279.236678 -214.043006)
		(stroke
			(width 0.2)
			(type default)
		)
		(layer "In4.Cu")
	)
	(gr_line
		(start 279.236678 -210.443064)
		(end 280.636726 -210.443064)
		(stroke
			(width 0.2)
			(type default)
		)
		(layer "In4.Cu")
	)
	(gr_arc
		(start 279.236678 -209.345784)
		(mid 278.688038 -209.894424)
		(end 279.236678 -210.443064)
		(stroke
			(width 0.2)
			(type default)
		)
		(layer "In4.Cu")
	)
	(gr_line
		(start 279.236678 -206.843122)
		(end 280.636726 -206.843122)
		(stroke
			(width 0.2)
			(type default)
		)
		(layer "In4.Cu")
	)
	(gr_arc
		(start 279.236678 -205.745842)
		(mid 278.688038 -206.294482)
		(end 279.236678 -206.843122)
		(stroke
			(width 0.2)
			(type default)
		)
		(layer "In4.Cu")
	)
	(gr_line
		(start 279.236678 -203.24318)
		(end 280.636726 -203.24318)
		(stroke
			(width 0.2)
			(type default)
		)
		(layer "In4.Cu")
	)
	(gr_arc
		(start 279.236678 -202.1459)
		(mid 278.688038 -202.69454)
		(end 279.236678 -203.24318)
		(stroke
			(width 0.2)
			(type default)
		)
		(layer "In4.Cu")
	)
	(gr_line
		(start 279.236678 -199.642984)
		(end 280.636726 -199.642984)
		(stroke
			(width 0.2)
			(type default)
		)
		(layer "In4.Cu")
	)
	(gr_arc
		(start 279.236678 -198.545704)
		(mid 278.688038 -199.094344)
		(end 279.236678 -199.642984)
		(stroke
			(width 0.2)
			(type default)
		)
		(layer "In4.Cu")
	)
	(gr_line
		(start 279.236678 -196.043042)
		(end 280.636726 -196.043042)
		(stroke
			(width 0.2)
			(type default)
		)
		(layer "In4.Cu")
	)
	(gr_arc
		(start 279.236678 -194.945762)
		(mid 278.688038 -195.494402)
		(end 279.236678 -196.043042)
		(stroke
			(width 0.2)
			(type default)
		)
		(layer "In4.Cu")
	)
	(gr_line
		(start 279.236678 -192.4431)
		(end 280.636726 -192.4431)
		(stroke
			(width 0.2)
			(type default)
		)
		(layer "In4.Cu")
	)
	(gr_arc
		(start 279.236678 -191.34582)
		(mid 278.688038 -191.89446)
		(end 279.236678 -192.4431)
		(stroke
			(width 0.2)
			(type default)
		)
		(layer "In4.Cu")
	)
	(gr_line
		(start 279.236678 -188.843158)
		(end 280.636726 -188.843158)
		(stroke
			(width 0.2)
			(type default)
		)
		(layer "In4.Cu")
	)
	(gr_arc
		(start 279.236678 -187.745878)
		(mid 278.688038 -188.294518)
		(end 279.236678 -188.843158)
		(stroke
			(width 0.2)
			(type default)
		)
		(layer "In4.Cu")
	)
	(gr_line
		(start 279.236678 -185.243216)
		(end 280.636726 -185.243216)
		(stroke
			(width 0.2)
			(type default)
		)
		(layer "In4.Cu")
	)
	(gr_arc
		(start 279.236678 -184.145936)
		(mid 278.688038 -184.694576)
		(end 279.236678 -185.243216)
		(stroke
			(width 0.2)
			(type default)
		)
		(layer "In4.Cu")
	)
	(gr_line
		(start 279.236678 -181.64302)
		(end 280.636726 -181.64302)
		(stroke
			(width 0.2)
			(type default)
		)
		(layer "In4.Cu")
	)
	(gr_arc
		(start 279.236678 -180.54574)
		(mid 278.688038 -181.09438)
		(end 279.236678 -181.64302)
		(stroke
			(width 0.2)
			(type default)
		)
		(layer "In4.Cu")
	)
	(gr_line
		(start 279.236678 -178.043078)
		(end 280.636726 -178.043078)
		(stroke
			(width 0.2)
			(type default)
		)
		(layer "In4.Cu")
	)
	(gr_arc
		(start 279.236678 -176.945798)
		(mid 278.688038 -177.494438)
		(end 279.236678 -178.043078)
		(stroke
			(width 0.2)
			(type default)
		)
		(layer "In4.Cu")
	)
	(gr_line
		(start 279.236678 -145.243042)
		(end 280.636726 -145.243042)
		(stroke
			(width 0.2)
			(type default)
		)
		(layer "In4.Cu")
	)
	(gr_arc
		(start 279.236678 -144.145762)
		(mid 278.688038 -144.694402)
		(end 279.236678 -145.243042)
		(stroke
			(width 0.2)
			(type default)
		)
		(layer "In4.Cu")
	)
	(gr_line
		(start 279.236678 -141.6431)
		(end 280.636726 -141.6431)
		(stroke
			(width 0.2)
			(type default)
		)
		(layer "In4.Cu")
	)
	(gr_arc
		(start 279.236678 -140.54582)
		(mid 278.688038 -141.09446)
		(end 279.236678 -141.6431)
		(stroke
			(width 0.2)
			(type default)
		)
		(layer "In4.Cu")
	)
	(gr_line
		(start 279.236678 -138.045698)
		(end 280.636726 -138.045698)
		(stroke
			(width 0.2)
			(type default)
		)
		(layer "In4.Cu")
	)
	(gr_arc
		(start 279.236678 -136.943338)
		(mid 278.685498 -137.494518)
		(end 279.236678 -138.045698)
		(stroke
			(width 0.2)
			(type default)
		)
		(layer "In4.Cu")
	)
	(gr_line
		(start 279.236678 -134.442962)
		(end 280.636726 -134.442962)
		(stroke
			(width 0.2)
			(type default)
		)
		(layer "In4.Cu")
	)
	(gr_arc
		(start 279.236678 -133.345682)
		(mid 278.688038 -133.894322)
		(end 279.236678 -134.442962)
		(stroke
			(width 0.2)
			(type default)
		)
		(layer "In4.Cu")
	)
	(gr_line
		(start 279.236932 -136.943338)
		(end 279.236678 -136.943338)
		(stroke
			(width 0.2)
			(type default)
		)
		(layer "In4.Cu")
	)
	(gr_arc
		(start 279.45715 -385.707128)
		(mid 279.781587 -385.92391)
		(end 280.164286 -385.99999)
		(stroke
			(width 2.54)
			(type default)
		)
		(layer "In4.Cu")
	)
	(gr_arc
		(start 279.636728 -237.44301)
		(mid 280.185368 -236.89437)
		(end 279.636728 -236.34573)
		(stroke
			(width 0.2)
			(type default)
		)
		(layer "In4.Cu")
	)
	(gr_line
		(start 279.636728 -236.34573)
		(end 278.23668 -236.34573)
		(stroke
			(width 0.2)
			(type default)
		)
		(layer "In4.Cu")
	)
	(gr_arc
		(start 279.636728 -233.843068)
		(mid 280.185368 -233.294428)
		(end 279.636728 -232.745788)
		(stroke
			(width 0.2)
			(type default)
		)
		(layer "In4.Cu")
	)
	(gr_line
		(start 279.636728 -232.745788)
		(end 278.23668 -232.745788)
		(stroke
			(width 0.2)
			(type default)
		)
		(layer "In4.Cu")
	)
	(gr_arc
		(start 279.636728 -230.243126)
		(mid 280.185368 -229.694486)
		(end 279.636728 -229.145846)
		(stroke
			(width 0.2)
			(type default)
		)
		(layer "In4.Cu")
	)
	(gr_line
		(start 279.636728 -229.145846)
		(end 278.23668 -229.145846)
		(stroke
			(width 0.2)
			(type default)
		)
		(layer "In4.Cu")
	)
	(gr_arc
		(start 279.636728 -226.643184)
		(mid 280.185368 -226.094544)
		(end 279.636728 -225.545904)
		(stroke
			(width 0.2)
			(type default)
		)
		(layer "In4.Cu")
	)
	(gr_line
		(start 279.636728 -225.545904)
		(end 278.23668 -225.545904)
		(stroke
			(width 0.2)
			(type default)
		)
		(layer "In4.Cu")
	)
	(gr_arc
		(start 279.636728 -223.042988)
		(mid 280.185368 -222.494348)
		(end 279.636728 -221.945708)
		(stroke
			(width 0.2)
			(type default)
		)
		(layer "In4.Cu")
	)
	(gr_line
		(start 279.636728 -221.945708)
		(end 278.23668 -221.945708)
		(stroke
			(width 0.2)
			(type default)
		)
		(layer "In4.Cu")
	)
	(gr_arc
		(start 279.636728 -219.443046)
		(mid 280.185368 -218.894406)
		(end 279.636728 -218.345766)
		(stroke
			(width 0.2)
			(type default)
		)
		(layer "In4.Cu")
	)
	(gr_line
		(start 279.636728 -218.345766)
		(end 278.23668 -218.345766)
		(stroke
			(width 0.2)
			(type default)
		)
		(layer "In4.Cu")
	)
	(gr_arc
		(start 279.636728 -215.843104)
		(mid 280.185368 -215.294464)
		(end 279.636728 -214.745824)
		(stroke
			(width 0.2)
			(type default)
		)
		(layer "In4.Cu")
	)
	(gr_line
		(start 279.636728 -214.745824)
		(end 278.23668 -214.745824)
		(stroke
			(width 0.2)
			(type default)
		)
		(layer "In4.Cu")
	)
	(gr_arc
		(start 279.636728 -212.243162)
		(mid 280.185368 -211.694522)
		(end 279.636728 -211.145882)
		(stroke
			(width 0.2)
			(type default)
		)
		(layer "In4.Cu")
	)
	(gr_line
		(start 279.636728 -211.145882)
		(end 278.23668 -211.145882)
		(stroke
			(width 0.2)
			(type default)
		)
		(layer "In4.Cu")
	)
	(gr_arc
		(start 279.636728 -208.64322)
		(mid 280.185368 -208.09458)
		(end 279.636728 -207.54594)
		(stroke
			(width 0.2)
			(type default)
		)
		(layer "In4.Cu")
	)
	(gr_line
		(start 279.636728 -207.54594)
		(end 278.23668 -207.54594)
		(stroke
			(width 0.2)
			(type default)
		)
		(layer "In4.Cu")
	)
	(gr_arc
		(start 279.636728 -205.043024)
		(mid 280.185368 -204.494384)
		(end 279.636728 -203.945744)
		(stroke
			(width 0.2)
			(type default)
		)
		(layer "In4.Cu")
	)
	(gr_line
		(start 279.636728 -203.945744)
		(end 278.23668 -203.945744)
		(stroke
			(width 0.2)
			(type default)
		)
		(layer "In4.Cu")
	)
	(gr_arc
		(start 279.636728 -201.443082)
		(mid 280.185368 -200.894442)
		(end 279.636728 -200.345802)
		(stroke
			(width 0.2)
			(type default)
		)
		(layer "In4.Cu")
	)
	(gr_line
		(start 279.636728 -200.345802)
		(end 278.23668 -200.345802)
		(stroke
			(width 0.2)
			(type default)
		)
		(layer "In4.Cu")
	)
	(gr_arc
		(start 279.636728 -197.84314)
		(mid 280.185368 -197.2945)
		(end 279.636728 -196.74586)
		(stroke
			(width 0.2)
			(type default)
		)
		(layer "In4.Cu")
	)
	(gr_line
		(start 279.636728 -196.74586)
		(end 278.23668 -196.74586)
		(stroke
			(width 0.2)
			(type default)
		)
		(layer "In4.Cu")
	)
	(gr_arc
		(start 279.636728 -194.243198)
		(mid 280.185368 -193.694558)
		(end 279.636728 -193.145918)
		(stroke
			(width 0.2)
			(type default)
		)
		(layer "In4.Cu")
	)
	(gr_line
		(start 279.636728 -193.145918)
		(end 278.23668 -193.145918)
		(stroke
			(width 0.2)
			(type default)
		)
		(layer "In4.Cu")
	)
	(gr_arc
		(start 279.636728 -190.643002)
		(mid 280.185368 -190.094362)
		(end 279.636728 -189.545722)
		(stroke
			(width 0.2)
			(type default)
		)
		(layer "In4.Cu")
	)
	(gr_line
		(start 279.636728 -189.545722)
		(end 278.23668 -189.545722)
		(stroke
			(width 0.2)
			(type default)
		)
		(layer "In4.Cu")
	)
	(gr_arc
		(start 279.636728 -187.04306)
		(mid 280.185368 -186.49442)
		(end 279.636728 -185.94578)
		(stroke
			(width 0.2)
			(type default)
		)
		(layer "In4.Cu")
	)
	(gr_line
		(start 279.636728 -185.94578)
		(end 278.23668 -185.94578)
		(stroke
			(width 0.2)
			(type default)
		)
		(layer "In4.Cu")
	)
	(gr_arc
		(start 279.636728 -183.443118)
		(mid 280.185368 -182.894478)
		(end 279.636728 -182.345838)
		(stroke
			(width 0.2)
			(type default)
		)
		(layer "In4.Cu")
	)
	(gr_line
		(start 279.636728 -182.345838)
		(end 278.23668 -182.345838)
		(stroke
			(width 0.2)
			(type default)
		)
		(layer "In4.Cu")
	)
	(gr_arc
		(start 279.636728 -179.843176)
		(mid 280.185368 -179.294536)
		(end 279.636728 -178.745896)
		(stroke
			(width 0.2)
			(type default)
		)
		(layer "In4.Cu")
	)
	(gr_line
		(start 279.636728 -178.745896)
		(end 278.23668 -178.745896)
		(stroke
			(width 0.2)
			(type default)
		)
		(layer "In4.Cu")
	)
	(gr_arc
		(start 279.636728 -176.243234)
		(mid 280.185368 -175.694594)
		(end 279.636728 -175.145954)
		(stroke
			(width 0.2)
			(type default)
		)
		(layer "In4.Cu")
	)
	(gr_line
		(start 279.636728 -175.145954)
		(end 278.23668 -175.145954)
		(stroke
			(width 0.2)
			(type default)
		)
		(layer "In4.Cu")
	)
	(gr_arc
		(start 279.636728 -143.442944)
		(mid 280.185368 -142.894304)
		(end 279.636728 -142.345664)
		(stroke
			(width 0.2)
			(type default)
		)
		(layer "In4.Cu")
	)
	(gr_line
		(start 279.636728 -142.345664)
		(end 278.23668 -142.345664)
		(stroke
			(width 0.2)
			(type default)
		)
		(layer "In4.Cu")
	)
	(gr_arc
		(start 279.636728 -139.843002)
		(mid 280.185368 -139.294362)
		(end 279.636728 -138.745722)
		(stroke
			(width 0.2)
			(type default)
		)
		(layer "In4.Cu")
	)
	(gr_line
		(start 279.636728 -138.745722)
		(end 278.23668 -138.745722)
		(stroke
			(width 0.2)
			(type default)
		)
		(layer "In4.Cu")
	)
	(gr_arc
		(start 279.636728 -136.24306)
		(mid 280.185368 -135.69442)
		(end 279.636728 -135.14578)
		(stroke
			(width 0.2)
			(type default)
		)
		(layer "In4.Cu")
	)
	(gr_line
		(start 279.636728 -135.14578)
		(end 278.23668 -135.14578)
		(stroke
			(width 0.2)
			(type default)
		)
		(layer "In4.Cu")
	)
	(gr_arc
		(start 279.636728 -132.643118)
		(mid 280.185368 -132.094478)
		(end 279.636728 -131.545838)
		(stroke
			(width 0.2)
			(type default)
		)
		(layer "In4.Cu")
	)
	(gr_line
		(start 279.636728 -131.545838)
		(end 278.23668 -131.545838)
		(stroke
			(width 0.2)
			(type default)
		)
		(layer "In4.Cu")
	)
	(gr_line
		(start 280.164286 -385.99999)
		(end 306.649882 -385.99999)
		(stroke
			(width 2.54)
			(type default)
		)
		(layer "In4.Cu")
	)
	(gr_arc
		(start 280.636726 -239.243108)
		(mid 281.185366 -238.694468)
		(end 280.636726 -238.145828)
		(stroke
			(width 0.2)
			(type default)
		)
		(layer "In4.Cu")
	)
	(gr_line
		(start 280.636726 -238.145828)
		(end 279.236678 -238.145828)
		(stroke
			(width 0.2)
			(type default)
		)
		(layer "In4.Cu")
	)
	(gr_arc
		(start 280.636726 -235.643166)
		(mid 281.185366 -235.094526)
		(end 280.636726 -234.545886)
		(stroke
			(width 0.2)
			(type default)
		)
		(layer "In4.Cu")
	)
	(gr_line
		(start 280.636726 -234.545886)
		(end 279.236678 -234.545886)
		(stroke
			(width 0.2)
			(type default)
		)
		(layer "In4.Cu")
	)
	(gr_arc
		(start 280.636726 -232.043224)
		(mid 281.185366 -231.494584)
		(end 280.636726 -230.945944)
		(stroke
			(width 0.2)
			(type default)
		)
		(layer "In4.Cu")
	)
	(gr_line
		(start 280.636726 -230.945944)
		(end 279.236678 -230.945944)
		(stroke
			(width 0.2)
			(type default)
		)
		(layer "In4.Cu")
	)
	(gr_arc
		(start 280.636726 -228.443028)
		(mid 281.185366 -227.894388)
		(end 280.636726 -227.345748)
		(stroke
			(width 0.2)
			(type default)
		)
		(layer "In4.Cu")
	)
	(gr_line
		(start 280.636726 -227.345748)
		(end 279.236678 -227.345748)
		(stroke
			(width 0.2)
			(type default)
		)
		(layer "In4.Cu")
	)
	(gr_arc
		(start 280.636726 -224.843086)
		(mid 281.185366 -224.294446)
		(end 280.636726 -223.745806)
		(stroke
			(width 0.2)
			(type default)
		)
		(layer "In4.Cu")
	)
	(gr_line
		(start 280.636726 -223.745806)
		(end 279.236678 -223.745806)
		(stroke
			(width 0.2)
			(type default)
		)
		(layer "In4.Cu")
	)
	(gr_arc
		(start 280.636726 -221.243144)
		(mid 281.185366 -220.694504)
		(end 280.636726 -220.145864)
		(stroke
			(width 0.2)
			(type default)
		)
		(layer "In4.Cu")
	)
	(gr_line
		(start 280.636726 -220.145864)
		(end 279.236678 -220.145864)
		(stroke
			(width 0.2)
			(type default)
		)
		(layer "In4.Cu")
	)
	(gr_arc
		(start 280.636726 -217.643202)
		(mid 281.185366 -217.094562)
		(end 280.636726 -216.545922)
		(stroke
			(width 0.2)
			(type default)
		)
		(layer "In4.Cu")
	)
	(gr_line
		(start 280.636726 -216.545922)
		(end 279.236678 -216.545922)
		(stroke
			(width 0.2)
			(type default)
		)
		(layer "In4.Cu")
	)
	(gr_arc
		(start 280.636726 -214.043006)
		(mid 281.185366 -213.494366)
		(end 280.636726 -212.945726)
		(stroke
			(width 0.2)
			(type default)
		)
		(layer "In4.Cu")
	)
	(gr_line
		(start 280.636726 -212.945726)
		(end 279.236678 -212.945726)
		(stroke
			(width 0.2)
			(type default)
		)
		(layer "In4.Cu")
	)
	(gr_arc
		(start 280.636726 -210.443064)
		(mid 281.185366 -209.894424)
		(end 280.636726 -209.345784)
		(stroke
			(width 0.2)
			(type default)
		)
		(layer "In4.Cu")
	)
	(gr_line
		(start 280.636726 -209.345784)
		(end 279.236678 -209.345784)
		(stroke
			(width 0.2)
			(type default)
		)
		(layer "In4.Cu")
	)
	(gr_arc
		(start 280.636726 -206.843122)
		(mid 281.185366 -206.294482)
		(end 280.636726 -205.745842)
		(stroke
			(width 0.2)
			(type default)
		)
		(layer "In4.Cu")
	)
	(gr_line
		(start 280.636726 -205.745842)
		(end 279.236678 -205.745842)
		(stroke
			(width 0.2)
			(type default)
		)
		(layer "In4.Cu")
	)
	(gr_arc
		(start 280.636726 -203.24318)
		(mid 281.185366 -202.69454)
		(end 280.636726 -202.1459)
		(stroke
			(width 0.2)
			(type default)
		)
		(layer "In4.Cu")
	)
	(gr_line
		(start 280.636726 -202.1459)
		(end 279.236678 -202.1459)
		(stroke
			(width 0.2)
			(type default)
		)
		(layer "In4.Cu")
	)
	(gr_arc
		(start 280.636726 -199.642984)
		(mid 281.185366 -199.094344)
		(end 280.636726 -198.545704)
		(stroke
			(width 0.2)
			(type default)
		)
		(layer "In4.Cu")
	)
	(gr_line
		(start 280.636726 -198.545704)
		(end 279.236678 -198.545704)
		(stroke
			(width 0.2)
			(type default)
		)
		(layer "In4.Cu")
	)
	(gr_arc
		(start 280.636726 -196.043042)
		(mid 281.185366 -195.494402)
		(end 280.636726 -194.945762)
		(stroke
			(width 0.2)
			(type default)
		)
		(layer "In4.Cu")
	)
	(gr_line
		(start 280.636726 -194.945762)
		(end 279.236678 -194.945762)
		(stroke
			(width 0.2)
			(type default)
		)
		(layer "In4.Cu")
	)
	(gr_arc
		(start 280.636726 -192.4431)
		(mid 281.185366 -191.89446)
		(end 280.636726 -191.34582)
		(stroke
			(width 0.2)
			(type default)
		)
		(layer "In4.Cu")
	)
	(gr_line
		(start 280.636726 -191.34582)
		(end 279.236678 -191.34582)
		(stroke
			(width 0.2)
			(type default)
		)
		(layer "In4.Cu")
	)
	(gr_arc
		(start 280.636726 -188.843158)
		(mid 281.185366 -188.294518)
		(end 280.636726 -187.745878)
		(stroke
			(width 0.2)
			(type default)
		)
		(layer "In4.Cu")
	)
	(gr_line
		(start 280.636726 -187.745878)
		(end 279.236678 -187.745878)
		(stroke
			(width 0.2)
			(type default)
		)
		(layer "In4.Cu")
	)
	(gr_arc
		(start 280.636726 -185.243216)
		(mid 281.185366 -184.694576)
		(end 280.636726 -184.145936)
		(stroke
			(width 0.2)
			(type default)
		)
		(layer "In4.Cu")
	)
	(gr_line
		(start 280.636726 -184.145936)
		(end 279.236678 -184.145936)
		(stroke
			(width 0.2)
			(type default)
		)
		(layer "In4.Cu")
	)
	(gr_arc
		(start 280.636726 -181.64302)
		(mid 281.185366 -181.09438)
		(end 280.636726 -180.54574)
		(stroke
			(width 0.2)
			(type default)
		)
		(layer "In4.Cu")
	)
	(gr_line
		(start 280.636726 -180.54574)
		(end 279.236678 -180.54574)
		(stroke
			(width 0.2)
			(type default)
		)
		(layer "In4.Cu")
	)
	(gr_arc
		(start 280.636726 -178.043078)
		(mid 281.185366 -177.494438)
		(end 280.636726 -176.945798)
		(stroke
			(width 0.2)
			(type default)
		)
		(layer "In4.Cu")
	)
	(gr_line
		(start 280.636726 -176.945798)
		(end 279.236678 -176.945798)
		(stroke
			(width 0.2)
			(type default)
		)
		(layer "In4.Cu")
	)
	(gr_arc
		(start 280.636726 -145.243042)
		(mid 281.185366 -144.694402)
		(end 280.636726 -144.145762)
		(stroke
			(width 0.2)
			(type default)
		)
		(layer "In4.Cu")
	)
	(gr_line
		(start 280.636726 -144.145762)
		(end 279.236678 -144.145762)
		(stroke
			(width 0.2)
			(type default)
		)
		(layer "In4.Cu")
	)
	(gr_arc
		(start 280.636726 -141.6431)
		(mid 281.185366 -141.09446)
		(end 280.636726 -140.54582)
		(stroke
			(width 0.2)
			(type default)
		)
		(layer "In4.Cu")
	)
	(gr_line
		(start 280.636726 -140.54582)
		(end 279.236678 -140.54582)
		(stroke
			(width 0.2)
			(type default)
		)
		(layer "In4.Cu")
	)
	(gr_arc
		(start 280.636726 -138.045698)
		(mid 281.187906 -137.494518)
		(end 280.636726 -136.943338)
		(stroke
			(width 0.2)
			(type default)
		)
		(layer "In4.Cu")
	)
	(gr_line
		(start 280.636726 -136.943338)
		(end 279.236932 -136.943338)
		(stroke
			(width 0.2)
			(type default)
		)
		(layer "In4.Cu")
	)
	(gr_arc
		(start 280.636726 -134.442962)
		(mid 281.185366 -133.894322)
		(end 280.636726 -133.345682)
		(stroke
			(width 0.2)
			(type default)
		)
		(layer "In4.Cu")
	)
	(gr_line
		(start 280.636726 -133.345682)
		(end 279.236678 -133.345682)
		(stroke
			(width 0.2)
			(type default)
		)
		(layer "In4.Cu")
	)
	(gr_line
		(start 282.83662 -145.243042)
		(end 284.236668 -145.243042)
		(stroke
			(width 0.2)
			(type default)
		)
		(layer "In4.Cu")
	)
	(gr_arc
		(start 282.83662 -144.145762)
		(mid 282.28798 -144.694402)
		(end 282.83662 -145.243042)
		(stroke
			(width 0.2)
			(type default)
		)
		(layer "In4.Cu")
	)
	(gr_arc
		(start 284.236668 -145.243042)
		(mid 284.785308 -144.694402)
		(end 284.236668 -144.145762)
		(stroke
			(width 0.2)
			(type default)
		)
		(layer "In4.Cu")
	)
	(gr_line
		(start 284.236668 -144.145762)
		(end 282.83662 -144.145762)
		(stroke
			(width 0.2)
			(type default)
		)
		(layer "In4.Cu")
	)
	(gr_line
		(start 285.436564 -237.44301)
		(end 286.836612 -237.44301)
		(stroke
			(width 0.2)
			(type default)
		)
		(layer "In4.Cu")
	)
	(gr_arc
		(start 285.436564 -236.34573)
		(mid 284.887924 -236.89437)
		(end 285.436564 -237.44301)
		(stroke
			(width 0.2)
			(type default)
		)
		(layer "In4.Cu")
	)
	(gr_line
		(start 285.436564 -233.843068)
		(end 286.836612 -233.843068)
		(stroke
			(width 0.2)
			(type default)
		)
		(layer "In4.Cu")
	)
	(gr_arc
		(start 285.436564 -232.745788)
		(mid 284.887924 -233.294428)
		(end 285.436564 -233.843068)
		(stroke
			(width 0.2)
			(type default)
		)
		(layer "In4.Cu")
	)
	(gr_line
		(start 285.436564 -230.243126)
		(end 286.836612 -230.243126)
		(stroke
			(width 0.2)
			(type default)
		)
		(layer "In4.Cu")
	)
	(gr_arc
		(start 285.436564 -229.145846)
		(mid 284.887924 -229.694486)
		(end 285.436564 -230.243126)
		(stroke
			(width 0.2)
			(type default)
		)
		(layer "In4.Cu")
	)
	(gr_line
		(start 285.436564 -226.643184)
		(end 286.836612 -226.643184)
		(stroke
			(width 0.2)
			(type default)
		)
		(layer "In4.Cu")
	)
	(gr_arc
		(start 285.436564 -225.545904)
		(mid 284.887924 -226.094544)
		(end 285.436564 -226.643184)
		(stroke
			(width 0.2)
			(type default)
		)
		(layer "In4.Cu")
	)
	(gr_line
		(start 285.436564 -223.042988)
		(end 286.836612 -223.042988)
		(stroke
			(width 0.2)
			(type default)
		)
		(layer "In4.Cu")
	)
	(gr_arc
		(start 285.436564 -221.945708)
		(mid 284.887924 -222.494348)
		(end 285.436564 -223.042988)
		(stroke
			(width 0.2)
			(type default)
		)
		(layer "In4.Cu")
	)
	(gr_line
		(start 285.436564 -219.443046)
		(end 286.836612 -219.443046)
		(stroke
			(width 0.2)
			(type default)
		)
		(layer "In4.Cu")
	)
	(gr_arc
		(start 285.436564 -218.345766)
		(mid 284.887924 -218.894406)
		(end 285.436564 -219.443046)
		(stroke
			(width 0.2)
			(type default)
		)
		(layer "In4.Cu")
	)
	(gr_line
		(start 285.436564 -215.843104)
		(end 286.836612 -215.843104)
		(stroke
			(width 0.2)
			(type default)
		)
		(layer "In4.Cu")
	)
	(gr_arc
		(start 285.436564 -214.745824)
		(mid 284.887924 -215.294464)
		(end 285.436564 -215.843104)
		(stroke
			(width 0.2)
			(type default)
		)
		(layer "In4.Cu")
	)
	(gr_line
		(start 285.436564 -212.243162)
		(end 286.836612 -212.243162)
		(stroke
			(width 0.2)
			(type default)
		)
		(layer "In4.Cu")
	)
	(gr_arc
		(start 285.436564 -211.145882)
		(mid 284.887924 -211.694522)
		(end 285.436564 -212.243162)
		(stroke
			(width 0.2)
			(type default)
		)
		(layer "In4.Cu")
	)
	(gr_line
		(start 285.436564 -208.64322)
		(end 286.836612 -208.64322)
		(stroke
			(width 0.2)
			(type default)
		)
		(layer "In4.Cu")
	)
	(gr_arc
		(start 285.436564 -207.54594)
		(mid 284.887924 -208.09458)
		(end 285.436564 -208.64322)
		(stroke
			(width 0.2)
			(type default)
		)
		(layer "In4.Cu")
	)
	(gr_line
		(start 285.436564 -205.043024)
		(end 286.836612 -205.043024)
		(stroke
			(width 0.2)
			(type default)
		)
		(layer "In4.Cu")
	)
	(gr_arc
		(start 285.436564 -203.945744)
		(mid 284.887924 -204.494384)
		(end 285.436564 -205.043024)
		(stroke
			(width 0.2)
			(type default)
		)
		(layer "In4.Cu")
	)
	(gr_line
		(start 285.436564 -201.443082)
		(end 286.836612 -201.443082)
		(stroke
			(width 0.2)
			(type default)
		)
		(layer "In4.Cu")
	)
	(gr_arc
		(start 285.436564 -200.345802)
		(mid 284.887924 -200.894442)
		(end 285.436564 -201.443082)
		(stroke
			(width 0.2)
			(type default)
		)
		(layer "In4.Cu")
	)
	(gr_line
		(start 285.436564 -197.84314)
		(end 286.836612 -197.84314)
		(stroke
			(width 0.2)
			(type default)
		)
		(layer "In4.Cu")
	)
	(gr_arc
		(start 285.436564 -196.74586)
		(mid 284.887924 -197.2945)
		(end 285.436564 -197.84314)
		(stroke
			(width 0.2)
			(type default)
		)
		(layer "In4.Cu")
	)
	(gr_line
		(start 285.436564 -194.243198)
		(end 286.836612 -194.243198)
		(stroke
			(width 0.2)
			(type default)
		)
		(layer "In4.Cu")
	)
	(gr_arc
		(start 285.436564 -193.145918)
		(mid 284.887924 -193.694558)
		(end 285.436564 -194.243198)
		(stroke
			(width 0.2)
			(type default)
		)
		(layer "In4.Cu")
	)
	(gr_line
		(start 285.436564 -190.643002)
		(end 286.836612 -190.643002)
		(stroke
			(width 0.2)
			(type default)
		)
		(layer "In4.Cu")
	)
	(gr_arc
		(start 285.436564 -189.545722)
		(mid 284.887924 -190.094362)
		(end 285.436564 -190.643002)
		(stroke
			(width 0.2)
			(type default)
		)
		(layer "In4.Cu")
	)
	(gr_line
		(start 285.436564 -187.04306)
		(end 286.836612 -187.04306)
		(stroke
			(width 0.2)
			(type default)
		)
		(layer "In4.Cu")
	)
	(gr_arc
		(start 285.436564 -185.94578)
		(mid 284.887924 -186.49442)
		(end 285.436564 -187.04306)
		(stroke
			(width 0.2)
			(type default)
		)
		(layer "In4.Cu")
	)
	(gr_line
		(start 285.436564 -183.443118)
		(end 286.836612 -183.443118)
		(stroke
			(width 0.2)
			(type default)
		)
		(layer "In4.Cu")
	)
	(gr_arc
		(start 285.436564 -182.345838)
		(mid 284.887924 -182.894478)
		(end 285.436564 -183.443118)
		(stroke
			(width 0.2)
			(type default)
		)
		(layer "In4.Cu")
	)
	(gr_line
		(start 285.436564 -179.843176)
		(end 286.836612 -179.843176)
		(stroke
			(width 0.2)
			(type default)
		)
		(layer "In4.Cu")
	)
	(gr_arc
		(start 285.436564 -178.745896)
		(mid 284.887924 -179.294536)
		(end 285.436564 -179.843176)
		(stroke
			(width 0.2)
			(type default)
		)
		(layer "In4.Cu")
	)
	(gr_line
		(start 285.436564 -176.243234)
		(end 286.836612 -176.243234)
		(stroke
			(width 0.2)
			(type default)
		)
		(layer "In4.Cu")
	)
	(gr_arc
		(start 285.436564 -175.145954)
		(mid 284.887924 -175.694594)
		(end 285.436564 -176.243234)
		(stroke
			(width 0.2)
			(type default)
		)
		(layer "In4.Cu")
	)
	(gr_line
		(start 285.436564 -143.442944)
		(end 286.836612 -143.442944)
		(stroke
			(width 0.2)
			(type default)
		)
		(layer "In4.Cu")
	)
	(gr_arc
		(start 285.436564 -142.345664)
		(mid 284.887924 -142.894304)
		(end 285.436564 -143.442944)
		(stroke
			(width 0.2)
			(type default)
		)
		(layer "In4.Cu")
	)
	(gr_line
		(start 285.436564 -139.843002)
		(end 286.836612 -139.843002)
		(stroke
			(width 0.2)
			(type default)
		)
		(layer "In4.Cu")
	)
	(gr_arc
		(start 285.436564 -138.745722)
		(mid 284.887924 -139.294362)
		(end 285.436564 -139.843002)
		(stroke
			(width 0.2)
			(type default)
		)
		(layer "In4.Cu")
	)
	(gr_line
		(start 285.436564 -136.24306)
		(end 286.836612 -136.24306)
		(stroke
			(width 0.2)
			(type default)
		)
		(layer "In4.Cu")
	)
	(gr_arc
		(start 285.436564 -135.14578)
		(mid 284.887924 -135.69442)
		(end 285.436564 -136.24306)
		(stroke
			(width 0.2)
			(type default)
		)
		(layer "In4.Cu")
	)
	(gr_line
		(start 285.436564 -132.643118)
		(end 286.836612 -132.643118)
		(stroke
			(width 0.2)
			(type default)
		)
		(layer "In4.Cu")
	)
	(gr_arc
		(start 285.436564 -131.545838)
		(mid 284.887924 -132.094478)
		(end 285.436564 -132.643118)
		(stroke
			(width 0.2)
			(type default)
		)
		(layer "In4.Cu")
	)
	(gr_line
		(start 286.436562 -239.243108)
		(end 287.83661 -239.243108)
		(stroke
			(width 0.2)
			(type default)
		)
		(layer "In4.Cu")
	)
	(gr_arc
		(start 286.436562 -238.145828)
		(mid 285.887922 -238.694468)
		(end 286.436562 -239.243108)
		(stroke
			(width 0.2)
			(type default)
		)
		(layer "In4.Cu")
	)
	(gr_line
		(start 286.436562 -235.643166)
		(end 287.83661 -235.643166)
		(stroke
			(width 0.2)
			(type default)
		)
		(layer "In4.Cu")
	)
	(gr_arc
		(start 286.436562 -234.545886)
		(mid 285.887922 -235.094526)
		(end 286.436562 -235.643166)
		(stroke
			(width 0.2)
			(type default)
		)
		(layer "In4.Cu")
	)
	(gr_line
		(start 286.436562 -232.043224)
		(end 287.83661 -232.043224)
		(stroke
			(width 0.2)
			(type default)
		)
		(layer "In4.Cu")
	)
	(gr_arc
		(start 286.436562 -230.945944)
		(mid 285.887922 -231.494584)
		(end 286.436562 -232.043224)
		(stroke
			(width 0.2)
			(type default)
		)
		(layer "In4.Cu")
	)
	(gr_line
		(start 286.436562 -228.443028)
		(end 287.83661 -228.443028)
		(stroke
			(width 0.2)
			(type default)
		)
		(layer "In4.Cu")
	)
	(gr_arc
		(start 286.436562 -227.345748)
		(mid 285.887922 -227.894388)
		(end 286.436562 -228.443028)
		(stroke
			(width 0.2)
			(type default)
		)
		(layer "In4.Cu")
	)
	(gr_line
		(start 286.436562 -224.906586)
		(end 287.83661 -224.906586)
		(stroke
			(width 0.2)
			(type default)
		)
		(layer "In4.Cu")
	)
	(gr_arc
		(start 286.436562 -223.682306)
		(mid 285.824422 -224.294446)
		(end 286.436562 -224.906586)
		(stroke
			(width 0.2)
			(type default)
		)
		(layer "In4.Cu")
	)
	(gr_line
		(start 286.436562 -221.243144)
		(end 287.83661 -221.243144)
		(stroke
			(width 0.2)
			(type default)
		)
		(layer "In4.Cu")
	)
	(gr_arc
		(start 286.436562 -220.145864)
		(mid 285.887922 -220.694504)
		(end 286.436562 -221.243144)
		(stroke
			(width 0.2)
			(type default)
		)
		(layer "In4.Cu")
	)
	(gr_line
		(start 286.436562 -217.643202)
		(end 287.83661 -217.643202)
		(stroke
			(width 0.2)
			(type default)
		)
		(layer "In4.Cu")
	)
	(gr_arc
		(start 286.436562 -216.545922)
		(mid 285.887922 -217.094562)
		(end 286.436562 -217.643202)
		(stroke
			(width 0.2)
			(type default)
		)
		(layer "In4.Cu")
	)
	(gr_line
		(start 286.436562 -214.043006)
		(end 287.83661 -214.043006)
		(stroke
			(width 0.2)
			(type default)
		)
		(layer "In4.Cu")
	)
	(gr_arc
		(start 286.436562 -212.945726)
		(mid 285.887922 -213.494366)
		(end 286.436562 -214.043006)
		(stroke
			(width 0.2)
			(type default)
		)
		(layer "In4.Cu")
	)
	(gr_line
		(start 286.436562 -210.443064)
		(end 287.83661 -210.443064)
		(stroke
			(width 0.2)
			(type default)
		)
		(layer "In4.Cu")
	)
	(gr_arc
		(start 286.436562 -209.345784)
		(mid 285.887922 -209.894424)
		(end 286.436562 -210.443064)
		(stroke
			(width 0.2)
			(type default)
		)
		(layer "In4.Cu")
	)
	(gr_line
		(start 286.436562 -206.843122)
		(end 287.83661 -206.843122)
		(stroke
			(width 0.2)
			(type default)
		)
		(layer "In4.Cu")
	)
	(gr_arc
		(start 286.436562 -205.745842)
		(mid 285.887922 -206.294482)
		(end 286.436562 -206.843122)
		(stroke
			(width 0.2)
			(type default)
		)
		(layer "In4.Cu")
	)
	(gr_line
		(start 286.436562 -203.24318)
		(end 287.83661 -203.24318)
		(stroke
			(width 0.2)
			(type default)
		)
		(layer "In4.Cu")
	)
	(gr_arc
		(start 286.436562 -202.1459)
		(mid 285.887922 -202.69454)
		(end 286.436562 -203.24318)
		(stroke
			(width 0.2)
			(type default)
		)
		(layer "In4.Cu")
	)
	(gr_line
		(start 286.436562 -199.642984)
		(end 287.83661 -199.642984)
		(stroke
			(width 0.2)
			(type default)
		)
		(layer "In4.Cu")
	)
	(gr_arc
		(start 286.436562 -198.545704)
		(mid 285.887922 -199.094344)
		(end 286.436562 -199.642984)
		(stroke
			(width 0.2)
			(type default)
		)
		(layer "In4.Cu")
	)
	(gr_line
		(start 286.436562 -196.043042)
		(end 287.83661 -196.043042)
		(stroke
			(width 0.2)
			(type default)
		)
		(layer "In4.Cu")
	)
	(gr_arc
		(start 286.436562 -194.945762)
		(mid 285.887922 -195.494402)
		(end 286.436562 -196.043042)
		(stroke
			(width 0.2)
			(type default)
		)
		(layer "In4.Cu")
	)
	(gr_line
		(start 286.436562 -192.4431)
		(end 287.83661 -192.4431)
		(stroke
			(width 0.2)
			(type default)
		)
		(layer "In4.Cu")
	)
	(gr_arc
		(start 286.436562 -191.34582)
		(mid 285.887922 -191.89446)
		(end 286.436562 -192.4431)
		(stroke
			(width 0.2)
			(type default)
		)
		(layer "In4.Cu")
	)
	(gr_line
		(start 286.436562 -188.843158)
		(end 287.83661 -188.843158)
		(stroke
			(width 0.2)
			(type default)
		)
		(layer "In4.Cu")
	)
	(gr_arc
		(start 286.436562 -187.745878)
		(mid 285.887922 -188.294518)
		(end 286.436562 -188.843158)
		(stroke
			(width 0.2)
			(type default)
		)
		(layer "In4.Cu")
	)
	(gr_line
		(start 286.436562 -185.243216)
		(end 287.83661 -185.243216)
		(stroke
			(width 0.2)
			(type default)
		)
		(layer "In4.Cu")
	)
	(gr_arc
		(start 286.436562 -184.145936)
		(mid 285.887922 -184.694576)
		(end 286.436562 -185.243216)
		(stroke
			(width 0.2)
			(type default)
		)
		(layer "In4.Cu")
	)
	(gr_line
		(start 286.436562 -181.64302)
		(end 287.83661 -181.64302)
		(stroke
			(width 0.2)
			(type default)
		)
		(layer "In4.Cu")
	)
	(gr_arc
		(start 286.436562 -180.54574)
		(mid 285.887922 -181.09438)
		(end 286.436562 -181.64302)
		(stroke
			(width 0.2)
			(type default)
		)
		(layer "In4.Cu")
	)
	(gr_line
		(start 286.436562 -178.043078)
		(end 287.83661 -178.043078)
		(stroke
			(width 0.2)
			(type default)
		)
		(layer "In4.Cu")
	)
	(gr_arc
		(start 286.436562 -176.945798)
		(mid 285.887922 -177.494438)
		(end 286.436562 -178.043078)
		(stroke
			(width 0.2)
			(type default)
		)
		(layer "In4.Cu")
	)
	(gr_line
		(start 286.436562 -145.243042)
		(end 287.83661 -145.243042)
		(stroke
			(width 0.2)
			(type default)
		)
		(layer "In4.Cu")
	)
	(gr_arc
		(start 286.436562 -144.145762)
		(mid 285.887922 -144.694402)
		(end 286.436562 -145.243042)
		(stroke
			(width 0.2)
			(type default)
		)
		(layer "In4.Cu")
	)
	(gr_line
		(start 286.436562 -141.6431)
		(end 287.83661 -141.6431)
		(stroke
			(width 0.2)
			(type default)
		)
		(layer "In4.Cu")
	)
	(gr_arc
		(start 286.436562 -140.54582)
		(mid 285.887922 -141.09446)
		(end 286.436562 -141.6431)
		(stroke
			(width 0.2)
			(type default)
		)
		(layer "In4.Cu")
	)
	(gr_line
		(start 286.436562 -138.043158)
		(end 287.83661 -138.043158)
		(stroke
			(width 0.2)
			(type default)
		)
		(layer "In4.Cu")
	)
	(gr_arc
		(start 286.436562 -136.945878)
		(mid 285.887922 -137.494518)
		(end 286.436562 -138.043158)
		(stroke
			(width 0.2)
			(type default)
		)
		(layer "In4.Cu")
	)
	(gr_line
		(start 286.436562 -134.442962)
		(end 287.83661 -134.442962)
		(stroke
			(width 0.2)
			(type default)
		)
		(layer "In4.Cu")
	)
	(gr_arc
		(start 286.436562 -133.345682)
		(mid 285.887922 -133.894322)
		(end 286.436562 -134.442962)
		(stroke
			(width 0.2)
			(type default)
		)
		(layer "In4.Cu")
	)
	(gr_line
		(start 286.436816 -223.682306)
		(end 286.436562 -223.682306)
		(stroke
			(width 0.2)
			(type default)
		)
		(layer "In4.Cu")
	)
	(gr_arc
		(start 286.836612 -237.44301)
		(mid 287.385252 -236.89437)
		(end 286.836612 -236.34573)
		(stroke
			(width 0.2)
			(type default)
		)
		(layer "In4.Cu")
	)
	(gr_line
		(start 286.836612 -236.34573)
		(end 285.436564 -236.34573)
		(stroke
			(width 0.2)
			(type default)
		)
		(layer "In4.Cu")
	)
	(gr_arc
		(start 286.836612 -233.843068)
		(mid 287.385252 -233.294428)
		(end 286.836612 -232.745788)
		(stroke
			(width 0.2)
			(type default)
		)
		(layer "In4.Cu")
	)
	(gr_line
		(start 286.836612 -232.745788)
		(end 285.436564 -232.745788)
		(stroke
			(width 0.2)
			(type default)
		)
		(layer "In4.Cu")
	)
	(gr_arc
		(start 286.836612 -230.243126)
		(mid 287.385252 -229.694486)
		(end 286.836612 -229.145846)
		(stroke
			(width 0.2)
			(type default)
		)
		(layer "In4.Cu")
	)
	(gr_line
		(start 286.836612 -229.145846)
		(end 285.436564 -229.145846)
		(stroke
			(width 0.2)
			(type default)
		)
		(layer "In4.Cu")
	)
	(gr_arc
		(start 286.836612 -226.643184)
		(mid 287.385252 -226.094544)
		(end 286.836612 -225.545904)
		(stroke
			(width 0.2)
			(type default)
		)
		(layer "In4.Cu")
	)
	(gr_line
		(start 286.836612 -225.545904)
		(end 285.436564 -225.545904)
		(stroke
			(width 0.2)
			(type default)
		)
		(layer "In4.Cu")
	)
	(gr_arc
		(start 286.836612 -223.042988)
		(mid 287.385252 -222.494348)
		(end 286.836612 -221.945708)
		(stroke
			(width 0.2)
			(type default)
		)
		(layer "In4.Cu")
	)
	(gr_line
		(start 286.836612 -221.945708)
		(end 285.436564 -221.945708)
		(stroke
			(width 0.2)
			(type default)
		)
		(layer "In4.Cu")
	)
	(gr_arc
		(start 286.836612 -219.443046)
		(mid 287.385252 -218.894406)
		(end 286.836612 -218.345766)
		(stroke
			(width 0.2)
			(type default)
		)
		(layer "In4.Cu")
	)
	(gr_line
		(start 286.836612 -218.345766)
		(end 285.436564 -218.345766)
		(stroke
			(width 0.2)
			(type default)
		)
		(layer "In4.Cu")
	)
	(gr_arc
		(start 286.836612 -215.843104)
		(mid 287.385252 -215.294464)
		(end 286.836612 -214.745824)
		(stroke
			(width 0.2)
			(type default)
		)
		(layer "In4.Cu")
	)
	(gr_line
		(start 286.836612 -214.745824)
		(end 285.436564 -214.745824)
		(stroke
			(width 0.2)
			(type default)
		)
		(layer "In4.Cu")
	)
	(gr_arc
		(start 286.836612 -212.243162)
		(mid 287.385252 -211.694522)
		(end 286.836612 -211.145882)
		(stroke
			(width 0.2)
			(type default)
		)
		(layer "In4.Cu")
	)
	(gr_line
		(start 286.836612 -211.145882)
		(end 285.436564 -211.145882)
		(stroke
			(width 0.2)
			(type default)
		)
		(layer "In4.Cu")
	)
	(gr_arc
		(start 286.836612 -208.64322)
		(mid 287.385252 -208.09458)
		(end 286.836612 -207.54594)
		(stroke
			(width 0.2)
			(type default)
		)
		(layer "In4.Cu")
	)
	(gr_line
		(start 286.836612 -207.54594)
		(end 285.436564 -207.54594)
		(stroke
			(width 0.2)
			(type default)
		)
		(layer "In4.Cu")
	)
	(gr_arc
		(start 286.836612 -205.043024)
		(mid 287.385252 -204.494384)
		(end 286.836612 -203.945744)
		(stroke
			(width 0.2)
			(type default)
		)
		(layer "In4.Cu")
	)
	(gr_line
		(start 286.836612 -203.945744)
		(end 285.436564 -203.945744)
		(stroke
			(width 0.2)
			(type default)
		)
		(layer "In4.Cu")
	)
	(gr_arc
		(start 286.836612 -201.443082)
		(mid 287.385252 -200.894442)
		(end 286.836612 -200.345802)
		(stroke
			(width 0.2)
			(type default)
		)
		(layer "In4.Cu")
	)
	(gr_line
		(start 286.836612 -200.345802)
		(end 285.436564 -200.345802)
		(stroke
			(width 0.2)
			(type default)
		)
		(layer "In4.Cu")
	)
	(gr_arc
		(start 286.836612 -197.84314)
		(mid 287.385252 -197.2945)
		(end 286.836612 -196.74586)
		(stroke
			(width 0.2)
			(type default)
		)
		(layer "In4.Cu")
	)
	(gr_line
		(start 286.836612 -196.74586)
		(end 285.436564 -196.74586)
		(stroke
			(width 0.2)
			(type default)
		)
		(layer "In4.Cu")
	)
	(gr_arc
		(start 286.836612 -194.243198)
		(mid 287.385252 -193.694558)
		(end 286.836612 -193.145918)
		(stroke
			(width 0.2)
			(type default)
		)
		(layer "In4.Cu")
	)
	(gr_line
		(start 286.836612 -193.145918)
		(end 285.436564 -193.145918)
		(stroke
			(width 0.2)
			(type default)
		)
		(layer "In4.Cu")
	)
	(gr_arc
		(start 286.836612 -190.643002)
		(mid 287.385252 -190.094362)
		(end 286.836612 -189.545722)
		(stroke
			(width 0.2)
			(type default)
		)
		(layer "In4.Cu")
	)
	(gr_line
		(start 286.836612 -189.545722)
		(end 285.436564 -189.545722)
		(stroke
			(width 0.2)
			(type default)
		)
		(layer "In4.Cu")
	)
	(gr_arc
		(start 286.836612 -187.04306)
		(mid 287.385252 -186.49442)
		(end 286.836612 -185.94578)
		(stroke
			(width 0.2)
			(type default)
		)
		(layer "In4.Cu")
	)
	(gr_line
		(start 286.836612 -185.94578)
		(end 285.436564 -185.94578)
		(stroke
			(width 0.2)
			(type default)
		)
		(layer "In4.Cu")
	)
	(gr_arc
		(start 286.836612 -183.443118)
		(mid 287.385252 -182.894478)
		(end 286.836612 -182.345838)
		(stroke
			(width 0.2)
			(type default)
		)
		(layer "In4.Cu")
	)
	(gr_line
		(start 286.836612 -182.345838)
		(end 285.436564 -182.345838)
		(stroke
			(width 0.2)
			(type default)
		)
		(layer "In4.Cu")
	)
	(gr_arc
		(start 286.836612 -179.843176)
		(mid 287.385252 -179.294536)
		(end 286.836612 -178.745896)
		(stroke
			(width 0.2)
			(type default)
		)
		(layer "In4.Cu")
	)
	(gr_line
		(start 286.836612 -178.745896)
		(end 285.436564 -178.745896)
		(stroke
			(width 0.2)
			(type default)
		)
		(layer "In4.Cu")
	)
	(gr_arc
		(start 286.836612 -176.243234)
		(mid 287.385252 -175.694594)
		(end 286.836612 -175.145954)
		(stroke
			(width 0.2)
			(type default)
		)
		(layer "In4.Cu")
	)
	(gr_line
		(start 286.836612 -175.145954)
		(end 285.436564 -175.145954)
		(stroke
			(width 0.2)
			(type default)
		)
		(layer "In4.Cu")
	)
	(gr_arc
		(start 286.836612 -143.442944)
		(mid 287.385252 -142.894304)
		(end 286.836612 -142.345664)
		(stroke
			(width 0.2)
			(type default)
		)
		(layer "In4.Cu")
	)
	(gr_line
		(start 286.836612 -142.345664)
		(end 285.436564 -142.345664)
		(stroke
			(width 0.2)
			(type default)
		)
		(layer "In4.Cu")
	)
	(gr_arc
		(start 286.836612 -139.843002)
		(mid 287.385252 -139.294362)
		(end 286.836612 -138.745722)
		(stroke
			(width 0.2)
			(type default)
		)
		(layer "In4.Cu")
	)
	(gr_line
		(start 286.836612 -138.745722)
		(end 285.436564 -138.745722)
		(stroke
			(width 0.2)
			(type default)
		)
		(layer "In4.Cu")
	)
	(gr_arc
		(start 286.836612 -136.24306)
		(mid 287.385252 -135.69442)
		(end 286.836612 -135.14578)
		(stroke
			(width 0.2)
			(type default)
		)
		(layer "In4.Cu")
	)
	(gr_line
		(start 286.836612 -135.14578)
		(end 285.436564 -135.14578)
		(stroke
			(width 0.2)
			(type default)
		)
		(layer "In4.Cu")
	)
	(gr_arc
		(start 286.836612 -132.643118)
		(mid 287.385252 -132.094478)
		(end 286.836612 -131.545838)
		(stroke
			(width 0.2)
			(type default)
		)
		(layer "In4.Cu")
	)
	(gr_line
		(start 286.836612 -131.545838)
		(end 285.436564 -131.545838)
		(stroke
			(width 0.2)
			(type default)
		)
		(layer "In4.Cu")
	)
	(gr_arc
		(start 287.83661 -239.243108)
		(mid 288.38525 -238.694468)
		(end 287.83661 -238.145828)
		(stroke
			(width 0.2)
			(type default)
		)
		(layer "In4.Cu")
	)
	(gr_line
		(start 287.83661 -238.145828)
		(end 286.436562 -238.145828)
		(stroke
			(width 0.2)
			(type default)
		)
		(layer "In4.Cu")
	)
	(gr_arc
		(start 287.83661 -235.643166)
		(mid 288.38525 -235.094526)
		(end 287.83661 -234.545886)
		(stroke
			(width 0.2)
			(type default)
		)
		(layer "In4.Cu")
	)
	(gr_line
		(start 287.83661 -234.545886)
		(end 286.436562 -234.545886)
		(stroke
			(width 0.2)
			(type default)
		)
		(layer "In4.Cu")
	)
	(gr_arc
		(start 287.83661 -232.043224)
		(mid 288.38525 -231.494584)
		(end 287.83661 -230.945944)
		(stroke
			(width 0.2)
			(type default)
		)
		(layer "In4.Cu")
	)
	(gr_line
		(start 287.83661 -230.945944)
		(end 286.436562 -230.945944)
		(stroke
			(width 0.2)
			(type default)
		)
		(layer "In4.Cu")
	)
	(gr_arc
		(start 287.83661 -228.443028)
		(mid 288.38525 -227.894388)
		(end 287.83661 -227.345748)
		(stroke
			(width 0.2)
			(type default)
		)
		(layer "In4.Cu")
	)
	(gr_line
		(start 287.83661 -227.345748)
		(end 286.436562 -227.345748)
		(stroke
			(width 0.2)
			(type default)
		)
		(layer "In4.Cu")
	)
	(gr_arc
		(start 287.83661 -224.906586)
		(mid 288.44875 -224.294446)
		(end 287.83661 -223.682306)
		(stroke
			(width 0.2)
			(type default)
		)
		(layer "In4.Cu")
	)
	(gr_line
		(start 287.83661 -223.682306)
		(end 286.436816 -223.682306)
		(stroke
			(width 0.2)
			(type default)
		)
		(layer "In4.Cu")
	)
	(gr_arc
		(start 287.83661 -221.243144)
		(mid 288.38525 -220.694504)
		(end 287.83661 -220.145864)
		(stroke
			(width 0.2)
			(type default)
		)
		(layer "In4.Cu")
	)
	(gr_line
		(start 287.83661 -220.145864)
		(end 286.436562 -220.145864)
		(stroke
			(width 0.2)
			(type default)
		)
		(layer "In4.Cu")
	)
	(gr_arc
		(start 287.83661 -217.643202)
		(mid 288.38525 -217.094562)
		(end 287.83661 -216.545922)
		(stroke
			(width 0.2)
			(type default)
		)
		(layer "In4.Cu")
	)
	(gr_line
		(start 287.83661 -216.545922)
		(end 286.436562 -216.545922)
		(stroke
			(width 0.2)
			(type default)
		)
		(layer "In4.Cu")
	)
	(gr_arc
		(start 287.83661 -214.043006)
		(mid 288.38525 -213.494366)
		(end 287.83661 -212.945726)
		(stroke
			(width 0.2)
			(type default)
		)
		(layer "In4.Cu")
	)
	(gr_line
		(start 287.83661 -212.945726)
		(end 286.436562 -212.945726)
		(stroke
			(width 0.2)
			(type default)
		)
		(layer "In4.Cu")
	)
	(gr_arc
		(start 287.83661 -210.443064)
		(mid 288.38525 -209.894424)
		(end 287.83661 -209.345784)
		(stroke
			(width 0.2)
			(type default)
		)
		(layer "In4.Cu")
	)
	(gr_line
		(start 287.83661 -209.345784)
		(end 286.436562 -209.345784)
		(stroke
			(width 0.2)
			(type default)
		)
		(layer "In4.Cu")
	)
	(gr_arc
		(start 287.83661 -206.843122)
		(mid 288.38525 -206.294482)
		(end 287.83661 -205.745842)
		(stroke
			(width 0.2)
			(type default)
		)
		(layer "In4.Cu")
	)
	(gr_line
		(start 287.83661 -205.745842)
		(end 286.436562 -205.745842)
		(stroke
			(width 0.2)
			(type default)
		)
		(layer "In4.Cu")
	)
	(gr_arc
		(start 287.83661 -203.24318)
		(mid 288.38525 -202.69454)
		(end 287.83661 -202.1459)
		(stroke
			(width 0.2)
			(type default)
		)
		(layer "In4.Cu")
	)
	(gr_line
		(start 287.83661 -202.1459)
		(end 286.436562 -202.1459)
		(stroke
			(width 0.2)
			(type default)
		)
		(layer "In4.Cu")
	)
	(gr_arc
		(start 287.83661 -199.642984)
		(mid 288.38525 -199.094344)
		(end 287.83661 -198.545704)
		(stroke
			(width 0.2)
			(type default)
		)
		(layer "In4.Cu")
	)
	(gr_line
		(start 287.83661 -198.545704)
		(end 286.436562 -198.545704)
		(stroke
			(width 0.2)
			(type default)
		)
		(layer "In4.Cu")
	)
	(gr_arc
		(start 287.83661 -196.043042)
		(mid 288.38525 -195.494402)
		(end 287.83661 -194.945762)
		(stroke
			(width 0.2)
			(type default)
		)
		(layer "In4.Cu")
	)
	(gr_line
		(start 287.83661 -194.945762)
		(end 286.436562 -194.945762)
		(stroke
			(width 0.2)
			(type default)
		)
		(layer "In4.Cu")
	)
	(gr_arc
		(start 287.83661 -192.4431)
		(mid 288.38525 -191.89446)
		(end 287.83661 -191.34582)
		(stroke
			(width 0.2)
			(type default)
		)
		(layer "In4.Cu")
	)
	(gr_line
		(start 287.83661 -191.34582)
		(end 286.436562 -191.34582)
		(stroke
			(width 0.2)
			(type default)
		)
		(layer "In4.Cu")
	)
	(gr_arc
		(start 287.83661 -188.843158)
		(mid 288.38525 -188.294518)
		(end 287.83661 -187.745878)
		(stroke
			(width 0.2)
			(type default)
		)
		(layer "In4.Cu")
	)
	(gr_line
		(start 287.83661 -187.745878)
		(end 286.436562 -187.745878)
		(stroke
			(width 0.2)
			(type default)
		)
		(layer "In4.Cu")
	)
	(gr_arc
		(start 287.83661 -185.243216)
		(mid 288.38525 -184.694576)
		(end 287.83661 -184.145936)
		(stroke
			(width 0.2)
			(type default)
		)
		(layer "In4.Cu")
	)
	(gr_line
		(start 287.83661 -184.145936)
		(end 286.436562 -184.145936)
		(stroke
			(width 0.2)
			(type default)
		)
		(layer "In4.Cu")
	)
	(gr_arc
		(start 287.83661 -181.64302)
		(mid 288.38525 -181.09438)
		(end 287.83661 -180.54574)
		(stroke
			(width 0.2)
			(type default)
		)
		(layer "In4.Cu")
	)
	(gr_line
		(start 287.83661 -180.54574)
		(end 286.436562 -180.54574)
		(stroke
			(width 0.2)
			(type default)
		)
		(layer "In4.Cu")
	)
	(gr_arc
		(start 287.83661 -178.043078)
		(mid 288.38525 -177.494438)
		(end 287.83661 -176.945798)
		(stroke
			(width 0.2)
			(type default)
		)
		(layer "In4.Cu")
	)
	(gr_line
		(start 287.83661 -176.945798)
		(end 286.436562 -176.945798)
		(stroke
			(width 0.2)
			(type default)
		)
		(layer "In4.Cu")
	)
	(gr_arc
		(start 287.83661 -145.243042)
		(mid 288.38525 -144.694402)
		(end 287.83661 -144.145762)
		(stroke
			(width 0.2)
			(type default)
		)
		(layer "In4.Cu")
	)
	(gr_line
		(start 287.83661 -144.145762)
		(end 286.436562 -144.145762)
		(stroke
			(width 0.2)
			(type default)
		)
		(layer "In4.Cu")
	)
	(gr_arc
		(start 287.83661 -141.6431)
		(mid 288.38525 -141.09446)
		(end 287.83661 -140.54582)
		(stroke
			(width 0.2)
			(type default)
		)
		(layer "In4.Cu")
	)
	(gr_line
		(start 287.83661 -140.54582)
		(end 286.436562 -140.54582)
		(stroke
			(width 0.2)
			(type default)
		)
		(layer "In4.Cu")
	)
	(gr_arc
		(start 287.83661 -138.043158)
		(mid 288.38525 -137.494518)
		(end 287.83661 -136.945878)
		(stroke
			(width 0.2)
			(type default)
		)
		(layer "In4.Cu")
	)
	(gr_line
		(start 287.83661 -136.945878)
		(end 286.436562 -136.945878)
		(stroke
			(width 0.2)
			(type default)
		)
		(layer "In4.Cu")
	)
	(gr_arc
		(start 287.83661 -134.442962)
		(mid 288.38525 -133.894322)
		(end 287.83661 -133.345682)
		(stroke
			(width 0.2)
			(type default)
		)
		(layer "In4.Cu")
	)
	(gr_line
		(start 287.83661 -133.345682)
		(end 286.436562 -133.345682)
		(stroke
			(width 0.2)
			(type default)
		)
		(layer "In4.Cu")
	)
	(gr_line
		(start 289.1028 -130.0988)
		(end 275.3868 -130.0988)
		(stroke
			(width 0.381)
			(type default)
		)
		(layer "In4.Cu")
	)
	(gr_line
		(start 289.4584 -174.1678)
		(end 276.5298 -174.1678)
		(stroke
			(width 0.381)
			(type default)
		)
		(layer "In4.Cu")
	)
	(gr_line
		(start 289.4838 -146.8374)
		(end 290.3728 -145.9484)
		(stroke
			(width 0.381)
			(type default)
		)
		(layer "In4.Cu")
	)
	(gr_line
		(start 289.8648 -240.3348)
		(end 290.9316 -239.268)
		(stroke
			(width 0.381)
			(type default)
		)
		(layer "In4.Cu")
	)
	(gr_line
		(start 290.3728 -145.9484)
		(end 290.3728 -131.3688)
		(stroke
			(width 0.381)
			(type default)
		)
		(layer "In4.Cu")
	)
	(gr_line
		(start 290.3728 -131.3688)
		(end 289.1028 -130.0988)
		(stroke
			(width 0.381)
			(type default)
		)
		(layer "In4.Cu")
	)
	(gr_line
		(start 290.9316 -239.268)
		(end 290.9316 -175.641)
		(stroke
			(width 0.381)
			(type default)
		)
		(layer "In4.Cu")
	)
	(gr_line
		(start 290.9316 -175.641)
		(end 289.4584 -174.1678)
		(stroke
			(width 0.381)
			(type default)
		)
		(layer "In4.Cu")
	)
	(gr_line
		(start 306.382674 -65.529714)
		(end 314.3504 -73.49744)
		(stroke
			(width 0.381)
			(type default)
		)
		(layer "In4.Cu")
	)
	(gr_arc
		(start 306.649882 -385.99999)
		(mid 307.356987 -385.707097)
		(end 307.64988 -384.999992)
		(stroke
			(width 2.54)
			(type default)
		)
		(layer "In4.Cu")
	)
	(gr_line
		(start 307.64988 -384.999992)
		(end 307.64988 -383.29997)
		(stroke
			(width 2.54)
			(type default)
		)
		(layer "In4.Cu")
	)
	(gr_arc
		(start 308.649878 -382.299972)
		(mid 307.942776 -382.592871)
		(end 307.64988 -383.29997)
		(stroke
			(width 2.54)
			(type default)
		)
		(layer "In4.Cu")
	)
	(gr_line
		(start 308.649878 -382.299972)
		(end 315.149992 -382.299972)
		(stroke
			(width 2.54)
			(type default)
		)
		(layer "In4.Cu")
	)
	(gr_line
		(start 309.999888 -48.200056)
		(end 269.999968 -48.200056)
		(stroke
			(width 2.54)
			(type default)
		)
		(layer "In4.Cu")
	)
	(gr_arc
		(start 309.999888 -48.200056)
		(mid 310.706986 -47.907165)
		(end 310.999886 -47.200058)
		(stroke
			(width 2.54)
			(type default)
		)
		(layer "In4.Cu")
	)
	(gr_line
		(start 310.999886 -0.999998)
		(end 310.999886 -47.200058)
		(stroke
			(width 2.54)
			(type default)
		)
		(layer "In4.Cu")
	)
	(gr_arc
		(start 311.999884 0)
		(mid 311.292779 -0.292893)
		(end 310.999886 -0.999998)
		(stroke
			(width 2.54)
			(type default)
		)
		(layer "In4.Cu")
	)
	(gr_line
		(start 314.3504 -111.455454)
		(end 327.942448 -125.047502)
		(stroke
			(width 0.381)
			(type default)
		)
		(layer "In4.Cu")
	)
	(gr_line
		(start 314.3504 -73.49744)
		(end 314.3504 -111.455454)
		(stroke
			(width 0.381)
			(type default)
		)
		(layer "In4.Cu")
	)
	(gr_line
		(start 314.350654 -110.369096)
		(end 314.846716 -109.873034)
		(stroke
			(width 0.381)
			(type default)
		)
		(layer "In4.Cu")
	)
	(gr_line
		(start 314.354464 -97.978468)
		(end 314.837572 -97.49536)
		(stroke
			(width 0.381)
			(type default)
		)
		(layer "In4.Cu")
	)
	(gr_line
		(start 314.355988 -109.855)
		(end 314.354464 -109.853476)
		(stroke
			(width 0.381)
			(type default)
		)
		(layer "In4.Cu")
	)
	(gr_line
		(start 314.381134 -109.407198)
		(end 314.378848 -109.407198)
		(stroke
			(width 0.381)
			(type default)
		)
		(layer "In4.Cu")
	)
	(gr_line
		(start 314.837572 -97.49536)
		(end 314.360306 -97.018094)
		(stroke
			(width 0.381)
			(type default)
		)
		(layer "In4.Cu")
	)
	(gr_line
		(start 314.846716 -109.873034)
		(end 314.84697 -109.873034)
		(stroke
			(width 0.381)
			(type default)
		)
		(layer "In4.Cu")
	)
	(gr_line
		(start 314.84697 -109.873034)
		(end 314.381134 -109.407198)
		(stroke
			(width 0.381)
			(type default)
		)
		(layer "In4.Cu")
	)
	(gr_arc
		(start 316.14999 -384.999992)
		(mid 316.442883 -385.707097)
		(end 317.149988 -385.99999)
		(stroke
			(width 2.54)
			(type default)
		)
		(layer "In4.Cu")
	)
	(gr_arc
		(start 316.14999 -383.29997)
		(mid 315.857086 -382.592887)
		(end 315.149992 -382.299972)
		(stroke
			(width 2.54)
			(type default)
		)
		(layer "In4.Cu")
	)
	(gr_line
		(start 316.14999 -383.29997)
		(end 316.14999 -384.999992)
		(stroke
			(width 2.54)
			(type default)
		)
		(layer "In4.Cu")
	)
	(gr_line
		(start 317.149988 -385.99999)
		(end 362.700062 -385.99999)
		(stroke
			(width 2.54)
			(type default)
		)
		(layer "In4.Cu")
	)
	(gr_arc
		(start 318.91732 -245.45544)
		(mid 319.402333 -245.940834)
		(end 319.8876 -245.455694)
		(stroke
			(width 0.2)
			(type default)
		)
		(layer "In4.Cu")
	)
	(gr_line
		(start 318.91732 -244.312694)
		(end 318.91732 -245.45544)
		(stroke
			(width 0.2)
			(type default)
		)
		(layer "In4.Cu")
	)
	(gr_line
		(start 319.2145 -129.112264)
		(end 320.3575 -129.112264)
		(stroke
			(width 0.2)
			(type default)
		)
		(layer "In4.Cu")
	)
	(gr_line
		(start 319.2145 -14.11224)
		(end 320.3575 -14.11224)
		(stroke
			(width 0.2)
			(type default)
		)
		(layer "In4.Cu")
	)
	(gr_arc
		(start 319.214754 -128.141984)
		(mid 318.72936 -128.626997)
		(end 319.2145 -129.112264)
		(stroke
			(width 0.2)
			(type default)
		)
		(layer "In4.Cu")
	)
	(gr_arc
		(start 319.214754 -13.14196)
		(mid 318.72936 -13.626973)
		(end 319.2145 -14.11224)
		(stroke
			(width 0.2)
			(type default)
		)
		(layer "In4.Cu")
	)
	(gr_line
		(start 319.8876 -245.455694)
		(end 319.8876 -244.312694)
		(stroke
			(width 0.2)
			(type default)
		)
		(layer "In4.Cu")
	)
	(gr_arc
		(start 319.8876 -244.312694)
		(mid 319.40246 -243.827554)
		(end 318.91732 -244.312694)
		(stroke
			(width 0.2)
			(type default)
		)
		(layer "In4.Cu")
	)
	(gr_arc
		(start 320.3575 -129.112264)
		(mid 320.84264 -128.627124)
		(end 320.3575 -128.141984)
		(stroke
			(width 0.2)
			(type default)
		)
		(layer "In4.Cu")
	)
	(gr_line
		(start 320.3575 -128.141984)
		(end 319.214754 -128.141984)
		(stroke
			(width 0.2)
			(type default)
		)
		(layer "In4.Cu")
	)
	(gr_arc
		(start 320.3575 -14.11224)
		(mid 320.84264 -13.6271)
		(end 320.3575 -13.14196)
		(stroke
			(width 0.2)
			(type default)
		)
		(layer "In4.Cu")
	)
	(gr_line
		(start 320.3575 -13.14196)
		(end 319.214754 -13.14196)
		(stroke
			(width 0.2)
			(type default)
		)
		(layer "In4.Cu")
	)
	(gr_line
		(start 322.575428 -324.739)
		(end 247.523 -324.739)
		(stroke
			(width 0.381)
			(type default)
		)
		(layer "In4.Cu")
	)
	(gr_line
		(start 322.6816 -132.922264)
		(end 323.951346 -132.922264)
		(stroke
			(width 0.2)
			(type default)
		)
		(layer "In4.Cu")
	)
	(gr_arc
		(start 322.6816 -131.951984)
		(mid 322.19646 -132.437124)
		(end 322.6816 -132.922264)
		(stroke
			(width 0.2)
			(type default)
		)
		(layer "In4.Cu")
	)
	(gr_line
		(start 322.6816 -17.92224)
		(end 323.951346 -17.92224)
		(stroke
			(width 0.2)
			(type default)
		)
		(layer "In4.Cu")
	)
	(gr_arc
		(start 322.6816 -16.95196)
		(mid 322.19646 -17.4371)
		(end 322.6816 -17.92224)
		(stroke
			(width 0.2)
			(type default)
		)
		(layer "In4.Cu")
	)
	(gr_arc
		(start 323.10451 -249.385074)
		(mid 323.58965 -249.870214)
		(end 324.07479 -249.385074)
		(stroke
			(width 0.2)
			(type default)
		)
		(layer "In4.Cu")
	)
	(gr_line
		(start 323.10451 -248.115074)
		(end 323.10451 -249.385074)
		(stroke
			(width 0.2)
			(type default)
		)
		(layer "In4.Cu")
	)
	(gr_arc
		(start 323.951346 -132.922264)
		(mid 324.43674 -132.437251)
		(end 323.9516 -131.951984)
		(stroke
			(width 0.2)
			(type default)
		)
		(layer "In4.Cu")
	)
	(gr_arc
		(start 323.951346 -17.92224)
		(mid 324.43674 -17.437227)
		(end 323.9516 -16.95196)
		(stroke
			(width 0.2)
			(type default)
		)
		(layer "In4.Cu")
	)
	(gr_line
		(start 323.9516 -131.951984)
		(end 322.6816 -131.951984)
		(stroke
			(width 0.2)
			(type default)
		)
		(layer "In4.Cu")
	)
	(gr_line
		(start 323.9516 -16.95196)
		(end 322.6816 -16.95196)
		(stroke
			(width 0.2)
			(type default)
		)
		(layer "In4.Cu")
	)
	(gr_line
		(start 324.07479 -249.385074)
		(end 324.07479 -248.115328)
		(stroke
			(width 0.2)
			(type default)
		)
		(layer "In4.Cu")
	)
	(gr_arc
		(start 324.07479 -248.115328)
		(mid 323.589777 -247.629934)
		(end 323.10451 -248.115074)
		(stroke
			(width 0.2)
			(type default)
		)
		(layer "In4.Cu")
	)
	(gr_line
		(start 327.942448 -239.250474)
		(end 328.843894 -240.15192)
		(stroke
			(width 0.381)
			(type default)
		)
		(layer "In4.Cu")
	)
	(gr_line
		(start 327.942448 -125.047502)
		(end 327.942448 -239.250474)
		(stroke
			(width 0.381)
			(type default)
		)
		(layer "In4.Cu")
	)
	(gr_line
		(start 328.843894 -318.470534)
		(end 322.575428 -324.739)
		(stroke
			(width 0.381)
			(type default)
		)
		(layer "In4.Cu")
	)
	(gr_line
		(start 328.843894 -240.15192)
		(end 328.843894 -318.470534)
		(stroke
			(width 0.381)
			(type default)
		)
		(layer "In4.Cu")
	)
	(gr_line
		(start 328.93 -38.608)
		(end 344.3478 -54.0258)
		(stroke
			(width 0.381)
			(type default)
		)
		(layer "In4.Cu")
	)
	(gr_line
		(start 328.93 -19.177)
		(end 328.93 -38.608)
		(stroke
			(width 0.381)
			(type default)
		)
		(layer "In4.Cu")
	)
	(gr_line
		(start 330.8096 -17.2974)
		(end 328.93 -19.177)
		(stroke
			(width 0.381)
			(type default)
		)
		(layer "In4.Cu")
	)
	(gr_line
		(start 338.074 -256.413)
		(end 339.09 -257.429)
		(stroke
			(width 0.381)
			(type default)
		)
		(layer "In4.Cu")
	)
	(gr_line
		(start 338.074 -136.398)
		(end 338.074 -256.413)
		(stroke
			(width 0.381)
			(type default)
		)
		(layer "In4.Cu")
	)
	(gr_line
		(start 339.09 -257.429)
		(end 483.4382 -257.429)
		(stroke
			(width 0.381)
			(type default)
		)
		(layer "In4.Cu")
	)
	(gr_line
		(start 339.598 -134.874)
		(end 338.074 -136.398)
		(stroke
			(width 0.381)
			(type default)
		)
		(layer "In4.Cu")
	)
	(gr_line
		(start 341.6554 -97.4598)
		(end 314.369196 -97.4598)
		(stroke
			(width 0.381)
			(type default)
		)
		(layer "In4.Cu")
	)
	(gr_line
		(start 343.408 -17.2974)
		(end 330.8096 -17.2974)
		(stroke
			(width 0.381)
			(type default)
		)
		(layer "In4.Cu")
	)
	(gr_line
		(start 344.3478 -94.7674)
		(end 341.6554 -97.4598)
		(stroke
			(width 0.381)
			(type default)
		)
		(layer "In4.Cu")
	)
	(gr_line
		(start 344.3478 -54.0258)
		(end 344.3478 -94.7674)
		(stroke
			(width 0.381)
			(type default)
		)
		(layer "In4.Cu")
	)
	(gr_line
		(start 348.234 -134.874)
		(end 339.598 -134.874)
		(stroke
			(width 0.381)
			(type default)
		)
		(layer "In4.Cu")
	)
	(gr_line
		(start 349.411544 -11.293856)
		(end 343.408 -17.2974)
		(stroke
			(width 0.381)
			(type default)
		)
		(layer "In4.Cu")
	)
	(gr_arc
		(start 350.457262 -245.46052)
		(mid 350.942275 -245.945914)
		(end 351.427542 -245.460774)
		(stroke
			(width 0.2)
			(type default)
		)
		(layer "In4.Cu")
	)
	(gr_line
		(start 350.457262 -244.317774)
		(end 350.457262 -245.46052)
		(stroke
			(width 0.2)
			(type default)
		)
		(layer "In4.Cu")
	)
	(gr_line
		(start 350.764602 -129.112264)
		(end 351.907602 -129.112264)
		(stroke
			(width 0.2)
			(type default)
		)
		(layer "In4.Cu")
	)
	(gr_line
		(start 350.764602 -14.11224)
		(end 351.907602 -14.11224)
		(stroke
			(width 0.2)
			(type default)
		)
		(layer "In4.Cu")
	)
	(gr_arc
		(start 350.764856 -128.141984)
		(mid 350.279462 -128.626997)
		(end 350.764602 -129.112264)
		(stroke
			(width 0.2)
			(type default)
		)
		(layer "In4.Cu")
	)
	(gr_arc
		(start 350.764856 -13.14196)
		(mid 350.279462 -13.626973)
		(end 350.764602 -14.11224)
		(stroke
			(width 0.2)
			(type default)
		)
		(layer "In4.Cu")
	)
	(gr_circle
		(center 350.799908 -372.599966)
		(end 352.212148 -372.599966)
		(stroke
			(width 0.2)
			(type default)
		)
		(fill no)
		(layer "In4.Cu")
	)
	(gr_circle
		(center 350.799908 -367.09985)
		(end 352.212148 -367.09985)
		(stroke
			(width 0.2)
			(type default)
		)
		(fill no)
		(layer "In4.Cu")
	)
	(gr_line
		(start 351.427542 -245.460774)
		(end 351.427542 -244.317774)
		(stroke
			(width 0.2)
			(type default)
		)
		(layer "In4.Cu")
	)
	(gr_arc
		(start 351.427542 -244.317774)
		(mid 350.942402 -243.832634)
		(end 350.457262 -244.317774)
		(stroke
			(width 0.2)
			(type default)
		)
		(layer "In4.Cu")
	)
	(gr_line
		(start 351.79 -131.318)
		(end 348.234 -134.874)
		(stroke
			(width 0.381)
			(type default)
		)
		(layer "In4.Cu")
	)
	(gr_arc
		(start 351.907602 -129.112264)
		(mid 352.392742 -128.627124)
		(end 351.907602 -128.141984)
		(stroke
			(width 0.2)
			(type default)
		)
		(layer "In4.Cu")
	)
	(gr_line
		(start 351.907602 -128.141984)
		(end 350.764856 -128.141984)
		(stroke
			(width 0.2)
			(type default)
		)
		(layer "In4.Cu")
	)
	(gr_arc
		(start 351.907602 -14.11224)
		(mid 352.392742 -13.6271)
		(end 351.907602 -13.14196)
		(stroke
			(width 0.2)
			(type default)
		)
		(layer "In4.Cu")
	)
	(gr_line
		(start 351.907602 -13.14196)
		(end 350.764856 -13.14196)
		(stroke
			(width 0.2)
			(type default)
		)
		(layer "In4.Cu")
	)
	(gr_line
		(start 354.231702 -132.922264)
		(end 355.501702 -132.922264)
		(stroke
			(width 0.2)
			(type default)
		)
		(layer "In4.Cu")
	)
	(gr_line
		(start 354.231702 -17.92224)
		(end 355.501702 -17.92224)
		(stroke
			(width 0.2)
			(type default)
		)
		(layer "In4.Cu")
	)
	(gr_arc
		(start 354.231956 -131.951984)
		(mid 353.746562 -132.436997)
		(end 354.231702 -132.922264)
		(stroke
			(width 0.2)
			(type default)
		)
		(layer "In4.Cu")
	)
	(gr_arc
		(start 354.231956 -16.95196)
		(mid 353.746562 -17.436973)
		(end 354.231702 -17.92224)
		(stroke
			(width 0.2)
			(type default)
		)
		(layer "In4.Cu")
	)
	(gr_arc
		(start 354.654612 -249.385074)
		(mid 355.139752 -249.870214)
		(end 355.624892 -249.385074)
		(stroke
			(width 0.2)
			(type default)
		)
		(layer "In4.Cu")
	)
	(gr_line
		(start 354.654612 -248.115074)
		(end 354.654612 -249.385074)
		(stroke
			(width 0.2)
			(type default)
		)
		(layer "In4.Cu")
	)
	(gr_arc
		(start 355.501702 -132.922264)
		(mid 355.986842 -132.437124)
		(end 355.501702 -131.951984)
		(stroke
			(width 0.2)
			(type default)
		)
		(layer "In4.Cu")
	)
	(gr_line
		(start 355.501702 -131.951984)
		(end 354.231956 -131.951984)
		(stroke
			(width 0.2)
			(type default)
		)
		(layer "In4.Cu")
	)
	(gr_arc
		(start 355.501702 -17.92224)
		(mid 355.986842 -17.4371)
		(end 355.501702 -16.95196)
		(stroke
			(width 0.2)
			(type default)
		)
		(layer "In4.Cu")
	)
	(gr_line
		(start 355.501702 -16.95196)
		(end 354.231956 -16.95196)
		(stroke
			(width 0.2)
			(type default)
		)
		(layer "In4.Cu")
	)
	(gr_line
		(start 355.624892 -249.385074)
		(end 355.624892 -248.115328)
		(stroke
			(width 0.2)
			(type default)
		)
		(layer "In4.Cu")
	)
	(gr_arc
		(start 355.624892 -248.115328)
		(mid 355.139879 -247.629934)
		(end 354.654612 -248.115074)
		(stroke
			(width 0.2)
			(type default)
		)
		(layer "In4.Cu")
	)
	(gr_line
		(start 357.632 -131.318)
		(end 351.79 -131.318)
		(stroke
			(width 0.381)
			(type default)
		)
		(layer "In4.Cu")
	)
	(gr_line
		(start 358.521 -135.001)
		(end 358.521 -132.207)
		(stroke
			(width 0.381)
			(type default)
		)
		(layer "In4.Cu")
	)
	(gr_line
		(start 358.521 -132.207)
		(end 357.632 -131.318)
		(stroke
			(width 0.381)
			(type default)
		)
		(layer "In4.Cu")
	)
	(gr_line
		(start 360.7308 -137.2108)
		(end 358.521 -135.001)
		(stroke
			(width 0.381)
			(type default)
		)
		(layer "In4.Cu")
	)
	(gr_arc
		(start 362.700062 -385.99999)
		(mid 363.407167 -385.707097)
		(end 363.70006 -384.999992)
		(stroke
			(width 2.54)
			(type default)
		)
		(layer "In4.Cu")
	)
	(gr_line
		(start 363.70006 -384.999992)
		(end 363.70006 -381)
		(stroke
			(width 2.54)
			(type default)
		)
		(layer "In4.Cu")
	)
	(gr_arc
		(start 364.700058 -380.000002)
		(mid 363.99298 -380.292909)
		(end 363.70006 -381)
		(stroke
			(width 2.54)
			(type default)
		)
		(layer "In4.Cu")
	)
	(gr_line
		(start 364.700058 -380.000002)
		(end 416.699954 -380.000002)
		(stroke
			(width 2.54)
			(type default)
		)
		(layer "In4.Cu")
	)
	(gr_line
		(start 367.0554 -137.2108)
		(end 360.7308 -137.2108)
		(stroke
			(width 0.381)
			(type default)
		)
		(layer "In4.Cu")
	)
	(gr_line
		(start 369.3922 -134.874)
		(end 367.0554 -137.2108)
		(stroke
			(width 0.381)
			(type default)
		)
		(layer "In4.Cu")
	)
	(gr_line
		(start 380.365 -134.874)
		(end 369.3922 -134.874)
		(stroke
			(width 0.381)
			(type default)
		)
		(layer "In4.Cu")
	)
	(gr_arc
		(start 382.00711 -245.44528)
		(mid 382.492123 -245.930674)
		(end 382.97739 -245.445534)
		(stroke
			(width 0.2)
			(type default)
		)
		(layer "In4.Cu")
	)
	(gr_line
		(start 382.00711 -244.302534)
		(end 382.00711 -245.44528)
		(stroke
			(width 0.2)
			(type default)
		)
		(layer "In4.Cu")
	)
	(gr_line
		(start 382.31445 -129.112264)
		(end 383.45745 -129.112264)
		(stroke
			(width 0.2)
			(type default)
		)
		(layer "In4.Cu")
	)
	(gr_line
		(start 382.31445 -14.11224)
		(end 383.45745 -14.11224)
		(stroke
			(width 0.2)
			(type default)
		)
		(layer "In4.Cu")
	)
	(gr_arc
		(start 382.314704 -128.141984)
		(mid 381.82931 -128.626997)
		(end 382.31445 -129.112264)
		(stroke
			(width 0.2)
			(type default)
		)
		(layer "In4.Cu")
	)
	(gr_arc
		(start 382.314704 -13.14196)
		(mid 381.82931 -13.626973)
		(end 382.31445 -14.11224)
		(stroke
			(width 0.2)
			(type default)
		)
		(layer "In4.Cu")
	)
	(gr_line
		(start 382.97739 -245.445534)
		(end 382.97739 -244.302534)
		(stroke
			(width 0.2)
			(type default)
		)
		(layer "In4.Cu")
	)
	(gr_arc
		(start 382.97739 -244.302534)
		(mid 382.49225 -243.817394)
		(end 382.00711 -244.302534)
		(stroke
			(width 0.2)
			(type default)
		)
		(layer "In4.Cu")
	)
	(gr_arc
		(start 383.45745 -129.112264)
		(mid 383.94259 -128.627124)
		(end 383.45745 -128.141984)
		(stroke
			(width 0.2)
			(type default)
		)
		(layer "In4.Cu")
	)
	(gr_line
		(start 383.45745 -128.141984)
		(end 382.314704 -128.141984)
		(stroke
			(width 0.2)
			(type default)
		)
		(layer "In4.Cu")
	)
	(gr_arc
		(start 383.45745 -14.11224)
		(mid 383.94259 -13.6271)
		(end 383.45745 -13.14196)
		(stroke
			(width 0.2)
			(type default)
		)
		(layer "In4.Cu")
	)
	(gr_line
		(start 383.45745 -13.14196)
		(end 382.314704 -13.14196)
		(stroke
			(width 0.2)
			(type default)
		)
		(layer "In4.Cu")
	)
	(gr_line
		(start 384.048 -131.191)
		(end 380.365 -134.874)
		(stroke
			(width 0.381)
			(type default)
		)
		(layer "In4.Cu")
	)
	(gr_line
		(start 385.78155 -132.922264)
		(end 387.051296 -132.922264)
		(stroke
			(width 0.2)
			(type default)
		)
		(layer "In4.Cu")
	)
	(gr_arc
		(start 385.78155 -131.951984)
		(mid 385.29641 -132.437124)
		(end 385.78155 -132.922264)
		(stroke
			(width 0.2)
			(type default)
		)
		(layer "In4.Cu")
	)
	(gr_line
		(start 385.78155 -17.92224)
		(end 387.051296 -17.92224)
		(stroke
			(width 0.2)
			(type default)
		)
		(layer "In4.Cu")
	)
	(gr_arc
		(start 385.78155 -16.95196)
		(mid 385.29641 -17.4371)
		(end 385.78155 -17.92224)
		(stroke
			(width 0.2)
			(type default)
		)
		(layer "In4.Cu")
	)
	(gr_arc
		(start 386.20446 -249.385074)
		(mid 386.6896 -249.870214)
		(end 387.17474 -249.385074)
		(stroke
			(width 0.2)
			(type default)
		)
		(layer "In4.Cu")
	)
	(gr_line
		(start 386.20446 -248.115074)
		(end 386.20446 -249.385074)
		(stroke
			(width 0.2)
			(type default)
		)
		(layer "In4.Cu")
	)
	(gr_arc
		(start 387.051296 -132.922264)
		(mid 387.53669 -132.437251)
		(end 387.05155 -131.951984)
		(stroke
			(width 0.2)
			(type default)
		)
		(layer "In4.Cu")
	)
	(gr_arc
		(start 387.051296 -17.92224)
		(mid 387.53669 -17.437227)
		(end 387.05155 -16.95196)
		(stroke
			(width 0.2)
			(type default)
		)
		(layer "In4.Cu")
	)
	(gr_line
		(start 387.05155 -131.951984)
		(end 385.78155 -131.951984)
		(stroke
			(width 0.2)
			(type default)
		)
		(layer "In4.Cu")
	)
	(gr_line
		(start 387.05155 -16.95196)
		(end 385.78155 -16.95196)
		(stroke
			(width 0.2)
			(type default)
		)
		(layer "In4.Cu")
	)
	(gr_line
		(start 387.17474 -249.385074)
		(end 387.17474 -248.115328)
		(stroke
			(width 0.2)
			(type default)
		)
		(layer "In4.Cu")
	)
	(gr_arc
		(start 387.17474 -248.115328)
		(mid 386.689727 -247.629934)
		(end 386.20446 -248.115074)
		(stroke
			(width 0.2)
			(type default)
		)
		(layer "In4.Cu")
	)
	(gr_line
		(start 389.128 -131.191)
		(end 384.048 -131.191)
		(stroke
			(width 0.381)
			(type default)
		)
		(layer "In4.Cu")
	)
	(gr_line
		(start 392.811 -134.874)
		(end 389.128 -131.191)
		(stroke
			(width 0.381)
			(type default)
		)
		(layer "In4.Cu")
	)
	(gr_line
		(start 393.213844 -11.293856)
		(end 349.411544 -11.293856)
		(stroke
			(width 0.381)
			(type default)
		)
		(layer "In4.Cu")
	)
	(gr_line
		(start 393.887452 -10.620248)
		(end 393.213844 -11.293856)
		(stroke
			(width 0.381)
			(type default)
		)
		(layer "In4.Cu")
	)
	(gr_line
		(start 398.239742 -10.620248)
		(end 393.887452 -10.620248)
		(stroke
			(width 0.381)
			(type default)
		)
		(layer "In4.Cu")
	)
	(gr_line
		(start 398.922494 -11.303)
		(end 398.239742 -10.620248)
		(stroke
			(width 0.381)
			(type default)
		)
		(layer "In4.Cu")
	)
	(gr_line
		(start 405.003 -134.874)
		(end 392.811 -134.874)
		(stroke
			(width 0.381)
			(type default)
		)
		(layer "In4.Cu")
	)
	(gr_line
		(start 408.686 -131.191)
		(end 405.003 -134.874)
		(stroke
			(width 0.381)
			(type default)
		)
		(layer "In4.Cu")
	)
	(gr_arc
		(start 413.557212 -245.58752)
		(mid 414.042225 -246.072914)
		(end 414.527492 -245.587774)
		(stroke
			(width 0.2)
			(type default)
		)
		(layer "In4.Cu")
	)
	(gr_line
		(start 413.557212 -244.444774)
		(end 413.557212 -245.58752)
		(stroke
			(width 0.2)
			(type default)
		)
		(layer "In4.Cu")
	)
	(gr_line
		(start 413.864552 -129.112264)
		(end 415.007552 -129.112264)
		(stroke
			(width 0.2)
			(type default)
		)
		(layer "In4.Cu")
	)
	(gr_line
		(start 413.864552 -14.11224)
		(end 415.007552 -14.11224)
		(stroke
			(width 0.2)
			(type default)
		)
		(layer "In4.Cu")
	)
	(gr_arc
		(start 413.864806 -128.141984)
		(mid 413.379412 -128.626997)
		(end 413.864552 -129.112264)
		(stroke
			(width 0.2)
			(type default)
		)
		(layer "In4.Cu")
	)
	(gr_arc
		(start 413.864806 -13.14196)
		(mid 413.379412 -13.626973)
		(end 413.864552 -14.11224)
		(stroke
			(width 0.2)
			(type default)
		)
		(layer "In4.Cu")
	)
	(gr_line
		(start 414.274 -145.3896)
		(end 414.274 -142.748)
		(stroke
			(width 0.381)
			(type default)
		)
		(layer "In4.Cu")
	)
	(gr_line
		(start 414.274 -142.748)
		(end 418.465 -138.557)
		(stroke
			(width 0.381)
			(type default)
		)
		(layer "In4.Cu")
	)
	(gr_line
		(start 414.527492 -245.587774)
		(end 414.527492 -244.444774)
		(stroke
			(width 0.2)
			(type default)
		)
		(layer "In4.Cu")
	)
	(gr_arc
		(start 414.527492 -244.444774)
		(mid 414.042352 -243.959634)
		(end 413.557212 -244.444774)
		(stroke
			(width 0.2)
			(type default)
		)
		(layer "In4.Cu")
	)
	(gr_arc
		(start 415.007552 -129.112264)
		(mid 415.492692 -128.627124)
		(end 415.007552 -128.141984)
		(stroke
			(width 0.2)
			(type default)
		)
		(layer "In4.Cu")
	)
	(gr_line
		(start 415.007552 -128.141984)
		(end 413.864806 -128.141984)
		(stroke
			(width 0.2)
			(type default)
		)
		(layer "In4.Cu")
	)
	(gr_arc
		(start 415.007552 -14.11224)
		(mid 415.492692 -13.6271)
		(end 415.007552 -13.14196)
		(stroke
			(width 0.2)
			(type default)
		)
		(layer "In4.Cu")
	)
	(gr_line
		(start 415.007552 -13.14196)
		(end 413.864806 -13.14196)
		(stroke
			(width 0.2)
			(type default)
		)
		(layer "In4.Cu")
	)
	(gr_line
		(start 415.036 -109.855)
		(end 314.355988 -109.855)
		(stroke
			(width 0.381)
			(type default)
		)
		(layer "In4.Cu")
	)
	(gr_line
		(start 417.331652 -132.922264)
		(end 418.601652 -132.922264)
		(stroke
			(width 0.2)
			(type default)
		)
		(layer "In4.Cu")
	)
	(gr_line
		(start 417.331652 -17.92224)
		(end 418.601652 -17.92224)
		(stroke
			(width 0.2)
			(type default)
		)
		(layer "In4.Cu")
	)
	(gr_arc
		(start 417.331906 -131.951984)
		(mid 416.846512 -132.436997)
		(end 417.331652 -132.922264)
		(stroke
			(width 0.2)
			(type default)
		)
		(layer "In4.Cu")
	)
	(gr_arc
		(start 417.331906 -16.95196)
		(mid 416.846512 -17.436973)
		(end 417.331652 -17.92224)
		(stroke
			(width 0.2)
			(type default)
		)
		(layer "In4.Cu")
	)
	(gr_arc
		(start 417.699952 -384.999992)
		(mid 417.992845 -385.707097)
		(end 418.69995 -385.99999)
		(stroke
			(width 2.54)
			(type default)
		)
		(layer "In4.Cu")
	)
	(gr_arc
		(start 417.699952 -381)
		(mid 417.407057 -380.292911)
		(end 416.699954 -380.000002)
		(stroke
			(width 2.54)
			(type default)
		)
		(layer "In4.Cu")
	)
	(gr_line
		(start 417.699952 -381)
		(end 417.699952 -384.999992)
		(stroke
			(width 2.54)
			(type default)
		)
		(layer "In4.Cu")
	)
	(gr_arc
		(start 417.754562 -249.385074)
		(mid 418.239702 -249.870214)
		(end 418.724842 -249.385074)
		(stroke
			(width 0.2)
			(type default)
		)
		(layer "In4.Cu")
	)
	(gr_line
		(start 417.754562 -248.115074)
		(end 417.754562 -249.385074)
		(stroke
			(width 0.2)
			(type default)
		)
		(layer "In4.Cu")
	)
	(gr_line
		(start 418.465 -138.557)
		(end 418.465 -136.144)
		(stroke
			(width 0.381)
			(type default)
		)
		(layer "In4.Cu")
	)
	(gr_line
		(start 418.465 -136.144)
		(end 420.878 -133.731)
		(stroke
			(width 0.381)
			(type default)
		)
		(layer "In4.Cu")
	)
	(gr_arc
		(start 418.601652 -132.922264)
		(mid 419.086792 -132.437124)
		(end 418.601652 -131.951984)
		(stroke
			(width 0.2)
			(type default)
		)
		(layer "In4.Cu")
	)
	(gr_line
		(start 418.601652 -131.951984)
		(end 417.331906 -131.951984)
		(stroke
			(width 0.2)
			(type default)
		)
		(layer "In4.Cu")
	)
	(gr_arc
		(start 418.601652 -17.92224)
		(mid 419.086792 -17.4371)
		(end 418.601652 -16.95196)
		(stroke
			(width 0.2)
			(type default)
		)
		(layer "In4.Cu")
	)
	(gr_line
		(start 418.601652 -16.95196)
		(end 417.331906 -16.95196)
		(stroke
			(width 0.2)
			(type default)
		)
		(layer "In4.Cu")
	)
	(gr_line
		(start 418.69995 -385.99999)
		(end 464.250024 -385.99999)
		(stroke
			(width 2.54)
			(type default)
		)
		(layer "In4.Cu")
	)
	(gr_line
		(start 418.724842 -249.385074)
		(end 418.724842 -248.115328)
		(stroke
			(width 0.2)
			(type default)
		)
		(layer "In4.Cu")
	)
	(gr_arc
		(start 418.724842 -248.115328)
		(mid 418.239829 -247.629934)
		(end 417.754562 -248.115074)
		(stroke
			(width 0.2)
			(type default)
		)
		(layer "In4.Cu")
	)
	(gr_line
		(start 420.37 -131.191)
		(end 408.686 -131.191)
		(stroke
			(width 0.381)
			(type default)
		)
		(layer "In4.Cu")
	)
	(gr_line
		(start 420.878 -133.731)
		(end 420.878 -131.699)
		(stroke
			(width 0.381)
			(type default)
		)
		(layer "In4.Cu")
	)
	(gr_line
		(start 420.878 -131.699)
		(end 420.37 -131.191)
		(stroke
			(width 0.381)
			(type default)
		)
		(layer "In4.Cu")
	)
	(gr_line
		(start 424.307 -138.684)
		(end 424.307 -119.126)
		(stroke
			(width 0.381)
			(type default)
		)
		(layer "In4.Cu")
	)
	(gr_line
		(start 424.307 -119.126)
		(end 415.036 -109.855)
		(stroke
			(width 0.381)
			(type default)
		)
		(layer "In4.Cu")
	)
	(gr_line
		(start 428.1678 -142.5448)
		(end 424.307 -138.684)
		(stroke
			(width 0.381)
			(type default)
		)
		(layer "In4.Cu")
	)
	(gr_line
		(start 435.9402 -142.5448)
		(end 428.1678 -142.5448)
		(stroke
			(width 0.381)
			(type default)
		)
		(layer "In4.Cu")
	)
	(gr_line
		(start 439.547 -11.303)
		(end 398.922494 -11.303)
		(stroke
			(width 0.381)
			(type default)
		)
		(layer "In4.Cu")
	)
	(gr_line
		(start 444.373 -16.129)
		(end 439.547 -11.303)
		(stroke
			(width 0.381)
			(type default)
		)
		(layer "In4.Cu")
	)
	(gr_arc
		(start 445.11722 -245.45544)
		(mid 445.602233 -245.940834)
		(end 446.0875 -245.455694)
		(stroke
			(width 0.2)
			(type default)
		)
		(layer "In4.Cu")
	)
	(gr_line
		(start 445.11722 -244.312694)
		(end 445.11722 -245.45544)
		(stroke
			(width 0.2)
			(type default)
		)
		(layer "In4.Cu")
	)
	(gr_line
		(start 445.4144 -129.112264)
		(end 446.5574 -129.112264)
		(stroke
			(width 0.2)
			(type default)
		)
		(layer "In4.Cu")
	)
	(gr_line
		(start 445.4144 -14.11224)
		(end 446.5574 -14.11224)
		(stroke
			(width 0.2)
			(type default)
		)
		(layer "In4.Cu")
	)
	(gr_arc
		(start 445.414654 -128.141984)
		(mid 444.92926 -128.626997)
		(end 445.4144 -129.112264)
		(stroke
			(width 0.2)
			(type default)
		)
		(layer "In4.Cu")
	)
	(gr_arc
		(start 445.414654 -13.14196)
		(mid 444.92926 -13.626973)
		(end 445.4144 -14.11224)
		(stroke
			(width 0.2)
			(type default)
		)
		(layer "In4.Cu")
	)
	(gr_line
		(start 446.0875 -245.455694)
		(end 446.0875 -244.312694)
		(stroke
			(width 0.2)
			(type default)
		)
		(layer "In4.Cu")
	)
	(gr_arc
		(start 446.0875 -244.312694)
		(mid 445.60236 -243.827554)
		(end 445.11722 -244.312694)
		(stroke
			(width 0.2)
			(type default)
		)
		(layer "In4.Cu")
	)
	(gr_arc
		(start 446.5574 -129.112264)
		(mid 447.04254 -128.627124)
		(end 446.5574 -128.141984)
		(stroke
			(width 0.2)
			(type default)
		)
		(layer "In4.Cu")
	)
	(gr_line
		(start 446.5574 -128.141984)
		(end 445.414654 -128.141984)
		(stroke
			(width 0.2)
			(type default)
		)
		(layer "In4.Cu")
	)
	(gr_arc
		(start 446.5574 -14.11224)
		(mid 447.04254 -13.6271)
		(end 446.5574 -13.14196)
		(stroke
			(width 0.2)
			(type default)
		)
		(layer "In4.Cu")
	)
	(gr_line
		(start 446.5574 -13.14196)
		(end 445.414654 -13.14196)
		(stroke
			(width 0.2)
			(type default)
		)
		(layer "In4.Cu")
	)
	(gr_line
		(start 447.294 -131.191)
		(end 435.9402 -142.5448)
		(stroke
			(width 0.381)
			(type default)
		)
		(layer "In4.Cu")
	)
	(gr_circle
		(center 447.399918 -372.599966)
		(end 448.812158 -372.599966)
		(stroke
			(width 0.2)
			(type default)
		)
		(fill no)
		(layer "In4.Cu")
	)
	(gr_circle
		(center 447.399918 -367.09985)
		(end 448.812158 -367.09985)
		(stroke
			(width 0.2)
			(type default)
		)
		(fill no)
		(layer "In4.Cu")
	)
	(gr_line
		(start 448.8815 -132.922264)
		(end 450.151246 -132.922264)
		(stroke
			(width 0.2)
			(type default)
		)
		(layer "In4.Cu")
	)
	(gr_arc
		(start 448.8815 -131.951984)
		(mid 448.39636 -132.437124)
		(end 448.8815 -132.922264)
		(stroke
			(width 0.2)
			(type default)
		)
		(layer "In4.Cu")
	)
	(gr_line
		(start 448.8815 -17.92224)
		(end 450.151246 -17.92224)
		(stroke
			(width 0.2)
			(type default)
		)
		(layer "In4.Cu")
	)
	(gr_arc
		(start 448.8815 -16.95196)
		(mid 448.39636 -17.4371)
		(end 448.8815 -17.92224)
		(stroke
			(width 0.2)
			(type default)
		)
		(layer "In4.Cu")
	)
	(gr_arc
		(start 449.30441 -249.385074)
		(mid 449.78955 -249.870214)
		(end 450.27469 -249.385074)
		(stroke
			(width 0.2)
			(type default)
		)
		(layer "In4.Cu")
	)
	(gr_line
		(start 449.30441 -248.115074)
		(end 449.30441 -249.385074)
		(stroke
			(width 0.2)
			(type default)
		)
		(layer "In4.Cu")
	)
	(gr_arc
		(start 450.151246 -132.922264)
		(mid 450.63664 -132.437251)
		(end 450.1515 -131.951984)
		(stroke
			(width 0.2)
			(type default)
		)
		(layer "In4.Cu")
	)
	(gr_arc
		(start 450.151246 -17.92224)
		(mid 450.63664 -17.437227)
		(end 450.1515 -16.95196)
		(stroke
			(width 0.2)
			(type default)
		)
		(layer "In4.Cu")
	)
	(gr_line
		(start 450.1515 -131.951984)
		(end 448.8815 -131.951984)
		(stroke
			(width 0.2)
			(type default)
		)
		(layer "In4.Cu")
	)
	(gr_line
		(start 450.1515 -16.95196)
		(end 448.8815 -16.95196)
		(stroke
			(width 0.2)
			(type default)
		)
		(layer "In4.Cu")
	)
	(gr_line
		(start 450.27469 -249.385074)
		(end 450.27469 -248.115328)
		(stroke
			(width 0.2)
			(type default)
		)
		(layer "In4.Cu")
	)
	(gr_arc
		(start 450.27469 -248.115328)
		(mid 449.789677 -247.629934)
		(end 449.30441 -248.115074)
		(stroke
			(width 0.2)
			(type default)
		)
		(layer "In4.Cu")
	)
	(gr_line
		(start 450.2912 -186.7154)
		(end 450.2912 -181.4068)
		(stroke
			(width 0.381)
			(type default)
		)
		(layer "In4.Cu")
	)
	(gr_line
		(start 450.2912 -181.4068)
		(end 414.274 -145.3896)
		(stroke
			(width 0.381)
			(type default)
		)
		(layer "In4.Cu")
	)
	(gr_line
		(start 451.993 -16.129)
		(end 444.373 -16.129)
		(stroke
			(width 0.381)
			(type default)
		)
		(layer "In4.Cu")
	)
	(gr_line
		(start 452.247 -131.191)
		(end 447.294 -131.191)
		(stroke
			(width 0.381)
			(type default)
		)
		(layer "In4.Cu")
	)
	(gr_line
		(start 454.2536 -190.6778)
		(end 450.2912 -186.7154)
		(stroke
			(width 0.381)
			(type default)
		)
		(layer "In4.Cu")
	)
	(gr_line
		(start 454.533 -18.669)
		(end 451.993 -16.129)
		(stroke
			(width 0.381)
			(type default)
		)
		(layer "In4.Cu")
	)
	(gr_line
		(start 454.66 -140.462)
		(end 454.66 -133.604)
		(stroke
			(width 0.381)
			(type default)
		)
		(layer "In4.Cu")
	)
	(gr_line
		(start 454.66 -133.604)
		(end 452.247 -131.191)
		(stroke
			(width 0.381)
			(type default)
		)
		(layer "In4.Cu")
	)
	(gr_line
		(start 456.7428 -142.5448)
		(end 454.66 -140.462)
		(stroke
			(width 0.381)
			(type default)
		)
		(layer "In4.Cu")
	)
	(gr_line
		(start 459.5622 -190.6778)
		(end 454.2536 -190.6778)
		(stroke
			(width 0.381)
			(type default)
		)
		(layer "In4.Cu")
	)
	(gr_line
		(start 461.264 -18.669)
		(end 454.533 -18.669)
		(stroke
			(width 0.381)
			(type default)
		)
		(layer "In4.Cu")
	)
	(gr_arc
		(start 464.250024 -385.99999)
		(mid 464.957129 -385.707097)
		(end 465.250022 -384.999992)
		(stroke
			(width 2.54)
			(type default)
		)
		(layer "In4.Cu")
	)
	(gr_line
		(start 464.693 -22.098)
		(end 461.264 -18.669)
		(stroke
			(width 0.381)
			(type default)
		)
		(layer "In4.Cu")
	)
	(gr_line
		(start 465.250022 -384.999992)
		(end 465.250022 -383.29997)
		(stroke
			(width 2.54)
			(type default)
		)
		(layer "In4.Cu")
	)
	(gr_arc
		(start 466.25002 -382.299972)
		(mid 465.542891 -382.592856)
		(end 465.250022 -383.29997)
		(stroke
			(width 2.54)
			(type default)
		)
		(layer "In4.Cu")
	)
	(gr_line
		(start 466.25002 -382.299972)
		(end 472.74988 -382.299972)
		(stroke
			(width 2.54)
			(type default)
		)
		(layer "In4.Cu")
	)
	(gr_line
		(start 470.916 -22.098)
		(end 464.693 -22.098)
		(stroke
			(width 0.381)
			(type default)
		)
		(layer "In4.Cu")
	)
	(gr_line
		(start 470.9922 -142.5448)
		(end 456.7428 -142.5448)
		(stroke
			(width 0.381)
			(type default)
		)
		(layer "In4.Cu")
	)
	(gr_line
		(start 471.678 -21.336)
		(end 470.916 -22.098)
		(stroke
			(width 0.381)
			(type default)
		)
		(layer "In4.Cu")
	)
	(gr_arc
		(start 473.749878 -384.999992)
		(mid 474.042771 -385.707097)
		(end 474.749876 -385.99999)
		(stroke
			(width 2.54)
			(type default)
		)
		(layer "In4.Cu")
	)
	(gr_arc
		(start 473.749878 -383.29997)
		(mid 473.456974 -382.592891)
		(end 472.74988 -382.299972)
		(stroke
			(width 2.54)
			(type default)
		)
		(layer "In4.Cu")
	)
	(gr_line
		(start 473.749878 -383.29997)
		(end 473.749878 -384.999992)
		(stroke
			(width 2.54)
			(type default)
		)
		(layer "In4.Cu")
	)
	(gr_line
		(start 474.726 -138.811)
		(end 470.9922 -142.5448)
		(stroke
			(width 0.381)
			(type default)
		)
		(layer "In4.Cu")
	)
	(gr_line
		(start 474.749876 -385.99999)
		(end 487.449876 -385.99999)
		(stroke
			(width 2.54)
			(type default)
		)
		(layer "In4.Cu")
	)
	(gr_line
		(start 476.25 -21.336)
		(end 471.678 -21.336)
		(stroke
			(width 0.381)
			(type default)
		)
		(layer "In4.Cu")
	)
	(gr_arc
		(start 476.667322 -245.45544)
		(mid 477.152335 -245.940834)
		(end 477.637602 -245.455694)
		(stroke
			(width 0.2)
			(type default)
		)
		(layer "In4.Cu")
	)
	(gr_line
		(start 476.667322 -244.312694)
		(end 476.667322 -245.45544)
		(stroke
			(width 0.2)
			(type default)
		)
		(layer "In4.Cu")
	)
	(gr_line
		(start 476.964502 -129.112264)
		(end 478.107502 -129.112264)
		(stroke
			(width 0.2)
			(type default)
		)
		(layer "In4.Cu")
	)
	(gr_line
		(start 476.964502 -14.11224)
		(end 478.107502 -14.11224)
		(stroke
			(width 0.2)
			(type default)
		)
		(layer "In4.Cu")
	)
	(gr_arc
		(start 476.964756 -128.141984)
		(mid 476.479362 -128.626997)
		(end 476.964502 -129.112264)
		(stroke
			(width 0.2)
			(type default)
		)
		(layer "In4.Cu")
	)
	(gr_arc
		(start 476.964756 -13.14196)
		(mid 476.479362 -13.626973)
		(end 476.964502 -14.11224)
		(stroke
			(width 0.2)
			(type default)
		)
		(layer "In4.Cu")
	)
	(gr_line
		(start 477.393 -138.811)
		(end 474.726 -138.811)
		(stroke
			(width 0.381)
			(type default)
		)
		(layer "In4.Cu")
	)
	(gr_line
		(start 477.637602 -245.455694)
		(end 477.637602 -244.312694)
		(stroke
			(width 0.2)
			(type default)
		)
		(layer "In4.Cu")
	)
	(gr_arc
		(start 477.637602 -244.312694)
		(mid 477.152462 -243.827554)
		(end 476.667322 -244.312694)
		(stroke
			(width 0.2)
			(type default)
		)
		(layer "In4.Cu")
	)
	(gr_arc
		(start 478.107502 -129.112264)
		(mid 478.592642 -128.627124)
		(end 478.107502 -128.141984)
		(stroke
			(width 0.2)
			(type default)
		)
		(layer "In4.Cu")
	)
	(gr_line
		(start 478.107502 -128.141984)
		(end 476.964756 -128.141984)
		(stroke
			(width 0.2)
			(type default)
		)
		(layer "In4.Cu")
	)
	(gr_arc
		(start 478.107502 -14.11224)
		(mid 478.592642 -13.6271)
		(end 478.107502 -13.14196)
		(stroke
			(width 0.2)
			(type default)
		)
		(layer "In4.Cu")
	)
	(gr_line
		(start 478.107502 -13.14196)
		(end 476.964756 -13.14196)
		(stroke
			(width 0.2)
			(type default)
		)
		(layer "In4.Cu")
	)
	(gr_line
		(start 478.155 -19.431)
		(end 476.25 -21.336)
		(stroke
			(width 0.381)
			(type default)
		)
		(layer "In4.Cu")
	)
	(gr_line
		(start 478.155 -17.145)
		(end 478.155 -19.431)
		(stroke
			(width 0.381)
			(type default)
		)
		(layer "In4.Cu")
	)
	(gr_line
		(start 478.409 -112.1156)
		(end 478.409 -101.7778)
		(stroke
			(width 0.381)
			(type default)
		)
		(layer "In4.Cu")
	)
	(gr_line
		(start 478.409 -101.7778)
		(end 479.425 -100.7618)
		(stroke
			(width 0.381)
			(type default)
		)
		(layer "In4.Cu")
	)
	(gr_line
		(start 478.536 -133.477)
		(end 479.044 -133.985)
		(stroke
			(width 0.381)
			(type default)
		)
		(layer "In4.Cu")
	)
	(gr_line
		(start 478.536 -131.699)
		(end 478.536 -133.477)
		(stroke
			(width 0.381)
			(type default)
		)
		(layer "In4.Cu")
	)
	(gr_line
		(start 479.044 -137.16)
		(end 477.393 -138.811)
		(stroke
			(width 0.381)
			(type default)
		)
		(layer "In4.Cu")
	)
	(gr_line
		(start 479.044 -133.985)
		(end 479.044 -137.16)
		(stroke
			(width 0.381)
			(type default)
		)
		(layer "In4.Cu")
	)
	(gr_line
		(start 479.044 -16.256)
		(end 478.155 -17.145)
		(stroke
			(width 0.381)
			(type default)
		)
		(layer "In4.Cu")
	)
	(gr_line
		(start 479.298 -130.937)
		(end 478.536 -131.699)
		(stroke
			(width 0.381)
			(type default)
		)
		(layer "In4.Cu")
	)
	(gr_line
		(start 479.425 -100.7618)
		(end 479.425 -24.638)
		(stroke
			(width 0.381)
			(type default)
		)
		(layer "In4.Cu")
	)
	(gr_line
		(start 479.425 -24.638)
		(end 481.711 -22.352)
		(stroke
			(width 0.381)
			(type default)
		)
		(layer "In4.Cu")
	)
	(gr_line
		(start 480.431602 -132.922264)
		(end 481.701602 -132.922264)
		(stroke
			(width 0.2)
			(type default)
		)
		(layer "In4.Cu")
	)
	(gr_line
		(start 480.431602 -17.92224)
		(end 481.701602 -17.92224)
		(stroke
			(width 0.2)
			(type default)
		)
		(layer "In4.Cu")
	)
	(gr_arc
		(start 480.431856 -131.951984)
		(mid 479.946462 -132.436997)
		(end 480.431602 -132.922264)
		(stroke
			(width 0.2)
			(type default)
		)
		(layer "In4.Cu")
	)
	(gr_arc
		(start 480.431856 -16.95196)
		(mid 479.946462 -17.436973)
		(end 480.431602 -17.92224)
		(stroke
			(width 0.2)
			(type default)
		)
		(layer "In4.Cu")
	)
	(gr_arc
		(start 480.854512 -249.385074)
		(mid 481.339652 -249.870214)
		(end 481.824792 -249.385074)
		(stroke
			(width 0.2)
			(type default)
		)
		(layer "In4.Cu")
	)
	(gr_line
		(start 480.854512 -248.115074)
		(end 480.854512 -249.385074)
		(stroke
			(width 0.2)
			(type default)
		)
		(layer "In4.Cu")
	)
	(gr_arc
		(start 481.701602 -132.922264)
		(mid 482.186742 -132.437124)
		(end 481.701602 -131.951984)
		(stroke
			(width 0.2)
			(type default)
		)
		(layer "In4.Cu")
	)
	(gr_line
		(start 481.701602 -131.951984)
		(end 480.431856 -131.951984)
		(stroke
			(width 0.2)
			(type default)
		)
		(layer "In4.Cu")
	)
	(gr_arc
		(start 481.701602 -17.92224)
		(mid 482.186742 -17.4371)
		(end 481.701602 -16.95196)
		(stroke
			(width 0.2)
			(type default)
		)
		(layer "In4.Cu")
	)
	(gr_line
		(start 481.701602 -16.95196)
		(end 480.431856 -16.95196)
		(stroke
			(width 0.2)
			(type default)
		)
		(layer "In4.Cu")
	)
	(gr_line
		(start 481.711 -22.352)
		(end 481.711 -19.812)
		(stroke
			(width 0.381)
			(type default)
		)
		(layer "In4.Cu")
	)
	(gr_line
		(start 481.711 -19.812)
		(end 483.997 -17.526)
		(stroke
			(width 0.381)
			(type default)
		)
		(layer "In4.Cu")
	)
	(gr_line
		(start 481.824792 -249.385074)
		(end 481.824792 -248.115328)
		(stroke
			(width 0.2)
			(type default)
		)
		(layer "In4.Cu")
	)
	(gr_arc
		(start 481.824792 -248.115328)
		(mid 481.339779 -247.629934)
		(end 480.854512 -248.115074)
		(stroke
			(width 0.2)
			(type default)
		)
		(layer "In4.Cu")
	)
	(gr_line
		(start 483.4382 -257.429)
		(end 486.5878 -254.2794)
		(stroke
			(width 0.381)
			(type default)
		)
		(layer "In4.Cu")
	)
	(gr_line
		(start 483.616 -16.256)
		(end 479.044 -16.256)
		(stroke
			(width 0.381)
			(type default)
		)
		(layer "In4.Cu")
	)
	(gr_line
		(start 483.997 -17.526)
		(end 483.997 -16.637)
		(stroke
			(width 0.381)
			(type default)
		)
		(layer "In4.Cu")
	)
	(gr_line
		(start 483.997 -16.637)
		(end 483.616 -16.256)
		(stroke
			(width 0.381)
			(type default)
		)
		(layer "In4.Cu")
	)
	(gr_line
		(start 484.378 -130.937)
		(end 479.298 -130.937)
		(stroke
			(width 0.381)
			(type default)
		)
		(layer "In4.Cu")
	)
	(gr_line
		(start 485.775 -129.54)
		(end 484.378 -130.937)
		(stroke
			(width 0.381)
			(type default)
		)
		(layer "In4.Cu")
	)
	(gr_line
		(start 485.775 -119.4816)
		(end 478.409 -112.1156)
		(stroke
			(width 0.381)
			(type default)
		)
		(layer "In4.Cu")
	)
	(gr_line
		(start 485.775 -119.4816)
		(end 485.775 -129.54)
		(stroke
			(width 0.381)
			(type default)
		)
		(layer "In4.Cu")
	)
	(gr_line
		(start 486.5878 -254.2794)
		(end 486.5878 -217.7034)
		(stroke
			(width 0.381)
			(type default)
		)
		(layer "In4.Cu")
	)
	(gr_line
		(start 486.5878 -217.7034)
		(end 459.5622 -190.6778)
		(stroke
			(width 0.381)
			(type default)
		)
		(layer "In4.Cu")
	)
	(gr_arc
		(start 487.449876 -385.99999)
		(mid 488.156981 -385.707097)
		(end 488.449874 -384.999992)
		(stroke
			(width 2.54)
			(type default)
		)
		(layer "In4.Cu")
	)
	(gr_line
		(start 488.449874 -384.999992)
		(end 488.449874 -372.000018)
		(stroke
			(width 2.54)
			(type default)
		)
		(layer "In4.Cu")
	)
	(gr_arc
		(start 489.450126 -371.00002)
		(mid 488.742881 -371.292834)
		(end 488.449874 -372.000018)
		(stroke
			(width 2.54)
			(type default)
		)
		(layer "In4.Cu")
	)
	(gr_line
		(start 489.450126 -371.00002)
		(end 490.450124 -371.00002)
		(stroke
			(width 2.54)
			(type default)
		)
		(layer "In4.Cu")
	)
	(gr_arc
		(start 490.450124 -371.00002)
		(mid 491.157229 -370.707127)
		(end 491.450122 -370.000022)
		(stroke
			(width 2.54)
			(type default)
		)
		(layer "In4.Cu")
	)
	(gr_line
		(start 490.450124 0)
		(end 311.999884 0)
		(stroke
			(width 2.54)
			(type default)
		)
		(layer "In4.Cu")
	)
	(gr_line
		(start 491.450122 -370.000022)
		(end 491.450122 -0.999998)
		(stroke
			(width 2.54)
			(type default)
		)
		(layer "In4.Cu")
	)
	(gr_arc
		(start 491.450122 -0.999998)
		(mid 491.157229 -0.292893)
		(end 490.450124 0)
		(stroke
			(width 2.54)
			(type default)
		)
		(layer "In4.Cu")
	)
	(gr_line
		(start 32.508952 -249.038872)
		(end 32.508952 -249.385074)
		(stroke
			(width 0.060198)
			(type default)
		)
		(layer "In5.Cu")
	)
	(gr_arc
		(start 32.508952 -248.461022)
		(mid 32.544297 -248.54632)
		(end 32.629602 -248.581672)
		(stroke
			(width 0.060198)
			(type default)
		)
		(layer "In5.Cu")
	)
	(gr_line
		(start 32.508952 -248.115074)
		(end 32.508952 -248.461022)
		(stroke
			(width 0.060198)
			(type default)
		)
		(layer "In5.Cu")
	)
	(gr_line
		(start 32.508952 -134.038848)
		(end 32.508952 -134.38505)
		(stroke
			(width 0.060198)
			(type default)
		)
		(layer "In5.Cu")
	)
	(gr_arc
		(start 32.508952 -133.460998)
		(mid 32.544289 -133.546311)
		(end 32.629602 -133.581648)
		(stroke
			(width 0.060198)
			(type default)
		)
		(layer "In5.Cu")
	)
	(gr_line
		(start 32.508952 -133.11505)
		(end 32.508952 -133.460998)
		(stroke
			(width 0.060198)
			(type default)
		)
		(layer "In5.Cu")
	)
	(gr_line
		(start 32.508952 -19.038824)
		(end 32.508952 -19.385026)
		(stroke
			(width 0.060198)
			(type default)
		)
		(layer "In5.Cu")
	)
	(gr_arc
		(start 32.508952 -18.460974)
		(mid 32.54428 -18.546303)
		(end 32.629602 -18.581624)
		(stroke
			(width 0.060198)
			(type default)
		)
		(layer "In5.Cu")
	)
	(gr_line
		(start 32.508952 -18.115026)
		(end 32.508952 -18.460974)
		(stroke
			(width 0.060198)
			(type default)
		)
		(layer "In5.Cu")
	)
	(gr_arc
		(start 32.629602 -248.918222)
		(mid 32.54429 -248.95356)
		(end 32.508952 -249.038872)
		(stroke
			(width 0.060198)
			(type default)
		)
		(layer "In5.Cu")
	)
	(gr_arc
		(start 32.629602 -133.918198)
		(mid 32.54429 -133.953536)
		(end 32.508952 -134.038848)
		(stroke
			(width 0.060198)
			(type default)
		)
		(layer "In5.Cu")
	)
	(gr_arc
		(start 32.629602 -18.918174)
		(mid 32.54429 -18.953512)
		(end 32.508952 -19.038824)
		(stroke
			(width 0.060198)
			(type default)
		)
		(layer "In5.Cu")
	)
	(gr_line
		(start 34.76752 -18.581624)
		(end 34.817304 -18.614136)
		(stroke
			(width 0.060198)
			(type default)
		)
		(layer "In5.Cu")
	)
	(gr_line
		(start 34.976054 -133.581648)
		(end 35.014662 -133.602476)
		(stroke
			(width 0.060198)
			(type default)
		)
		(layer "In5.Cu")
	)
	(gr_line
		(start 37.25291 -135.19531)
		(end 37.338508 -135.48106)
		(stroke
			(width 0.060198)
			(type default)
		)
		(layer "In5.Cu")
	)
	(gr_line
		(start 37.338508 -135.48106)
		(end 37.657024 -135.653018)
		(stroke
			(width 0.060198)
			(type default)
		)
		(layer "In5.Cu")
	)
	(gr_line
		(start 37.44722 -134.914894)
		(end 38.068758 -135.250428)
		(stroke
			(width 0.060198)
			(type default)
		)
		(layer "In5.Cu")
	)
	(gr_line
		(start 37.657024 -135.653018)
		(end 37.943028 -135.56742)
		(stroke
			(width 0.060198)
			(type default)
		)
		(layer "In5.Cu")
	)
	(gr_line
		(start 38.265608 -135.74141)
		(end 38.351206 -136.027414)
		(stroke
			(width 0.060198)
			(type default)
		)
		(layer "In5.Cu")
	)
	(gr_line
		(start 38.351206 -136.027414)
		(end 38.669722 -136.199118)
		(stroke
			(width 0.060198)
			(type default)
		)
		(layer "In5.Cu")
	)
	(gr_line
		(start 38.460426 -135.461502)
		(end 39.082472 -135.797036)
		(stroke
			(width 0.060198)
			(type default)
		)
		(layer "In5.Cu")
	)
	(gr_line
		(start 38.669722 -136.199118)
		(end 38.955472 -136.113774)
		(stroke
			(width 0.060198)
			(type default)
		)
		(layer "In5.Cu")
	)
	(gr_line
		(start 39.278306 -136.287764)
		(end 39.36365 -136.573768)
		(stroke
			(width 0.060198)
			(type default)
		)
		(layer "In5.Cu")
	)
	(gr_line
		(start 39.36365 -136.573768)
		(end 39.68242 -136.745472)
		(stroke
			(width 0.060198)
			(type default)
		)
		(layer "In5.Cu")
	)
	(gr_line
		(start 39.472108 -136.007094)
		(end 40.095424 -136.34339)
		(stroke
			(width 0.060198)
			(type default)
		)
		(layer "In5.Cu")
	)
	(gr_line
		(start 39.68242 -136.745472)
		(end 39.96817 -136.660128)
		(stroke
			(width 0.060198)
			(type default)
		)
		(layer "In5.Cu")
	)
	(gr_line
		(start 40.729916 -22.87778)
		(end 40.79113 -23.169626)
		(stroke
			(width 0.060198)
			(type default)
		)
		(layer "In5.Cu")
	)
	(gr_line
		(start 40.79113 -23.169626)
		(end 41.094406 -23.367492)
		(stroke
			(width 0.060198)
			(type default)
		)
		(layer "In5.Cu")
	)
	(gr_line
		(start 40.948102 -22.615652)
		(end 41.538144 -23.000716)
		(stroke
			(width 0.060198)
			(type default)
		)
		(layer "In5.Cu")
	)
	(gr_line
		(start 41.094406 -23.367492)
		(end 41.386252 -23.306278)
		(stroke
			(width 0.060198)
			(type default)
		)
		(layer "In5.Cu")
	)
	(gr_line
		(start 41.693592 -23.506938)
		(end 41.754806 -23.79853)
		(stroke
			(width 0.060198)
			(type default)
		)
		(layer "In5.Cu")
	)
	(gr_line
		(start 41.754806 -23.79853)
		(end 42.057828 -23.996396)
		(stroke
			(width 0.060198)
			(type default)
		)
		(layer "In5.Cu")
	)
	(gr_line
		(start 41.913302 -23.245572)
		(end 42.500804 -23.629112)
		(stroke
			(width 0.060198)
			(type default)
		)
		(layer "In5.Cu")
	)
	(gr_line
		(start 42.057828 -23.996396)
		(end 42.349674 -23.935182)
		(stroke
			(width 0.060198)
			(type default)
		)
		(layer "In5.Cu")
	)
	(gr_line
		(start 42.657014 -24.135588)
		(end 42.718482 -24.427434)
		(stroke
			(width 0.060198)
			(type default)
		)
		(layer "In5.Cu")
	)
	(gr_line
		(start 42.718482 -24.427434)
		(end 43.021504 -24.6253)
		(stroke
			(width 0.060198)
			(type default)
		)
		(layer "In5.Cu")
	)
	(gr_line
		(start 42.874692 -23.872952)
		(end 43.466258 -24.259032)
		(stroke
			(width 0.060198)
			(type default)
		)
		(layer "In5.Cu")
	)
	(gr_line
		(start 43.021504 -24.6253)
		(end 43.31335 -24.564086)
		(stroke
			(width 0.060198)
			(type default)
		)
		(layer "In5.Cu")
	)
	(gr_line
		(start 50.793904 -142.498064)
		(end 50.801016 -142.501874)
		(stroke
			(width 0.060198)
			(type default)
		)
		(layer "In5.Cu")
	)
	(gr_line
		(start 50.801016 -142.501874)
		(end 50.809144 -142.503652)
		(stroke
			(width 0.060198)
			(type default)
		)
		(layer "In5.Cu")
	)
	(gr_line
		(start 61.101732 -35.768788)
		(end 61.126878 -35.785044)
		(stroke
			(width 0.060198)
			(type default)
		)
		(layer "In5.Cu")
	)
	(gr_line
		(start 61.126878 -35.785044)
		(end 61.143388 -35.810698)
		(stroke
			(width 0.060198)
			(type default)
		)
		(layer "In5.Cu")
	)
	(gr_line
		(start 64.0588 -249.038872)
		(end 64.0588 -249.385074)
		(stroke
			(width 0.060198)
			(type default)
		)
		(layer "In5.Cu")
	)
	(gr_arc
		(start 64.0588 -248.461022)
		(mid 64.094142 -248.546338)
		(end 64.17945 -248.581672)
		(stroke
			(width 0.060198)
			(type default)
		)
		(layer "In5.Cu")
	)
	(gr_line
		(start 64.0588 -248.115074)
		(end 64.0588 -248.461022)
		(stroke
			(width 0.060198)
			(type default)
		)
		(layer "In5.Cu")
	)
	(gr_line
		(start 64.0588 -134.038848)
		(end 64.0588 -134.38505)
		(stroke
			(width 0.060198)
			(type default)
		)
		(layer "In5.Cu")
	)
	(gr_arc
		(start 64.0588 -133.460998)
		(mid 64.094134 -133.546329)
		(end 64.17945 -133.581648)
		(stroke
			(width 0.060198)
			(type default)
		)
		(layer "In5.Cu")
	)
	(gr_line
		(start 64.0588 -133.11505)
		(end 64.0588 -133.460998)
		(stroke
			(width 0.060198)
			(type default)
		)
		(layer "In5.Cu")
	)
	(gr_line
		(start 64.0588 -19.038824)
		(end 64.0588 -19.385026)
		(stroke
			(width 0.060198)
			(type default)
		)
		(layer "In5.Cu")
	)
	(gr_arc
		(start 64.0588 -18.460974)
		(mid 64.094125 -18.546321)
		(end 64.17945 -18.581624)
		(stroke
			(width 0.060198)
			(type default)
		)
		(layer "In5.Cu")
	)
	(gr_line
		(start 64.0588 -18.115026)
		(end 64.0588 -18.460974)
		(stroke
			(width 0.060198)
			(type default)
		)
		(layer "In5.Cu")
	)
	(gr_arc
		(start 64.17945 -248.918222)
		(mid 64.094138 -248.95356)
		(end 64.0588 -249.038872)
		(stroke
			(width 0.060198)
			(type default)
		)
		(layer "In5.Cu")
	)
	(gr_arc
		(start 64.17945 -133.918198)
		(mid 64.094138 -133.953536)
		(end 64.0588 -134.038848)
		(stroke
			(width 0.060198)
			(type default)
		)
		(layer "In5.Cu")
	)
	(gr_arc
		(start 64.17945 -18.918174)
		(mid 64.094138 -18.953512)
		(end 64.0588 -19.038824)
		(stroke
			(width 0.060198)
			(type default)
		)
		(layer "In5.Cu")
	)
	(gr_line
		(start 65.38722 -133.581648)
		(end 65.404746 -133.587998)
		(stroke
			(width 0.060198)
			(type default)
		)
		(layer "In5.Cu")
	)
	(gr_line
		(start 67.842638 -18.581624)
		(end 67.894454 -18.616422)
		(stroke
			(width 0.060198)
			(type default)
		)
		(layer "In5.Cu")
	)
	(gr_line
		(start 68.346066 -19.330162)
		(end 68.402962 -19.623278)
		(stroke
			(width 0.060198)
			(type default)
		)
		(layer "In5.Cu")
	)
	(gr_line
		(start 68.402962 -19.623278)
		(end 68.70319 -19.825462)
		(stroke
			(width 0.060198)
			(type default)
		)
		(layer "In5.Cu")
	)
	(gr_line
		(start 68.5673 -19.07032)
		(end 68.649596 -19.125692)
		(stroke
			(width 0.060198)
			(type default)
		)
		(layer "In5.Cu")
	)
	(gr_line
		(start 68.649596 -19.125692)
		(end 68.64985 -19.1262)
		(stroke
			(width 0.060198)
			(type default)
		)
		(layer "In5.Cu")
	)
	(gr_line
		(start 68.64985 -19.1262)
		(end 69.15404 -19.466306)
		(stroke
			(width 0.060198)
			(type default)
		)
		(layer "In5.Cu")
	)
	(gr_line
		(start 68.70319 -19.825462)
		(end 68.996052 -19.76882)
		(stroke
			(width 0.060198)
			(type default)
		)
		(layer "In5.Cu")
	)
	(gr_line
		(start 68.857622 -135.203946)
		(end 68.97751 -135.461248)
		(stroke
			(width 0.060198)
			(type default)
		)
		(layer "In5.Cu")
	)
	(gr_line
		(start 68.97751 -135.461248)
		(end 69.31787 -135.584692)
		(stroke
			(width 0.060198)
			(type default)
		)
		(layer "In5.Cu")
	)
	(gr_line
		(start 69.00926 -134.89813)
		(end 69.65569 -135.13308)
		(stroke
			(width 0.060198)
			(type default)
		)
		(layer "In5.Cu")
	)
	(gr_line
		(start 69.299836 -19.973798)
		(end 69.356986 -20.26666)
		(stroke
			(width 0.060198)
			(type default)
		)
		(layer "In5.Cu")
	)
	(gr_line
		(start 69.31787 -135.584692)
		(end 69.575172 -135.464804)
		(stroke
			(width 0.060198)
			(type default)
		)
		(layer "In5.Cu")
	)
	(gr_line
		(start 69.356986 -20.26666)
		(end 69.65696 -20.469098)
		(stroke
			(width 0.060198)
			(type default)
		)
		(layer "In5.Cu")
	)
	(gr_line
		(start 69.520562 -19.713448)
		(end 70.108572 -20.109942)
		(stroke
			(width 0.060198)
			(type default)
		)
		(layer "In5.Cu")
	)
	(gr_line
		(start 69.65696 -20.469098)
		(end 69.949822 -20.412202)
		(stroke
			(width 0.060198)
			(type default)
		)
		(layer "In5.Cu")
	)
	(gr_line
		(start 69.919596 -135.590026)
		(end 70.039992 -135.847328)
		(stroke
			(width 0.060198)
			(type default)
		)
		(layer "In5.Cu")
	)
	(gr_line
		(start 70.039992 -135.847328)
		(end 70.380098 -135.970772)
		(stroke
			(width 0.060198)
			(type default)
		)
		(layer "In5.Cu")
	)
	(gr_line
		(start 70.070218 -135.283702)
		(end 70.71868 -135.519414)
		(stroke
			(width 0.060198)
			(type default)
		)
		(layer "In5.Cu")
	)
	(gr_line
		(start 70.254114 -20.61718)
		(end 70.310756 -20.910042)
		(stroke
			(width 0.060198)
			(type default)
		)
		(layer "In5.Cu")
	)
	(gr_line
		(start 70.310756 -20.910042)
		(end 70.610984 -21.11248)
		(stroke
			(width 0.060198)
			(type default)
		)
		(layer "In5.Cu")
	)
	(gr_line
		(start 70.380098 -135.970772)
		(end 70.6374 -135.850884)
		(stroke
			(width 0.060198)
			(type default)
		)
		(layer "In5.Cu")
	)
	(gr_line
		(start 70.474586 -20.35683)
		(end 71.062596 -20.753324)
		(stroke
			(width 0.060198)
			(type default)
		)
		(layer "In5.Cu")
	)
	(gr_line
		(start 70.610984 -21.11248)
		(end 70.903592 -21.055584)
		(stroke
			(width 0.060198)
			(type default)
		)
		(layer "In5.Cu")
	)
	(gr_line
		(start 70.981824 -135.976106)
		(end 71.10222 -136.233408)
		(stroke
			(width 0.060198)
			(type default)
		)
		(layer "In5.Cu")
	)
	(gr_line
		(start 71.10222 -136.233408)
		(end 71.442326 -136.357106)
		(stroke
			(width 0.060198)
			(type default)
		)
		(layer "In5.Cu")
	)
	(gr_line
		(start 71.13143 -135.669274)
		(end 71.781924 -135.905748)
		(stroke
			(width 0.060198)
			(type default)
		)
		(layer "In5.Cu")
	)
	(gr_line
		(start 71.442326 -136.357106)
		(end 71.699628 -136.236964)
		(stroke
			(width 0.060198)
			(type default)
		)
		(layer "In5.Cu")
	)
	(gr_line
		(start 83.704176 -71.174356)
		(end 83.720178 -71.199248)
		(stroke
			(width 0.060198)
			(type default)
		)
		(layer "In5.Cu")
	)
	(gr_line
		(start 83.720178 -71.199248)
		(end 83.745832 -71.216012)
		(stroke
			(width 0.060198)
			(type default)
		)
		(layer "In5.Cu")
	)
	(gr_line
		(start 90.031062 -145.928588)
		(end 90.04808 -145.939764)
		(stroke
			(width 0.060198)
			(type default)
		)
		(layer "In5.Cu")
	)
	(gr_line
		(start 90.04808 -145.939764)
		(end 90.067892 -145.943828)
		(stroke
			(width 0.060198)
			(type default)
		)
		(layer "In5.Cu")
	)
	(gr_line
		(start 91.50477 -34.54273)
		(end 91.52509 -34.556446)
		(stroke
			(width 0.060198)
			(type default)
		)
		(layer "In5.Cu")
	)
	(gr_line
		(start 91.52509 -34.556446)
		(end 91.538806 -34.576766)
		(stroke
			(width 0.060198)
			(type default)
		)
		(layer "In5.Cu")
	)
	(gr_line
		(start 95.608902 -249.038872)
		(end 95.608902 -249.385074)
		(stroke
			(width 0.060198)
			(type default)
		)
		(layer "In5.Cu")
	)
	(gr_arc
		(start 95.608902 -248.461022)
		(mid 95.644244 -248.546337)
		(end 95.729552 -248.581672)
		(stroke
			(width 0.060198)
			(type default)
		)
		(layer "In5.Cu")
	)
	(gr_line
		(start 95.608902 -248.115074)
		(end 95.608902 -248.461022)
		(stroke
			(width 0.060198)
			(type default)
		)
		(layer "In5.Cu")
	)
	(gr_line
		(start 95.608902 -134.038848)
		(end 95.608902 -134.38505)
		(stroke
			(width 0.060198)
			(type default)
		)
		(layer "In5.Cu")
	)
	(gr_arc
		(start 95.608902 -133.460998)
		(mid 95.644236 -133.546329)
		(end 95.729552 -133.581648)
		(stroke
			(width 0.060198)
			(type default)
		)
		(layer "In5.Cu")
	)
	(gr_line
		(start 95.608902 -133.11505)
		(end 95.608902 -133.460998)
		(stroke
			(width 0.060198)
			(type default)
		)
		(layer "In5.Cu")
	)
	(gr_line
		(start 95.608902 -19.038824)
		(end 95.608902 -19.385026)
		(stroke
			(width 0.060198)
			(type default)
		)
		(layer "In5.Cu")
	)
	(gr_arc
		(start 95.608902 -18.460974)
		(mid 95.644227 -18.54632)
		(end 95.729552 -18.581624)
		(stroke
			(width 0.060198)
			(type default)
		)
		(layer "In5.Cu")
	)
	(gr_line
		(start 95.608902 -18.115026)
		(end 95.608902 -18.460974)
		(stroke
			(width 0.060198)
			(type default)
		)
		(layer "In5.Cu")
	)
	(gr_arc
		(start 95.729552 -248.918222)
		(mid 95.64424 -248.95356)
		(end 95.608902 -249.038872)
		(stroke
			(width 0.060198)
			(type default)
		)
		(layer "In5.Cu")
	)
	(gr_arc
		(start 95.729552 -133.918198)
		(mid 95.64424 -133.953536)
		(end 95.608902 -134.038848)
		(stroke
			(width 0.060198)
			(type default)
		)
		(layer "In5.Cu")
	)
	(gr_arc
		(start 95.729552 -18.918174)
		(mid 95.64424 -18.953512)
		(end 95.608902 -19.038824)
		(stroke
			(width 0.060198)
			(type default)
		)
		(layer "In5.Cu")
	)
	(gr_line
		(start 96.794574 -133.581648)
		(end 96.8121 -133.588506)
		(stroke
			(width 0.060198)
			(type default)
		)
		(layer "In5.Cu")
	)
	(gr_line
		(start 97.129854 -18.581624)
		(end 97.148904 -18.588736)
		(stroke
			(width 0.060198)
			(type default)
		)
		(layer "In5.Cu")
	)
	(gr_line
		(start 97.775268 -18.826226)
		(end 97.841562 -18.851372)
		(stroke
			(width 0.060198)
			(type default)
		)
		(layer "In5.Cu")
	)
	(gr_line
		(start 97.841562 -18.851372)
		(end 97.88017 -18.910808)
		(stroke
			(width 0.060198)
			(type default)
		)
		(layer "In5.Cu")
	)
	(gr_line
		(start 98.331528 -19.606768)
		(end 98.344228 -19.626326)
		(stroke
			(width 0.060198)
			(type default)
		)
		(layer "In5.Cu")
	)
	(gr_line
		(start 98.344228 -19.626326)
		(end 98.349054 -19.648932)
		(stroke
			(width 0.060198)
			(type default)
		)
		(layer "In5.Cu")
	)
	(gr_line
		(start 99.164648 -81.229454)
		(end 99.181666 -81.24063)
		(stroke
			(width 0.060198)
			(type default)
		)
		(layer "In5.Cu")
	)
	(gr_line
		(start 99.181666 -81.24063)
		(end 99.201478 -81.244694)
		(stroke
			(width 0.060198)
			(type default)
		)
		(layer "In5.Cu")
	)
	(gr_line
		(start 99.544632 -26.890726)
		(end 99.548696 -26.910538)
		(stroke
			(width 0.060198)
			(type default)
		)
		(layer "In5.Cu")
	)
	(gr_line
		(start 99.548696 -26.910538)
		(end 99.559872 -26.927556)
		(stroke
			(width 0.060198)
			(type default)
		)
		(layer "In5.Cu")
	)
	(gr_line
		(start 100.45065 -28.67279)
		(end 100.509832 -28.395168)
		(stroke
			(width 0.060198)
			(type default)
		)
		(layer "In5.Cu")
	)
	(gr_line
		(start 100.45065 -28.67279)
		(end 100.647754 -28.976574)
		(stroke
			(width 0.060198)
			(type default)
		)
		(layer "In5.Cu")
	)
	(gr_line
		(start 100.647754 -28.976574)
		(end 100.92563 -29.035502)
		(stroke
			(width 0.060198)
			(type default)
		)
		(layer "In5.Cu")
	)
	(gr_line
		(start 100.815902 -28.244292)
		(end 101.188266 -28.817824)
		(stroke
			(width 0.060198)
			(type default)
		)
		(layer "In5.Cu")
	)
	(gr_line
		(start 101.066092 -29.620718)
		(end 101.125274 -29.343096)
		(stroke
			(width 0.060198)
			(type default)
		)
		(layer "In5.Cu")
	)
	(gr_line
		(start 101.066092 -29.620718)
		(end 101.263196 -29.924502)
		(stroke
			(width 0.060198)
			(type default)
		)
		(layer "In5.Cu")
	)
	(gr_line
		(start 101.263196 -29.924502)
		(end 101.541072 -29.98343)
		(stroke
			(width 0.060198)
			(type default)
		)
		(layer "In5.Cu")
	)
	(gr_line
		(start 101.43109 -29.191712)
		(end 101.8032 -29.765244)
		(stroke
			(width 0.060198)
			(type default)
		)
		(layer "In5.Cu")
	)
	(gr_line
		(start 101.681788 -30.5689)
		(end 101.740716 -30.291024)
		(stroke
			(width 0.060198)
			(type default)
		)
		(layer "In5.Cu")
	)
	(gr_line
		(start 101.681788 -30.5689)
		(end 101.878892 -30.87243)
		(stroke
			(width 0.060198)
			(type default)
		)
		(layer "In5.Cu")
	)
	(gr_line
		(start 101.878892 -30.87243)
		(end 102.156514 -30.931358)
		(stroke
			(width 0.060198)
			(type default)
		)
		(layer "In5.Cu")
	)
	(gr_line
		(start 102.046786 -30.140148)
		(end 102.41915 -30.71368)
		(stroke
			(width 0.060198)
			(type default)
		)
		(layer "In5.Cu")
	)
	(gr_line
		(start 105.790492 -234.700572)
		(end 105.887266 -234.68203)
		(stroke
			(width 0.060198)
			(type default)
		)
		(layer "In5.Cu")
	)
	(gr_line
		(start 105.816654 -235.040932)
		(end 106.063288 -235.208318)
		(stroke
			(width 0.060198)
			(type default)
		)
		(layer "In5.Cu")
	)
	(gr_line
		(start 105.887266 -234.681776)
		(end 105.887266 -234.68203)
		(stroke
			(width 0.060198)
			(type default)
		)
		(layer "In5.Cu")
	)
	(gr_line
		(start 105.887266 -234.681776)
		(end 106.486452 -234.566714)
		(stroke
			(width 0.060198)
			(type default)
		)
		(layer "In5.Cu")
	)
	(gr_line
		(start 106.063288 -235.208318)
		(end 106.418888 -235.139992)
		(stroke
			(width 0.060198)
			(type default)
		)
		(layer "In5.Cu")
	)
	(gr_line
		(start 106.418888 -235.139992)
		(end 106.586274 -234.89285)
		(stroke
			(width 0.060198)
			(type default)
		)
		(layer "In5.Cu")
	)
	(gr_line
		(start 106.917998 -234.48391)
		(end 107.61726 -234.349544)
		(stroke
			(width 0.060198)
			(type default)
		)
		(layer "In5.Cu")
	)
	(gr_line
		(start 106.946192 -234.823762)
		(end 107.193334 -234.991402)
		(stroke
			(width 0.060198)
			(type default)
		)
		(layer "In5.Cu")
	)
	(gr_line
		(start 107.193334 -234.991402)
		(end 107.54868 -234.923076)
		(stroke
			(width 0.060198)
			(type default)
		)
		(layer "In5.Cu")
	)
	(gr_line
		(start 107.54868 -234.923076)
		(end 107.71632 -234.675934)
		(stroke
			(width 0.060198)
			(type default)
		)
		(layer "In5.Cu")
	)
	(gr_line
		(start 108.049822 -234.26674)
		(end 108.746798 -234.132882)
		(stroke
			(width 0.060198)
			(type default)
		)
		(layer "In5.Cu")
	)
	(gr_line
		(start 108.076238 -234.606846)
		(end 108.32338 -234.774486)
		(stroke
			(width 0.060198)
			(type default)
		)
		(layer "In5.Cu")
	)
	(gr_line
		(start 108.32338 -234.774486)
		(end 108.678726 -234.70616)
		(stroke
			(width 0.060198)
			(type default)
		)
		(layer "In5.Cu")
	)
	(gr_line
		(start 108.678726 -234.70616)
		(end 108.846366 -234.459018)
		(stroke
			(width 0.060198)
			(type default)
		)
		(layer "In5.Cu")
	)
	(gr_line
		(start 120.193054 -77.660754)
		(end 120.208802 -77.684122)
		(stroke
			(width 0.060198)
			(type default)
		)
		(layer "In5.Cu")
	)
	(gr_line
		(start 120.208802 -77.684122)
		(end 120.232424 -77.699616)
		(stroke
			(width 0.060198)
			(type default)
		)
		(layer "In5.Cu")
	)
	(gr_line
		(start 120.911874 -238.121444)
		(end 121.599706 -237.993174)
		(stroke
			(width 0.060198)
			(type default)
		)
		(layer "In5.Cu")
	)
	(gr_line
		(start 120.941084 -238.461042)
		(end 121.176034 -238.622078)
		(stroke
			(width 0.060198)
			(type default)
		)
		(layer "In5.Cu")
	)
	(gr_line
		(start 121.176034 -238.622078)
		(end 121.531888 -238.555784)
		(stroke
			(width 0.060198)
			(type default)
		)
		(layer "In5.Cu")
	)
	(gr_line
		(start 121.531888 -238.555784)
		(end 121.693178 -238.320834)
		(stroke
			(width 0.060198)
			(type default)
		)
		(layer "In5.Cu")
	)
	(gr_line
		(start 122.023632 -237.91418)
		(end 122.70867 -237.786672)
		(stroke
			(width 0.060198)
			(type default)
		)
		(layer "In5.Cu")
	)
	(gr_line
		(start 122.052588 -238.253778)
		(end 122.287284 -238.414814)
		(stroke
			(width 0.060198)
			(type default)
		)
		(layer "In5.Cu")
	)
	(gr_line
		(start 122.287284 -238.414814)
		(end 122.643138 -238.34852)
		(stroke
			(width 0.060198)
			(type default)
		)
		(layer "In5.Cu")
	)
	(gr_line
		(start 122.643138 -238.34852)
		(end 122.80392 -238.11357)
		(stroke
			(width 0.060198)
			(type default)
		)
		(layer "In5.Cu")
	)
	(gr_line
		(start 123.132088 -237.707424)
		(end 123.820936 -237.5789)
		(stroke
			(width 0.060198)
			(type default)
		)
		(layer "In5.Cu")
	)
	(gr_line
		(start 123.16333 -238.046768)
		(end 123.39828 -238.207804)
		(stroke
			(width 0.060198)
			(type default)
		)
		(layer "In5.Cu")
	)
	(gr_line
		(start 123.39828 -238.207804)
		(end 123.754134 -238.141256)
		(stroke
			(width 0.060198)
			(type default)
		)
		(layer "In5.Cu")
	)
	(gr_line
		(start 123.754134 -238.141256)
		(end 123.91517 -237.90656)
		(stroke
			(width 0.060198)
			(type default)
		)
		(layer "In5.Cu")
	)
	(gr_line
		(start 123.934474 -147.675092)
		(end 123.951492 -147.686268)
		(stroke
			(width 0.060198)
			(type default)
		)
		(layer "In5.Cu")
	)
	(gr_line
		(start 123.951492 -147.686268)
		(end 123.971304 -147.690332)
		(stroke
			(width 0.060198)
			(type default)
		)
		(layer "In5.Cu")
	)
	(gr_line
		(start 127.15875 -249.038872)
		(end 127.15875 -249.385074)
		(stroke
			(width 0.060198)
			(type default)
		)
		(layer "In5.Cu")
	)
	(gr_arc
		(start 127.15875 -248.461022)
		(mid 127.194095 -248.54632)
		(end 127.2794 -248.581672)
		(stroke
			(width 0.060198)
			(type default)
		)
		(layer "In5.Cu")
	)
	(gr_line
		(start 127.15875 -248.115074)
		(end 127.15875 -248.461022)
		(stroke
			(width 0.060198)
			(type default)
		)
		(layer "In5.Cu")
	)
	(gr_line
		(start 127.15875 -134.038848)
		(end 127.15875 -134.38505)
		(stroke
			(width 0.060198)
			(type default)
		)
		(layer "In5.Cu")
	)
	(gr_arc
		(start 127.15875 -133.460998)
		(mid 127.194087 -133.546312)
		(end 127.2794 -133.581648)
		(stroke
			(width 0.060198)
			(type default)
		)
		(layer "In5.Cu")
	)
	(gr_line
		(start 127.15875 -133.11505)
		(end 127.15875 -133.460998)
		(stroke
			(width 0.060198)
			(type default)
		)
		(layer "In5.Cu")
	)
	(gr_line
		(start 127.15875 -19.038824)
		(end 127.15875 -19.385026)
		(stroke
			(width 0.060198)
			(type default)
		)
		(layer "In5.Cu")
	)
	(gr_arc
		(start 127.15875 -18.460974)
		(mid 127.194078 -18.546303)
		(end 127.2794 -18.581624)
		(stroke
			(width 0.060198)
			(type default)
		)
		(layer "In5.Cu")
	)
	(gr_line
		(start 127.15875 -18.115026)
		(end 127.15875 -18.460974)
		(stroke
			(width 0.060198)
			(type default)
		)
		(layer "In5.Cu")
	)
	(gr_arc
		(start 127.2794 -248.918222)
		(mid 127.194088 -248.95356)
		(end 127.15875 -249.038872)
		(stroke
			(width 0.060198)
			(type default)
		)
		(layer "In5.Cu")
	)
	(gr_arc
		(start 127.2794 -133.918198)
		(mid 127.194088 -133.953536)
		(end 127.15875 -134.038848)
		(stroke
			(width 0.060198)
			(type default)
		)
		(layer "In5.Cu")
	)
	(gr_arc
		(start 127.2794 -18.918174)
		(mid 127.194088 -18.953512)
		(end 127.15875 -19.038824)
		(stroke
			(width 0.060198)
			(type default)
		)
		(layer "In5.Cu")
	)
	(gr_line
		(start 129.07772 -133.581648)
		(end 129.118614 -133.604508)
		(stroke
			(width 0.060198)
			(type default)
		)
		(layer "In5.Cu")
	)
	(gr_line
		(start 129.449322 -18.581624)
		(end 129.455926 -18.583656)
		(stroke
			(width 0.060198)
			(type default)
		)
		(layer "In5.Cu")
	)
	(gr_line
		(start 130.347466 -18.848578)
		(end 130.426968 -18.8722)
		(stroke
			(width 0.060198)
			(type default)
		)
		(layer "In5.Cu")
	)
	(gr_line
		(start 130.426968 -18.8722)
		(end 130.472434 -18.94205)
		(stroke
			(width 0.060198)
			(type default)
		)
		(layer "In5.Cu")
	)
	(gr_line
		(start 132.34797 -24.387302)
		(end 132.423154 -24.741124)
		(stroke
			(width 0.060198)
			(type default)
		)
		(layer "In5.Cu")
	)
	(gr_line
		(start 132.34797 -24.387302)
		(end 132.51053 -24.136858)
		(stroke
			(width 0.060198)
			(type default)
		)
		(layer "In5.Cu")
	)
	(gr_line
		(start 132.364988 -21.857716)
		(end 132.376164 -21.874734)
		(stroke
			(width 0.060198)
			(type default)
		)
		(layer "In5.Cu")
	)
	(gr_line
		(start 132.376164 -21.874734)
		(end 132.380228 -21.894546)
		(stroke
			(width 0.060198)
			(type default)
		)
		(layer "In5.Cu")
	)
	(gr_line
		(start 132.423154 -24.741124)
		(end 132.673598 -24.903684)
		(stroke
			(width 0.060198)
			(type default)
		)
		(layer "In5.Cu")
	)
	(gr_line
		(start 132.587238 -25.512776)
		(end 132.662422 -25.866598)
		(stroke
			(width 0.060198)
			(type default)
		)
		(layer "In5.Cu")
	)
	(gr_line
		(start 132.587238 -25.512776)
		(end 132.749798 -25.262332)
		(stroke
			(width 0.060198)
			(type default)
		)
		(layer "In5.Cu")
	)
	(gr_line
		(start 132.662422 -25.866598)
		(end 132.912866 -26.029412)
		(stroke
			(width 0.060198)
			(type default)
		)
		(layer "In5.Cu")
	)
	(gr_line
		(start 132.826252 -26.63825)
		(end 132.90169 -26.992326)
		(stroke
			(width 0.060198)
			(type default)
		)
		(layer "In5.Cu")
	)
	(gr_line
		(start 132.826252 -26.63825)
		(end 132.988812 -26.387552)
		(stroke
			(width 0.060198)
			(type default)
		)
		(layer "In5.Cu")
	)
	(gr_line
		(start 132.850128 -24.103584)
		(end 132.997702 -24.797766)
		(stroke
			(width 0.060198)
			(type default)
		)
		(layer "In5.Cu")
	)
	(gr_line
		(start 132.90169 -26.992326)
		(end 133.15188 -27.154886)
		(stroke
			(width 0.060198)
			(type default)
		)
		(layer "In5.Cu")
	)
	(gr_line
		(start 133.04901 -149.62251)
		(end 133.21157 -149.8727)
		(stroke
			(width 0.060198)
			(type default)
		)
		(layer "In5.Cu")
	)
	(gr_line
		(start 133.089396 -25.22982)
		(end 133.236716 -25.922732)
		(stroke
			(width 0.060198)
			(type default)
		)
		(layer "In5.Cu")
	)
	(gr_line
		(start 133.15569 -149.298406)
		(end 133.849364 -149.445726)
		(stroke
			(width 0.060198)
			(type default)
		)
		(layer "In5.Cu")
	)
	(gr_line
		(start 133.21157 -149.8727)
		(end 133.565646 -149.947884)
		(stroke
			(width 0.060198)
			(type default)
		)
		(layer "In5.Cu")
	)
	(gr_line
		(start 133.32841 -26.354532)
		(end 133.47573 -27.047444)
		(stroke
			(width 0.060198)
			(type default)
		)
		(layer "In5.Cu")
	)
	(gr_line
		(start 133.565646 -149.947884)
		(end 133.815836 -149.785324)
		(stroke
			(width 0.060198)
			(type default)
		)
		(layer "In5.Cu")
	)
	(gr_line
		(start 134.174484 -149.861524)
		(end 134.337044 -150.111968)
		(stroke
			(width 0.060198)
			(type default)
		)
		(layer "In5.Cu")
	)
	(gr_line
		(start 134.280656 -149.53742)
		(end 134.976108 -149.685248)
		(stroke
			(width 0.060198)
			(type default)
		)
		(layer "In5.Cu")
	)
	(gr_line
		(start 134.337044 -150.111968)
		(end 134.69112 -150.187152)
		(stroke
			(width 0.060198)
			(type default)
		)
		(layer "In5.Cu")
	)
	(gr_line
		(start 134.550404 -88.414606)
		(end 134.570216 -88.41867)
		(stroke
			(width 0.060198)
			(type default)
		)
		(layer "In5.Cu")
	)
	(gr_line
		(start 134.570216 -88.41867)
		(end 134.587234 -88.429846)
		(stroke
			(width 0.060198)
			(type default)
		)
		(layer "In5.Cu")
	)
	(gr_line
		(start 134.69112 -150.187152)
		(end 134.94131 -150.024592)
		(stroke
			(width 0.060198)
			(type default)
		)
		(layer "In5.Cu")
	)
	(gr_line
		(start 135.299958 -150.100792)
		(end 135.454644 -150.339044)
		(stroke
			(width 0.060198)
			(type default)
		)
		(layer "In5.Cu")
	)
	(gr_line
		(start 135.4074 -149.776942)
		(end 136.080246 -149.919944)
		(stroke
			(width 0.060198)
			(type default)
		)
		(layer "In5.Cu")
	)
	(gr_line
		(start 135.454644 -150.339044)
		(end 135.80872 -150.414228)
		(stroke
			(width 0.060198)
			(type default)
		)
		(layer "In5.Cu")
	)
	(gr_line
		(start 135.80872 -150.414228)
		(end 136.046972 -150.259542)
		(stroke
			(width 0.060198)
			(type default)
		)
		(layer "In5.Cu")
	)
	(gr_line
		(start 139.498578 -88.439498)
		(end 139.51458 -88.46439)
		(stroke
			(width 0.060198)
			(type default)
		)
		(layer "In5.Cu")
	)
	(gr_line
		(start 139.51458 -88.46439)
		(end 139.539472 -88.480392)
		(stroke
			(width 0.060198)
			(type default)
		)
		(layer "In5.Cu")
	)
	(gr_line
		(start 140.993114 -239.117378)
		(end 141.685518 -238.969804)
		(stroke
			(width 0.060198)
			(type default)
		)
		(layer "In5.Cu")
	)
	(gr_line
		(start 141.026388 -239.456976)
		(end 141.276578 -239.619536)
		(stroke
			(width 0.060198)
			(type default)
		)
		(layer "In5.Cu")
	)
	(gr_line
		(start 141.276578 -239.619536)
		(end 141.630654 -239.544098)
		(stroke
			(width 0.060198)
			(type default)
		)
		(layer "In5.Cu")
	)
	(gr_line
		(start 141.36116 -65.765934)
		(end 141.365224 -65.785746)
		(stroke
			(width 0.060198)
			(type default)
		)
		(layer "In5.Cu")
	)
	(gr_line
		(start 141.365224 -65.785746)
		(end 141.3764 -65.802764)
		(stroke
			(width 0.060198)
			(type default)
		)
		(layer "In5.Cu")
	)
	(gr_line
		(start 141.630654 -239.544098)
		(end 141.79296 -239.293654)
		(stroke
			(width 0.060198)
			(type default)
		)
		(layer "In5.Cu")
	)
	(gr_line
		(start 142.118588 -238.877602)
		(end 142.810992 -238.730028)
		(stroke
			(width 0.060198)
			(type default)
		)
		(layer "In5.Cu")
	)
	(gr_line
		(start 142.151608 -239.2172)
		(end 142.401798 -239.37976)
		(stroke
			(width 0.060198)
			(type default)
		)
		(layer "In5.Cu")
	)
	(gr_line
		(start 142.401798 -239.37976)
		(end 142.755874 -239.304322)
		(stroke
			(width 0.060198)
			(type default)
		)
		(layer "In5.Cu")
	)
	(gr_line
		(start 142.755874 -239.304322)
		(end 142.918434 -239.053878)
		(stroke
			(width 0.060198)
			(type default)
		)
		(layer "In5.Cu")
	)
	(gr_line
		(start 143.244316 -238.637826)
		(end 143.935196 -238.490506)
		(stroke
			(width 0.060198)
			(type default)
		)
		(layer "In5.Cu")
	)
	(gr_line
		(start 143.277082 -238.977678)
		(end 143.527272 -239.139984)
		(stroke
			(width 0.060198)
			(type default)
		)
		(layer "In5.Cu")
	)
	(gr_line
		(start 143.527272 -239.139984)
		(end 143.881348 -239.064546)
		(stroke
			(width 0.060198)
			(type default)
		)
		(layer "In5.Cu")
	)
	(gr_line
		(start 143.881348 -239.064546)
		(end 144.043654 -238.814102)
		(stroke
			(width 0.060198)
			(type default)
		)
		(layer "In5.Cu")
	)
	(gr_line
		(start 155.50642 -148.74367)
		(end 155.516072 -148.749004)
		(stroke
			(width 0.060198)
			(type default)
		)
		(layer "In5.Cu")
	)
	(gr_line
		(start 155.516072 -148.749004)
		(end 155.52674 -148.75129)
		(stroke
			(width 0.060198)
			(type default)
		)
		(layer "In5.Cu")
	)
	(gr_line
		(start 158.708852 -249.038872)
		(end 158.708852 -249.385074)
		(stroke
			(width 0.060198)
			(type default)
		)
		(layer "In5.Cu")
	)
	(gr_arc
		(start 158.708852 -248.461022)
		(mid 158.744197 -248.54632)
		(end 158.829502 -248.581672)
		(stroke
			(width 0.060198)
			(type default)
		)
		(layer "In5.Cu")
	)
	(gr_line
		(start 158.708852 -248.115074)
		(end 158.708852 -248.461022)
		(stroke
			(width 0.060198)
			(type default)
		)
		(layer "In5.Cu")
	)
	(gr_line
		(start 158.708852 -134.038848)
		(end 158.708852 -134.38505)
		(stroke
			(width 0.060198)
			(type default)
		)
		(layer "In5.Cu")
	)
	(gr_arc
		(start 158.708852 -133.460998)
		(mid 158.744189 -133.546311)
		(end 158.829502 -133.581648)
		(stroke
			(width 0.060198)
			(type default)
		)
		(layer "In5.Cu")
	)
	(gr_line
		(start 158.708852 -133.11505)
		(end 158.708852 -133.460998)
		(stroke
			(width 0.060198)
			(type default)
		)
		(layer "In5.Cu")
	)
	(gr_line
		(start 158.708852 -19.038824)
		(end 158.708852 -19.385026)
		(stroke
			(width 0.060198)
			(type default)
		)
		(layer "In5.Cu")
	)
	(gr_arc
		(start 158.708852 -18.460974)
		(mid 158.74418 -18.546303)
		(end 158.829502 -18.581624)
		(stroke
			(width 0.060198)
			(type default)
		)
		(layer "In5.Cu")
	)
	(gr_line
		(start 158.708852 -18.115026)
		(end 158.708852 -18.460974)
		(stroke
			(width 0.060198)
			(type default)
		)
		(layer "In5.Cu")
	)
	(gr_arc
		(start 158.829502 -248.918222)
		(mid 158.74419 -248.95356)
		(end 158.708852 -249.038872)
		(stroke
			(width 0.060198)
			(type default)
		)
		(layer "In5.Cu")
	)
	(gr_arc
		(start 158.829502 -133.918198)
		(mid 158.74419 -133.953536)
		(end 158.708852 -134.038848)
		(stroke
			(width 0.060198)
			(type default)
		)
		(layer "In5.Cu")
	)
	(gr_arc
		(start 158.829502 -18.918174)
		(mid 158.74419 -18.953512)
		(end 158.708852 -19.038824)
		(stroke
			(width 0.060198)
			(type default)
		)
		(layer "In5.Cu")
	)
	(gr_line
		(start 160.16478 -248.581672)
		(end 160.166304 -248.581418)
		(stroke
			(width 0.060198)
			(type default)
		)
		(layer "In5.Cu")
	)
	(gr_line
		(start 160.183322 -18.581624)
		(end 160.248346 -18.639536)
		(stroke
			(width 0.060198)
			(type default)
		)
		(layer "In5.Cu")
	)
	(gr_line
		(start 160.223454 -248.913142)
		(end 160.229042 -248.912126)
		(stroke
			(width 0.060198)
			(type default)
		)
		(layer "In5.Cu")
	)
	(gr_line
		(start 160.788858 -248.460768)
		(end 161.462974 -248.330466)
		(stroke
			(width 0.060198)
			(type default)
		)
		(layer "In5.Cu")
	)
	(gr_line
		(start 160.815528 -248.801128)
		(end 161.050732 -248.960132)
		(stroke
			(width 0.060198)
			(type default)
		)
		(layer "In5.Cu")
	)
	(gr_line
		(start 161.050732 -248.960132)
		(end 161.406078 -248.891298)
		(stroke
			(width 0.060198)
			(type default)
		)
		(layer "In5.Cu")
	)
	(gr_line
		(start 161.406078 -248.891298)
		(end 161.565082 -248.65584)
		(stroke
			(width 0.060198)
			(type default)
		)
		(layer "In5.Cu")
	)
	(gr_line
		(start 161.897568 -248.246392)
		(end 162.57143 -248.11609)
		(stroke
			(width 0.060198)
			(type default)
		)
		(layer "In5.Cu")
	)
	(gr_line
		(start 161.925 -248.586244)
		(end 162.160458 -248.745248)
		(stroke
			(width 0.060198)
			(type default)
		)
		(layer "In5.Cu")
	)
	(gr_line
		(start 162.119564 -133.581648)
		(end 162.143186 -133.591554)
		(stroke
			(width 0.060198)
			(type default)
		)
		(layer "In5.Cu")
	)
	(gr_line
		(start 162.160458 -248.745248)
		(end 162.515804 -248.676414)
		(stroke
			(width 0.060198)
			(type default)
		)
		(layer "In5.Cu")
	)
	(gr_line
		(start 162.515804 -248.676414)
		(end 162.674808 -248.44121)
		(stroke
			(width 0.060198)
			(type default)
		)
		(layer "In5.Cu")
	)
	(gr_line
		(start 162.839908 -335.7245)
		(end 163.113974 -335.998566)
		(stroke
			(width 0.127)
			(type default)
		)
		(layer "In5.Cu")
	)
	(gr_line
		(start 162.8648 -360.826304)
		(end 163.138866 -361.10037)
		(stroke
			(width 0.127)
			(type default)
		)
		(layer "In5.Cu")
	)
	(gr_line
		(start 162.946588 -241.275616)
		(end 163.64331 -241.129312)
		(stroke
			(width 0.060198)
			(type default)
		)
		(layer "In5.Cu")
	)
	(gr_line
		(start 162.981132 -241.61496)
		(end 163.231322 -241.778028)
		(stroke
			(width 0.060198)
			(type default)
		)
		(layer "In5.Cu")
	)
	(gr_line
		(start 163.008564 -248.031254)
		(end 163.681156 -247.901206)
		(stroke
			(width 0.060198)
			(type default)
		)
		(layer "In5.Cu")
	)
	(gr_line
		(start 163.034726 -248.37136)
		(end 163.270184 -248.530618)
		(stroke
			(width 0.060198)
			(type default)
		)
		(layer "In5.Cu")
	)
	(gr_line
		(start 163.108132 -21.18868)
		(end 163.148264 -21.224494)
		(stroke
			(width 0.060198)
			(type default)
		)
		(layer "In5.Cu")
	)
	(gr_line
		(start 163.148264 -21.224494)
		(end 163.164012 -21.27504)
		(stroke
			(width 0.060198)
			(type default)
		)
		(layer "In5.Cu")
	)
	(gr_line
		(start 163.231322 -241.778028)
		(end 163.585652 -241.70386)
		(stroke
			(width 0.060198)
			(type default)
		)
		(layer "In5.Cu")
	)
	(gr_line
		(start 163.270184 -248.530618)
		(end 163.62553 -248.461784)
		(stroke
			(width 0.060198)
			(type default)
		)
		(layer "In5.Cu")
	)
	(gr_line
		(start 163.340034 -150.414482)
		(end 163.502594 -150.664926)
		(stroke
			(width 0.060198)
			(type default)
		)
		(layer "In5.Cu")
	)
	(gr_line
		(start 163.446714 -150.090378)
		(end 164.14242 -150.238206)
		(stroke
			(width 0.060198)
			(type default)
		)
		(layer "In5.Cu")
	)
	(gr_line
		(start 163.502594 -150.664926)
		(end 163.85667 -150.74011)
		(stroke
			(width 0.060198)
			(type default)
		)
		(layer "In5.Cu")
	)
	(gr_line
		(start 163.585652 -241.70386)
		(end 163.74872 -241.45367)
		(stroke
			(width 0.060198)
			(type default)
		)
		(layer "In5.Cu")
	)
	(gr_line
		(start 163.62553 -248.461784)
		(end 163.784534 -248.226326)
		(stroke
			(width 0.060198)
			(type default)
		)
		(layer "In5.Cu")
	)
	(gr_line
		(start 163.835842 -335.998566)
		(end 164.109908 -335.7245)
		(stroke
			(width 0.127)
			(type default)
		)
		(layer "In5.Cu")
	)
	(gr_line
		(start 163.85667 -150.74011)
		(end 164.10686 -150.57755)
		(stroke
			(width 0.060198)
			(type default)
		)
		(layer "In5.Cu")
	)
	(gr_line
		(start 163.860734 -361.10037)
		(end 164.1348 -360.826304)
		(stroke
			(width 0.127)
			(type default)
		)
		(layer "In5.Cu")
	)
	(gr_line
		(start 164.074348 -241.038888)
		(end 164.76853 -240.893092)
		(stroke
			(width 0.060198)
			(type default)
		)
		(layer "In5.Cu")
	)
	(gr_line
		(start 164.107368 -241.378486)
		(end 164.357304 -241.541808)
		(stroke
			(width 0.060198)
			(type default)
		)
		(layer "In5.Cu")
	)
	(gr_line
		(start 164.357304 -241.541808)
		(end 164.711634 -241.467386)
		(stroke
			(width 0.060198)
			(type default)
		)
		(layer "In5.Cu")
	)
	(gr_line
		(start 164.465508 -150.65375)
		(end 164.628068 -150.904194)
		(stroke
			(width 0.060198)
			(type default)
		)
		(layer "In5.Cu")
	)
	(gr_line
		(start 164.571426 -150.329646)
		(end 165.266116 -150.477474)
		(stroke
			(width 0.060198)
			(type default)
		)
		(layer "In5.Cu")
	)
	(gr_line
		(start 164.628068 -150.904194)
		(end 164.982144 -150.979378)
		(stroke
			(width 0.060198)
			(type default)
		)
		(layer "In5.Cu")
	)
	(gr_line
		(start 164.711634 -241.467386)
		(end 164.874702 -241.21745)
		(stroke
			(width 0.060198)
			(type default)
		)
		(layer "In5.Cu")
	)
	(gr_line
		(start 164.966142 -372.724934)
		(end 165.1 -372.858792)
		(stroke
			(width 0.127)
			(type default)
		)
		(layer "In5.Cu")
	)
	(gr_line
		(start 164.966142 -372.003066)
		(end 165.1 -371.869208)
		(stroke
			(width 0.127)
			(type default)
		)
		(layer "In5.Cu")
	)
	(gr_line
		(start 164.982144 -150.979378)
		(end 165.232334 -150.816818)
		(stroke
			(width 0.060198)
			(type default)
		)
		(layer "In5.Cu")
	)
	(gr_line
		(start 165.1 -370.191792)
		(end 165.233858 -370.057934)
		(stroke
			(width 0.127)
			(type default)
		)
		(layer "In5.Cu")
	)
	(gr_line
		(start 165.1 -369.202208)
		(end 165.233858 -369.336066)
		(stroke
			(width 0.127)
			(type default)
		)
		(layer "In5.Cu")
	)
	(gr_line
		(start 165.198552 -240.802922)
		(end 165.79723 -240.677192)
		(stroke
			(width 0.060198)
			(type default)
		)
		(layer "In5.Cu")
	)
	(gr_line
		(start 165.23335 -241.142012)
		(end 165.48354 -241.305334)
		(stroke
			(width 0.060198)
			(type default)
		)
		(layer "In5.Cu")
	)
	(gr_line
		(start 165.48354 -241.305334)
		(end 165.837616 -241.230912)
		(stroke
			(width 0.060198)
			(type default)
		)
		(layer "In5.Cu")
	)
	(gr_line
		(start 165.590982 -150.893018)
		(end 165.753542 -151.143462)
		(stroke
			(width 0.060198)
			(type default)
		)
		(layer "In5.Cu")
	)
	(gr_line
		(start 165.697662 -150.568914)
		(end 166.393368 -150.716742)
		(stroke
			(width 0.060198)
			(type default)
		)
		(layer "In5.Cu")
	)
	(gr_line
		(start 165.753542 -151.143462)
		(end 166.107618 -151.218646)
		(stroke
			(width 0.060198)
			(type default)
		)
		(layer "In5.Cu")
	)
	(gr_line
		(start 165.79469 -103.403908)
		(end 165.811454 -103.429562)
		(stroke
			(width 0.060198)
			(type default)
		)
		(layer "In5.Cu")
	)
	(gr_line
		(start 165.79723 -240.677446)
		(end 165.89502 -240.656872)
		(stroke
			(width 0.060198)
			(type default)
		)
		(layer "In5.Cu")
	)
	(gr_line
		(start 165.79723 -240.677192)
		(end 165.79723 -240.677446)
		(stroke
			(width 0.060198)
			(type default)
		)
		(layer "In5.Cu")
	)
	(gr_line
		(start 165.811454 -103.429562)
		(end 165.837108 -103.446326)
		(stroke
			(width 0.060198)
			(type default)
		)
		(layer "In5.Cu")
	)
	(gr_line
		(start 165.837616 -241.230912)
		(end 166.000938 -240.98123)
		(stroke
			(width 0.060198)
			(type default)
		)
		(layer "In5.Cu")
	)
	(gr_line
		(start 166.107618 -151.218646)
		(end 166.357808 -151.056086)
		(stroke
			(width 0.060198)
			(type default)
		)
		(layer "In5.Cu")
	)
	(gr_line
		(start 172.593508 -221.877382)
		(end 172.620178 -221.872302)
		(stroke
			(width 0.060198)
			(type default)
		)
		(layer "In5.Cu")
	)
	(gr_line
		(start 172.620178 -221.872302)
		(end 172.646848 -221.87789)
		(stroke
			(width 0.060198)
			(type default)
		)
		(layer "In5.Cu")
	)
	(gr_line
		(start 173.53661 -139.34186)
		(end 173.562264 -139.358624)
		(stroke
			(width 0.060198)
			(type default)
		)
		(layer "In5.Cu")
	)
	(gr_line
		(start 173.562264 -139.358624)
		(end 173.579028 -139.384278)
		(stroke
			(width 0.060198)
			(type default)
		)
		(layer "In5.Cu")
	)
	(gr_line
		(start 177.315368 -82.702908)
		(end 177.390806 -83.05673)
		(stroke
			(width 0.060198)
			(type default)
		)
		(layer "In5.Cu")
	)
	(gr_line
		(start 177.315368 -82.702908)
		(end 177.477928 -82.452464)
		(stroke
			(width 0.060198)
			(type default)
		)
		(layer "In5.Cu")
	)
	(gr_line
		(start 177.390806 -83.05673)
		(end 177.640742 -83.219036)
		(stroke
			(width 0.060198)
			(type default)
		)
		(layer "In5.Cu")
	)
	(gr_line
		(start 177.554636 -83.828382)
		(end 177.630074 -84.182204)
		(stroke
			(width 0.060198)
			(type default)
		)
		(layer "In5.Cu")
	)
	(gr_line
		(start 177.554636 -83.828382)
		(end 177.717196 -83.577938)
		(stroke
			(width 0.060198)
			(type default)
		)
		(layer "In5.Cu")
	)
	(gr_line
		(start 177.630074 -84.182204)
		(end 177.88001 -84.34451)
		(stroke
			(width 0.060198)
			(type default)
		)
		(layer "In5.Cu")
	)
	(gr_line
		(start 177.793904 -84.953856)
		(end 177.869088 -85.307932)
		(stroke
			(width 0.060198)
			(type default)
		)
		(layer "In5.Cu")
	)
	(gr_line
		(start 177.793904 -84.953856)
		(end 177.956464 -84.703666)
		(stroke
			(width 0.060198)
			(type default)
		)
		(layer "In5.Cu")
	)
	(gr_line
		(start 177.817526 -82.419952)
		(end 177.964338 -83.110324)
		(stroke
			(width 0.060198)
			(type default)
		)
		(layer "In5.Cu")
	)
	(gr_line
		(start 177.869088 -85.307932)
		(end 178.119278 -85.470238)
		(stroke
			(width 0.060198)
			(type default)
		)
		(layer "In5.Cu")
	)
	(gr_line
		(start 177.883058 -84.346542)
		(end 177.88382 -84.350606)
		(stroke
			(width 0.060198)
			(type default)
		)
		(layer "In5.Cu")
	)
	(gr_line
		(start 178.056794 -83.545934)
		(end 178.203352 -84.234782)
		(stroke
			(width 0.060198)
			(type default)
		)
		(layer "In5.Cu")
	)
	(gr_line
		(start 178.21021 -84.267548)
		(end 178.212496 -84.2772)
		(stroke
			(width 0.060198)
			(type default)
		)
		(layer "In5.Cu")
	)
	(gr_line
		(start 178.296316 -84.673186)
		(end 178.442366 -85.360256)
		(stroke
			(width 0.060198)
			(type default)
		)
		(layer "In5.Cu")
	)
	(gr_line
		(start 181.160674 -151.670512)
		(end 181.177438 -151.696166)
		(stroke
			(width 0.060198)
			(type default)
		)
		(layer "In5.Cu")
	)
	(gr_line
		(start 181.177438 -151.696166)
		(end 181.20233 -151.712168)
		(stroke
			(width 0.060198)
			(type default)
		)
		(layer "In5.Cu")
	)
	(gr_line
		(start 182.091076 -104.143302)
		(end 182.09514 -104.163114)
		(stroke
			(width 0.060198)
			(type default)
		)
		(layer "In5.Cu")
	)
	(gr_line
		(start 182.09514 -104.163114)
		(end 182.106316 -104.180132)
		(stroke
			(width 0.060198)
			(type default)
		)
		(layer "In5.Cu")
	)
	(gr_line
		(start 182.911496 -154.228292)
		(end 182.931308 -154.232356)
		(stroke
			(width 0.060198)
			(type default)
		)
		(layer "In5.Cu")
	)
	(gr_line
		(start 182.931308 -154.232356)
		(end 182.948326 -154.243532)
		(stroke
			(width 0.060198)
			(type default)
		)
		(layer "In5.Cu")
	)
	(gr_line
		(start 185.25236 -226.125786)
		(end 185.275474 -226.121468)
		(stroke
			(width 0.060198)
			(type default)
		)
		(layer "In5.Cu")
	)
	(gr_line
		(start 185.275474 -226.121468)
		(end 185.29935 -226.126294)
		(stroke
			(width 0.060198)
			(type default)
		)
		(layer "In5.Cu")
	)
	(gr_line
		(start 187.889388 -45.68063)
		(end 187.895738 -45.650404)
		(stroke
			(width 0.060198)
			(type default)
		)
		(layer "In5.Cu")
	)
	(gr_line
		(start 187.889388 -45.68063)
		(end 187.895992 -45.711618)
		(stroke
			(width 0.060198)
			(type default)
		)
		(layer "In5.Cu")
	)
	(gr_line
		(start 189.61481 -54.777132)
		(end 189.689994 -55.131208)
		(stroke
			(width 0.060198)
			(type default)
		)
		(layer "In5.Cu")
	)
	(gr_line
		(start 189.61481 -54.777132)
		(end 189.769496 -54.539134)
		(stroke
			(width 0.060198)
			(type default)
		)
		(layer "In5.Cu")
	)
	(gr_line
		(start 189.689994 -55.131208)
		(end 189.928246 -55.286148)
		(stroke
			(width 0.060198)
			(type default)
		)
		(layer "In5.Cu")
	)
	(gr_line
		(start 189.84976 -55.883048)
		(end 189.924944 -56.237124)
		(stroke
			(width 0.060198)
			(type default)
		)
		(layer "In5.Cu")
	)
	(gr_line
		(start 189.84976 -55.883048)
		(end 190.004446 -55.644796)
		(stroke
			(width 0.060198)
			(type default)
		)
		(layer "In5.Cu")
	)
	(gr_line
		(start 189.924944 -56.237124)
		(end 190.163196 -56.39181)
		(stroke
			(width 0.060198)
			(type default)
		)
		(layer "In5.Cu")
	)
	(gr_line
		(start 190.08471 -56.98871)
		(end 190.159894 -57.342786)
		(stroke
			(width 0.060198)
			(type default)
		)
		(layer "In5.Cu")
	)
	(gr_line
		(start 190.08471 -56.98871)
		(end 190.239396 -56.750458)
		(stroke
			(width 0.060198)
			(type default)
		)
		(layer "In5.Cu")
	)
	(gr_line
		(start 190.109094 -54.506114)
		(end 190.252096 -55.178452)
		(stroke
			(width 0.060198)
			(type default)
		)
		(layer "In5.Cu")
	)
	(gr_line
		(start 190.140336 -161.410904)
		(end 190.160148 -161.414968)
		(stroke
			(width 0.060198)
			(type default)
		)
		(layer "In5.Cu")
	)
	(gr_line
		(start 190.159894 -57.342786)
		(end 190.398146 -57.497472)
		(stroke
			(width 0.060198)
			(type default)
		)
		(layer "In5.Cu")
	)
	(gr_line
		(start 190.160148 -161.414968)
		(end 190.177166 -161.426144)
		(stroke
			(width 0.060198)
			(type default)
		)
		(layer "In5.Cu")
	)
	(gr_line
		(start 190.258954 -249.038872)
		(end 190.258954 -249.385074)
		(stroke
			(width 0.060198)
			(type default)
		)
		(layer "In5.Cu")
	)
	(gr_arc
		(start 190.258954 -248.461022)
		(mid 190.2943 -248.546319)
		(end 190.379604 -248.581672)
		(stroke
			(width 0.060198)
			(type default)
		)
		(layer "In5.Cu")
	)
	(gr_line
		(start 190.258954 -248.115074)
		(end 190.258954 -248.461022)
		(stroke
			(width 0.060198)
			(type default)
		)
		(layer "In5.Cu")
	)
	(gr_line
		(start 190.258954 -134.038848)
		(end 190.258954 -134.38505)
		(stroke
			(width 0.060198)
			(type default)
		)
		(layer "In5.Cu")
	)
	(gr_arc
		(start 190.258954 -133.460998)
		(mid 190.294291 -133.54631)
		(end 190.379604 -133.581648)
		(stroke
			(width 0.060198)
			(type default)
		)
		(layer "In5.Cu")
	)
	(gr_line
		(start 190.258954 -133.11505)
		(end 190.258954 -133.460998)
		(stroke
			(width 0.060198)
			(type default)
		)
		(layer "In5.Cu")
	)
	(gr_line
		(start 190.258954 -19.038824)
		(end 190.258954 -19.385026)
		(stroke
			(width 0.060198)
			(type default)
		)
		(layer "In5.Cu")
	)
	(gr_arc
		(start 190.258954 -18.460974)
		(mid 190.294283 -18.546302)
		(end 190.379604 -18.581624)
		(stroke
			(width 0.060198)
			(type default)
		)
		(layer "In5.Cu")
	)
	(gr_line
		(start 190.258954 -18.115026)
		(end 190.258954 -18.460974)
		(stroke
			(width 0.060198)
			(type default)
		)
		(layer "In5.Cu")
	)
	(gr_line
		(start 190.34379 -55.610506)
		(end 190.487046 -56.284368)
		(stroke
			(width 0.060198)
			(type default)
		)
		(layer "In5.Cu")
	)
	(gr_arc
		(start 190.379604 -248.918222)
		(mid 190.294292 -248.95356)
		(end 190.258954 -249.038872)
		(stroke
			(width 0.060198)
			(type default)
		)
		(layer "In5.Cu")
	)
	(gr_arc
		(start 190.379604 -133.918198)
		(mid 190.294292 -133.953536)
		(end 190.258954 -134.038848)
		(stroke
			(width 0.060198)
			(type default)
		)
		(layer "In5.Cu")
	)
	(gr_arc
		(start 190.379604 -18.918174)
		(mid 190.294292 -18.953512)
		(end 190.258954 -19.038824)
		(stroke
			(width 0.060198)
			(type default)
		)
		(layer "In5.Cu")
	)
	(gr_line
		(start 190.384684 -228.593904)
		(end 190.414656 -228.587554)
		(stroke
			(width 0.060198)
			(type default)
		)
		(layer "In5.Cu")
	)
	(gr_line
		(start 190.414656 -228.587554)
		(end 190.444628 -228.593904)
		(stroke
			(width 0.060198)
			(type default)
		)
		(layer "In5.Cu")
	)
	(gr_line
		(start 190.57874 -56.715406)
		(end 190.721996 -57.390284)
		(stroke
			(width 0.060198)
			(type default)
		)
		(layer "In5.Cu")
	)
	(gr_line
		(start 190.993268 -117.865144)
		(end 191.010032 -117.890798)
		(stroke
			(width 0.060198)
			(type default)
		)
		(layer "In5.Cu")
	)
	(gr_line
		(start 191.010032 -117.890798)
		(end 191.035686 -117.907562)
		(stroke
			(width 0.060198)
			(type default)
		)
		(layer "In5.Cu")
	)
	(gr_line
		(start 191.48806 -18.581624)
		(end 191.53632 -18.61312)
		(stroke
			(width 0.060198)
			(type default)
		)
		(layer "In5.Cu")
	)
	(gr_line
		(start 192.104264 -133.581648)
		(end 192.106296 -133.582156)
		(stroke
			(width 0.060198)
			(type default)
		)
		(layer "In5.Cu")
	)
	(gr_line
		(start 192.555876 -19.275806)
		(end 192.6336 -19.326352)
		(stroke
			(width 0.060198)
			(type default)
		)
		(layer "In5.Cu")
	)
	(gr_line
		(start 192.6336 -19.326352)
		(end 192.655698 -19.416776)
		(stroke
			(width 0.060198)
			(type default)
		)
		(layer "In5.Cu")
	)
	(gr_line
		(start 193.253868 -248.05386)
		(end 193.92265 -247.89638)
		(stroke
			(width 0.060198)
			(type default)
		)
		(layer "In5.Cu")
	)
	(gr_line
		(start 193.268092 -21.923502)
		(end 193.276982 -21.960078)
		(stroke
			(width 0.060198)
			(type default)
		)
		(layer "In5.Cu")
	)
	(gr_line
		(start 193.269108 -21.996908)
		(end 193.276982 -21.960078)
		(stroke
			(width 0.060198)
			(type default)
		)
		(layer "In5.Cu")
	)
	(gr_line
		(start 193.294508 -248.392696)
		(end 193.536062 -248.542048)
		(stroke
			(width 0.060198)
			(type default)
		)
		(layer "In5.Cu")
	)
	(gr_line
		(start 193.536062 -248.542048)
		(end 193.88836 -248.45899)
		(stroke
			(width 0.060198)
			(type default)
		)
		(layer "In5.Cu")
	)
	(gr_line
		(start 193.88836 -248.45899)
		(end 194.037712 -248.21769)
		(stroke
			(width 0.060198)
			(type default)
		)
		(layer "In5.Cu")
	)
	(gr_line
		(start 194.35445 -247.794526)
		(end 195.022216 -247.637046)
		(stroke
			(width 0.060198)
			(type default)
		)
		(layer "In5.Cu")
	)
	(gr_line
		(start 194.394836 -248.133362)
		(end 194.636136 -248.282714)
		(stroke
			(width 0.060198)
			(type default)
		)
		(layer "In5.Cu")
	)
	(gr_line
		(start 194.636136 -248.282714)
		(end 194.988434 -248.199656)
		(stroke
			(width 0.060198)
			(type default)
		)
		(layer "In5.Cu")
	)
	(gr_line
		(start 194.988434 -248.199656)
		(end 195.137786 -247.958356)
		(stroke
			(width 0.060198)
			(type default)
		)
		(layer "In5.Cu")
	)
	(gr_line
		(start 195.454016 -247.535192)
		(end 196.122798 -247.377712)
		(stroke
			(width 0.060198)
			(type default)
		)
		(layer "In5.Cu")
	)
	(gr_line
		(start 195.49491 -247.874028)
		(end 195.73621 -248.02338)
		(stroke
			(width 0.060198)
			(type default)
		)
		(layer "In5.Cu")
	)
	(gr_line
		(start 195.73621 -248.02338)
		(end 196.088508 -247.940322)
		(stroke
			(width 0.060198)
			(type default)
		)
		(layer "In5.Cu")
	)
	(gr_line
		(start 196.088508 -247.940322)
		(end 196.23786 -247.699022)
		(stroke
			(width 0.060198)
			(type default)
		)
		(layer "In5.Cu")
	)
	(gr_line
		(start 196.985382 -168.325038)
		(end 197.005194 -168.329102)
		(stroke
			(width 0.060198)
			(type default)
		)
		(layer "In5.Cu")
	)
	(gr_line
		(start 197.005194 -168.329102)
		(end 197.022212 -168.340278)
		(stroke
			(width 0.060198)
			(type default)
		)
		(layer "In5.Cu")
	)
	(gr_line
		(start 198.683118 -135.660638)
		(end 198.83374 -135.918194)
		(stroke
			(width 0.060198)
			(type default)
		)
		(layer "In5.Cu")
	)
	(gr_line
		(start 198.804784 -135.341868)
		(end 199.490076 -135.521954)
		(stroke
			(width 0.060198)
			(type default)
		)
		(layer "In5.Cu")
	)
	(gr_line
		(start 198.83374 -135.918194)
		(end 199.183752 -136.010142)
		(stroke
			(width 0.060198)
			(type default)
		)
		(layer "In5.Cu")
	)
	(gr_line
		(start 199.183752 -136.010142)
		(end 199.441308 -135.859774)
		(stroke
			(width 0.060198)
			(type default)
		)
		(layer "In5.Cu")
	)
	(gr_line
		(start 199.795892 -135.952992)
		(end 199.946514 -136.210548)
		(stroke
			(width 0.060198)
			(type default)
		)
		(layer "In5.Cu")
	)
	(gr_line
		(start 199.916288 -135.633714)
		(end 200.605644 -135.81507)
		(stroke
			(width 0.060198)
			(type default)
		)
		(layer "In5.Cu")
	)
	(gr_line
		(start 199.946514 -136.210548)
		(end 200.296526 -136.30275)
		(stroke
			(width 0.060198)
			(type default)
		)
		(layer "In5.Cu")
	)
	(gr_line
		(start 200.296526 -136.30275)
		(end 200.554336 -136.152128)
		(stroke
			(width 0.060198)
			(type default)
		)
		(layer "In5.Cu")
	)
	(gr_line
		(start 200.909174 -136.245346)
		(end 201.059542 -136.502902)
		(stroke
			(width 0.060198)
			(type default)
		)
		(layer "In5.Cu")
	)
	(gr_line
		(start 201.028554 -135.925814)
		(end 201.719942 -136.107424)
		(stroke
			(width 0.060198)
			(type default)
		)
		(layer "In5.Cu")
	)
	(gr_line
		(start 201.059542 -136.502902)
		(end 201.409554 -136.595104)
		(stroke
			(width 0.060198)
			(type default)
		)
		(layer "In5.Cu")
	)
	(gr_line
		(start 201.319384 -233.220768)
		(end 201.349864 -233.214418)
		(stroke
			(width 0.060198)
			(type default)
		)
		(layer "In5.Cu")
	)
	(gr_line
		(start 201.349864 -233.214418)
		(end 201.379328 -233.220768)
		(stroke
			(width 0.060198)
			(type default)
		)
		(layer "In5.Cu")
	)
	(gr_line
		(start 201.409554 -136.595104)
		(end 201.667364 -136.444482)
		(stroke
			(width 0.060198)
			(type default)
		)
		(layer "In5.Cu")
	)
	(gr_line
		(start 202.357736 -174.37227)
		(end 202.377548 -174.376334)
		(stroke
			(width 0.060198)
			(type default)
		)
		(layer "In5.Cu")
	)
	(gr_line
		(start 202.377548 -174.376334)
		(end 202.394566 -174.38751)
		(stroke
			(width 0.060198)
			(type default)
		)
		(layer "In5.Cu")
	)
	(gr_line
		(start 202.57135 -114.76736)
		(end 202.575414 -114.787172)
		(stroke
			(width 0.060198)
			(type default)
		)
		(layer "In5.Cu")
	)
	(gr_line
		(start 202.575414 -114.787172)
		(end 202.58659 -114.80419)
		(stroke
			(width 0.060198)
			(type default)
		)
		(layer "In5.Cu")
	)
	(gr_line
		(start 205.056994 -239.503204)
		(end 205.085696 -239.497108)
		(stroke
			(width 0.060198)
			(type default)
		)
		(layer "In5.Cu")
	)
	(gr_line
		(start 205.085696 -239.497108)
		(end 205.11516 -239.50295)
		(stroke
			(width 0.060198)
			(type default)
		)
		(layer "In5.Cu")
	)
	(gr_line
		(start 207.584548 -137.648442)
		(end 207.597756 -137.651998)
		(stroke
			(width 0.060198)
			(type default)
		)
		(layer "In5.Cu")
	)
	(gr_line
		(start 207.597756 -137.651998)
		(end 207.609694 -137.659618)
		(stroke
			(width 0.060198)
			(type default)
		)
		(layer "In5.Cu")
	)
	(gr_line
		(start 210.000088 -71.430896)
		(end 210.000088 -71.799958)
		(stroke
			(width 0.06985)
			(type default)
		)
		(layer "In5.Cu")
	)
	(gr_arc
		(start 210.000088 -70.768972)
		(mid 210.054238 -70.899743)
		(end 210.185 -70.953884)
		(stroke
			(width 0.06985)
			(type default)
		)
		(layer "In5.Cu")
	)
	(gr_line
		(start 210.000088 -70.39991)
		(end 210.000088 -70.768972)
		(stroke
			(width 0.06985)
			(type default)
		)
		(layer "In5.Cu")
	)
	(gr_arc
		(start 210.185 -71.245984)
		(mid 210.054247 -71.300143)
		(end 210.000088 -71.430896)
		(stroke
			(width 0.06985)
			(type default)
		)
		(layer "In5.Cu")
	)
	(gr_line
		(start 210.75396 -82.84337)
		(end 210.780122 -82.883756)
		(stroke
			(width 0.06985)
			(type default)
		)
		(layer "In5.Cu")
	)
	(gr_line
		(start 211.800186 -66.630804)
		(end 211.800186 -66.999866)
		(stroke
			(width 0.06985)
			(type default)
		)
		(layer "In5.Cu")
	)
	(gr_arc
		(start 211.800186 -65.96888)
		(mid 211.854338 -66.099646)
		(end 211.985098 -66.153792)
		(stroke
			(width 0.06985)
			(type default)
		)
		(layer "In5.Cu")
	)
	(gr_line
		(start 211.800186 -65.600072)
		(end 211.800186 -65.96888)
		(stroke
			(width 0.06985)
			(type default)
		)
		(layer "In5.Cu")
	)
	(gr_line
		(start 211.872068 -129.10312)
		(end 211.888832 -129.128774)
		(stroke
			(width 0.060198)
			(type default)
		)
		(layer "In5.Cu")
	)
	(gr_line
		(start 211.888832 -129.128774)
		(end 211.914486 -129.145538)
		(stroke
			(width 0.060198)
			(type default)
		)
		(layer "In5.Cu")
	)
	(gr_arc
		(start 211.985098 -66.445892)
		(mid 211.854345 -66.500051)
		(end 211.800186 -66.630804)
		(stroke
			(width 0.06985)
			(type default)
		)
		(layer "In5.Cu")
	)
	(gr_line
		(start 212.554058 -82.392266)
		(end 212.58022 -82.432652)
		(stroke
			(width 0.06985)
			(type default)
		)
		(layer "In5.Cu")
	)
	(gr_line
		(start 213.60003 -71.430896)
		(end 213.60003 -71.799958)
		(stroke
			(width 0.06985)
			(type default)
		)
		(layer "In5.Cu")
	)
	(gr_arc
		(start 213.60003 -70.768972)
		(mid 213.654182 -70.899728)
		(end 213.784942 -70.953884)
		(stroke
			(width 0.06985)
			(type default)
		)
		(layer "In5.Cu")
	)
	(gr_line
		(start 213.60003 -70.39991)
		(end 213.60003 -70.768972)
		(stroke
			(width 0.06985)
			(type default)
		)
		(layer "In5.Cu")
	)
	(gr_line
		(start 213.655148 -87.568024)
		(end 213.695534 -87.378032)
		(stroke
			(width 0.06985)
			(type default)
		)
		(layer "In5.Cu")
	)
	(gr_line
		(start 213.655148 -87.568024)
		(end 213.883494 -87.91956)
		(stroke
			(width 0.06985)
			(type default)
		)
		(layer "In5.Cu")
	)
	(gr_arc
		(start 213.784942 -71.245984)
		(mid 213.654189 -71.300143)
		(end 213.60003 -71.430896)
		(stroke
			(width 0.06985)
			(type default)
		)
		(layer "In5.Cu")
	)
	(gr_line
		(start 213.883494 -87.91956)
		(end 214.073486 -87.959946)
		(stroke
			(width 0.06985)
			(type default)
		)
		(layer "In5.Cu")
	)
	(gr_line
		(start 213.961726 -87.246968)
		(end 214.301324 -87.769954)
		(stroke
			(width 0.06985)
			(type default)
		)
		(layer "In5.Cu")
	)
	(gr_line
		(start 214.000334 -241.63909)
		(end 214.029798 -241.644932)
		(stroke
			(width 0.060198)
			(type default)
		)
		(layer "In5.Cu")
	)
	(gr_line
		(start 214.029798 -241.644932)
		(end 214.0585 -241.638836)
		(stroke
			(width 0.060198)
			(type default)
		)
		(layer "In5.Cu")
	)
	(gr_line
		(start 214.263986 -88.505284)
		(end 214.304118 -88.315292)
		(stroke
			(width 0.06985)
			(type default)
		)
		(layer "In5.Cu")
	)
	(gr_line
		(start 214.263986 -88.505284)
		(end 214.492078 -88.85682)
		(stroke
			(width 0.06985)
			(type default)
		)
		(layer "In5.Cu")
	)
	(gr_line
		(start 214.353902 -81.795112)
		(end 214.380064 -81.835498)
		(stroke
			(width 0.06985)
			(type default)
		)
		(layer "In5.Cu")
	)
	(gr_line
		(start 214.492078 -88.85682)
		(end 214.68207 -88.897206)
		(stroke
			(width 0.06985)
			(type default)
		)
		(layer "In5.Cu")
	)
	(gr_line
		(start 214.57031 -88.183974)
		(end 214.909908 -88.707214)
		(stroke
			(width 0.06985)
			(type default)
		)
		(layer "In5.Cu")
	)
	(gr_line
		(start 214.87257 -89.442798)
		(end 214.912956 -89.252806)
		(stroke
			(width 0.06985)
			(type default)
		)
		(layer "In5.Cu")
	)
	(gr_line
		(start 214.87257 -89.442798)
		(end 215.100662 -89.79408)
		(stroke
			(width 0.06985)
			(type default)
		)
		(layer "In5.Cu")
	)
	(gr_line
		(start 215.100662 -89.79408)
		(end 215.290654 -89.834466)
		(stroke
			(width 0.06985)
			(type default)
		)
		(layer "In5.Cu")
	)
	(gr_line
		(start 215.179656 -89.122504)
		(end 215.517984 -89.643966)
		(stroke
			(width 0.06985)
			(type default)
		)
		(layer "In5.Cu")
	)
	(gr_line
		(start 215.400128 -66.630804)
		(end 215.400128 -66.999866)
		(stroke
			(width 0.06985)
			(type default)
		)
		(layer "In5.Cu")
	)
	(gr_arc
		(start 215.400128 -65.96888)
		(mid 215.454283 -66.099631)
		(end 215.58504 -66.153792)
		(stroke
			(width 0.06985)
			(type default)
		)
		(layer "In5.Cu")
	)
	(gr_line
		(start 215.400128 -65.600072)
		(end 215.400128 -65.96888)
		(stroke
			(width 0.06985)
			(type default)
		)
		(layer "In5.Cu")
	)
	(gr_line
		(start 215.481154 -90.380058)
		(end 215.52154 -90.190066)
		(stroke
			(width 0.06985)
			(type default)
		)
		(layer "In5.Cu")
	)
	(gr_line
		(start 215.481154 -90.380058)
		(end 215.7095 -90.731594)
		(stroke
			(width 0.06985)
			(type default)
		)
		(layer "In5.Cu")
	)
	(gr_arc
		(start 215.58504 -66.445892)
		(mid 215.454287 -66.500051)
		(end 215.400128 -66.630804)
		(stroke
			(width 0.06985)
			(type default)
		)
		(layer "In5.Cu")
	)
	(gr_line
		(start 215.7095 -90.731594)
		(end 215.899492 -90.771726)
		(stroke
			(width 0.06985)
			(type default)
		)
		(layer "In5.Cu")
	)
	(gr_line
		(start 215.787986 -90.05951)
		(end 216.127076 -90.581734)
		(stroke
			(width 0.06985)
			(type default)
		)
		(layer "In5.Cu")
	)
	(gr_line
		(start 216.154 -81.862168)
		(end 216.180162 -81.902554)
		(stroke
			(width 0.06985)
			(type default)
		)
		(layer "In5.Cu")
	)
	(gr_line
		(start 217.199972 -71.430896)
		(end 217.199972 -71.799958)
		(stroke
			(width 0.06985)
			(type default)
		)
		(layer "In5.Cu")
	)
	(gr_arc
		(start 217.199972 -70.768972)
		(mid 217.254121 -70.899748)
		(end 217.384884 -70.953884)
		(stroke
			(width 0.06985)
			(type default)
		)
		(layer "In5.Cu")
	)
	(gr_line
		(start 217.199972 -70.39991)
		(end 217.199972 -70.768972)
		(stroke
			(width 0.06985)
			(type default)
		)
		(layer "In5.Cu")
	)
	(gr_arc
		(start 217.384884 -71.245984)
		(mid 217.254131 -71.300143)
		(end 217.199972 -71.430896)
		(stroke
			(width 0.06985)
			(type default)
		)
		(layer "In5.Cu")
	)
	(gr_line
		(start 217.953844 -81.921096)
		(end 217.980006 -81.961482)
		(stroke
			(width 0.06985)
			(type default)
		)
		(layer "In5.Cu")
	)
	(gr_line
		(start 219.00007 -66.630804)
		(end 219.00007 -66.999866)
		(stroke
			(width 0.06985)
			(type default)
		)
		(layer "In5.Cu")
	)
	(gr_arc
		(start 219.00007 -65.96888)
		(mid 219.054221 -66.099652)
		(end 219.184982 -66.153792)
		(stroke
			(width 0.06985)
			(type default)
		)
		(layer "In5.Cu")
	)
	(gr_line
		(start 219.00007 -65.600072)
		(end 219.00007 -65.96888)
		(stroke
			(width 0.06985)
			(type default)
		)
		(layer "In5.Cu")
	)
	(gr_arc
		(start 219.184982 -66.445892)
		(mid 219.054229 -66.500051)
		(end 219.00007 -66.630804)
		(stroke
			(width 0.06985)
			(type default)
		)
		(layer "In5.Cu")
	)
	(gr_line
		(start 220.569028 -83.38693)
		(end 220.572584 -83.403186)
		(stroke
			(width 0.06985)
			(type default)
		)
		(layer "In5.Cu")
	)
	(gr_line
		(start 220.572584 -83.403186)
		(end 220.581474 -83.416648)
		(stroke
			(width 0.06985)
			(type default)
		)
		(layer "In5.Cu")
	)
	(gr_line
		(start 220.800168 -71.430896)
		(end 220.800168 -71.799958)
		(stroke
			(width 0.06985)
			(type default)
		)
		(layer "In5.Cu")
	)
	(gr_arc
		(start 220.800168 -70.768972)
		(mid 220.854316 -70.89975)
		(end 220.98508 -70.953884)
		(stroke
			(width 0.06985)
			(type default)
		)
		(layer "In5.Cu")
	)
	(gr_line
		(start 220.800168 -70.39991)
		(end 220.800168 -70.768972)
		(stroke
			(width 0.06985)
			(type default)
		)
		(layer "In5.Cu")
	)
	(gr_arc
		(start 220.98508 -71.245984)
		(mid 220.854327 -71.300143)
		(end 220.800168 -71.430896)
		(stroke
			(width 0.06985)
			(type default)
		)
		(layer "In5.Cu")
	)
	(gr_line
		(start 221.053152 -95.738188)
		(end 221.093538 -95.548196)
		(stroke
			(width 0.06985)
			(type default)
		)
		(layer "In5.Cu")
	)
	(gr_line
		(start 221.053152 -95.738188)
		(end 221.281498 -96.089724)
		(stroke
			(width 0.06985)
			(type default)
		)
		(layer "In5.Cu")
	)
	(gr_line
		(start 221.281498 -96.089724)
		(end 221.47149 -96.13011)
		(stroke
			(width 0.06985)
			(type default)
		)
		(layer "In5.Cu")
	)
	(gr_line
		(start 221.359476 -95.41637)
		(end 221.700344 -95.941134)
		(stroke
			(width 0.06985)
			(type default)
		)
		(layer "In5.Cu")
	)
	(gr_line
		(start 221.66199 -96.675448)
		(end 221.702122 -96.485456)
		(stroke
			(width 0.06985)
			(type default)
		)
		(layer "In5.Cu")
	)
	(gr_line
		(start 221.66199 -96.675448)
		(end 221.890082 -97.026984)
		(stroke
			(width 0.06985)
			(type default)
		)
		(layer "In5.Cu")
	)
	(gr_line
		(start 221.74708 -88.019382)
		(end 221.787466 -87.82939)
		(stroke
			(width 0.06985)
			(type default)
		)
		(layer "In5.Cu")
	)
	(gr_line
		(start 221.74708 -88.019382)
		(end 221.975426 -88.370918)
		(stroke
			(width 0.06985)
			(type default)
		)
		(layer "In5.Cu")
	)
	(gr_line
		(start 221.798134 -80.06842)
		(end 221.878144 -80.4799)
		(stroke
			(width 0.06985)
			(type default)
		)
		(layer "In5.Cu")
	)
	(gr_line
		(start 221.798134 -80.06842)
		(end 221.89694 -79.92237)
		(stroke
			(width 0.06985)
			(type default)
		)
		(layer "In5.Cu")
	)
	(gr_line
		(start 221.878144 -80.4799)
		(end 222.024448 -80.578706)
		(stroke
			(width 0.06985)
			(type default)
		)
		(layer "In5.Cu")
	)
	(gr_line
		(start 221.890082 -97.026984)
		(end 222.080074 -97.06737)
		(stroke
			(width 0.06985)
			(type default)
		)
		(layer "In5.Cu")
	)
	(gr_line
		(start 221.967806 -96.35363)
		(end 222.307912 -96.877124)
		(stroke
			(width 0.06985)
			(type default)
		)
		(layer "In5.Cu")
	)
	(gr_line
		(start 221.975426 -88.370918)
		(end 222.165164 -88.41105)
		(stroke
			(width 0.06985)
			(type default)
		)
		(layer "In5.Cu")
	)
	(gr_line
		(start 221.988888 -81.167732)
		(end 222.068644 -81.578958)
		(stroke
			(width 0.06985)
			(type default)
		)
		(layer "In5.Cu")
	)
	(gr_line
		(start 221.988888 -81.167732)
		(end 222.105474 -80.994758)
		(stroke
			(width 0.06985)
			(type default)
		)
		(layer "In5.Cu")
	)
	(gr_line
		(start 222.053658 -87.697818)
		(end 222.394018 -88.22182)
		(stroke
			(width 0.06985)
			(type default)
		)
		(layer "In5.Cu")
	)
	(gr_line
		(start 222.058738 -235.721906)
		(end 222.08871 -235.728256)
		(stroke
			(width 0.060198)
			(type default)
		)
		(layer "In5.Cu")
	)
	(gr_line
		(start 222.068644 -81.578958)
		(end 222.241618 -81.695798)
		(stroke
			(width 0.06985)
			(type default)
		)
		(layer "In5.Cu")
	)
	(gr_line
		(start 222.08871 -235.728256)
		(end 222.118682 -235.721906)
		(stroke
			(width 0.060198)
			(type default)
		)
		(layer "In5.Cu")
	)
	(gr_line
		(start 222.11411 -86.032594)
		(end 222.154496 -85.842602)
		(stroke
			(width 0.06985)
			(type default)
		)
		(layer "In5.Cu")
	)
	(gr_line
		(start 222.11411 -86.032594)
		(end 222.342456 -86.383876)
		(stroke
			(width 0.06985)
			(type default)
		)
		(layer "In5.Cu")
	)
	(gr_line
		(start 222.192596 -79.899256)
		(end 222.30715 -80.488282)
		(stroke
			(width 0.06985)
			(type default)
		)
		(layer "In5.Cu")
	)
	(gr_line
		(start 222.205804 -82.28457)
		(end 222.285814 -82.69605)
		(stroke
			(width 0.06985)
			(type default)
		)
		(layer "In5.Cu")
	)
	(gr_line
		(start 222.205804 -82.28457)
		(end 222.32239 -82.11185)
		(stroke
			(width 0.06985)
			(type default)
		)
		(layer "In5.Cu")
	)
	(gr_line
		(start 222.270574 -97.612962)
		(end 222.31096 -97.42297)
		(stroke
			(width 0.06985)
			(type default)
		)
		(layer "In5.Cu")
	)
	(gr_line
		(start 222.270574 -97.612962)
		(end 222.498666 -97.964244)
		(stroke
			(width 0.06985)
			(type default)
		)
		(layer "In5.Cu")
	)
	(gr_line
		(start 222.285814 -82.69605)
		(end 222.458788 -82.812636)
		(stroke
			(width 0.06985)
			(type default)
		)
		(layer "In5.Cu")
	)
	(gr_line
		(start 222.342456 -86.383876)
		(end 222.532448 -86.424262)
		(stroke
			(width 0.06985)
			(type default)
		)
		(layer "In5.Cu")
	)
	(gr_line
		(start 222.355918 -88.956642)
		(end 222.39605 -88.76665)
		(stroke
			(width 0.06985)
			(type default)
		)
		(layer "In5.Cu")
	)
	(gr_line
		(start 222.355918 -88.956642)
		(end 222.58401 -89.308178)
		(stroke
			(width 0.06985)
			(type default)
		)
		(layer "In5.Cu")
	)
	(gr_line
		(start 222.375984 -234.022138)
		(end 222.405194 -234.02798)
		(stroke
			(width 0.060198)
			(type default)
		)
		(layer "In5.Cu")
	)
	(gr_line
		(start 222.401384 -80.972914)
		(end 222.52432 -81.605374)
		(stroke
			(width 0.06985)
			(type default)
		)
		(layer "In5.Cu")
	)
	(gr_line
		(start 222.405194 -234.02798)
		(end 222.433388 -234.021884)
		(stroke
			(width 0.060198)
			(type default)
		)
		(layer "In5.Cu")
	)
	(gr_line
		(start 222.421196 -85.7123)
		(end 222.760286 -86.23427)
		(stroke
			(width 0.06985)
			(type default)
		)
		(layer "In5.Cu")
	)
	(gr_line
		(start 222.438976 -83.37804)
		(end 222.518732 -83.789266)
		(stroke
			(width 0.06985)
			(type default)
		)
		(layer "In5.Cu")
	)
	(gr_line
		(start 222.438976 -83.37804)
		(end 222.53956 -83.228688)
		(stroke
			(width 0.06985)
			(type default)
		)
		(layer "In5.Cu")
	)
	(gr_line
		(start 222.498666 -97.964244)
		(end 222.688658 -98.00463)
		(stroke
			(width 0.06985)
			(type default)
		)
		(layer "In5.Cu")
	)
	(gr_line
		(start 222.518732 -83.789266)
		(end 222.668084 -83.890104)
		(stroke
			(width 0.06985)
			(type default)
		)
		(layer "In5.Cu")
	)
	(gr_line
		(start 222.577914 -97.293176)
		(end 222.916496 -97.814638)
		(stroke
			(width 0.06985)
			(type default)
		)
		(layer "In5.Cu")
	)
	(gr_line
		(start 222.58401 -89.308178)
		(end 222.774002 -89.348564)
		(stroke
			(width 0.06985)
			(type default)
		)
		(layer "In5.Cu")
	)
	(gr_line
		(start 222.588582 -232.787698)
		(end 222.618808 -232.794048)
		(stroke
			(width 0.060198)
			(type default)
		)
		(layer "In5.Cu")
	)
	(gr_line
		(start 222.600012 -66.630804)
		(end 222.600012 -66.999866)
		(stroke
			(width 0.06985)
			(type default)
		)
		(layer "In5.Cu")
	)
	(gr_arc
		(start 222.600012 -65.96888)
		(mid 222.654166 -66.099637)
		(end 222.784924 -66.153792)
		(stroke
			(width 0.06985)
			(type default)
		)
		(layer "In5.Cu")
	)
	(gr_line
		(start 222.600012 -65.600072)
		(end 222.600012 -65.96888)
		(stroke
			(width 0.06985)
			(type default)
		)
		(layer "In5.Cu")
	)
	(gr_line
		(start 222.618554 -82.090514)
		(end 222.741236 -82.721704)
		(stroke
			(width 0.06985)
			(type default)
		)
		(layer "In5.Cu")
	)
	(gr_line
		(start 222.618808 -232.794048)
		(end 222.649288 -232.787698)
		(stroke
			(width 0.060198)
			(type default)
		)
		(layer "In5.Cu")
	)
	(gr_line
		(start 222.661734 -88.634062)
		(end 223.003364 -89.16035)
		(stroke
			(width 0.06985)
			(type default)
		)
		(layer "In5.Cu")
	)
	(gr_line
		(start 222.722948 -86.9696)
		(end 222.763334 -86.779862)
		(stroke
			(width 0.06985)
			(type default)
		)
		(layer "In5.Cu")
	)
	(gr_line
		(start 222.722948 -86.9696)
		(end 222.951294 -87.321136)
		(stroke
			(width 0.06985)
			(type default)
		)
		(layer "In5.Cu")
	)
	(gr_line
		(start 222.754698 -84.323682)
		(end 222.758508 -84.342986)
		(stroke
			(width 0.06985)
			(type default)
		)
		(layer "In5.Cu")
	)
	(gr_line
		(start 222.758508 -84.342986)
		(end 222.769176 -84.359496)
		(stroke
			(width 0.06985)
			(type default)
		)
		(layer "In5.Cu")
	)
	(gr_arc
		(start 222.784924 -66.445892)
		(mid 222.654171 -66.500051)
		(end 222.600012 -66.630804)
		(stroke
			(width 0.06985)
			(type default)
		)
		(layer "In5.Cu")
	)
	(gr_line
		(start 222.835216 -83.205574)
		(end 222.95104 -83.801204)
		(stroke
			(width 0.06985)
			(type default)
		)
		(layer "In5.Cu")
	)
	(gr_line
		(start 222.879158 -98.550222)
		(end 222.919544 -98.36023)
		(stroke
			(width 0.06985)
			(type default)
		)
		(layer "In5.Cu")
	)
	(gr_line
		(start 222.879158 -98.550222)
		(end 223.107504 -98.901758)
		(stroke
			(width 0.06985)
			(type default)
		)
		(layer "In5.Cu")
	)
	(gr_line
		(start 222.951294 -87.321136)
		(end 223.141286 -87.361522)
		(stroke
			(width 0.06985)
			(type default)
		)
		(layer "In5.Cu")
	)
	(gr_line
		(start 222.964502 -89.893902)
		(end 223.004888 -89.704164)
		(stroke
			(width 0.06985)
			(type default)
		)
		(layer "In5.Cu")
	)
	(gr_line
		(start 222.964502 -89.893902)
		(end 223.192848 -90.245438)
		(stroke
			(width 0.06985)
			(type default)
		)
		(layer "In5.Cu")
	)
	(gr_line
		(start 223.029018 -86.647528)
		(end 223.370394 -87.1728)
		(stroke
			(width 0.06985)
			(type default)
		)
		(layer "In5.Cu")
	)
	(gr_line
		(start 223.107504 -98.901758)
		(end 223.297496 -98.942144)
		(stroke
			(width 0.06985)
			(type default)
		)
		(layer "In5.Cu")
	)
	(gr_line
		(start 223.18599 -98.22942)
		(end 223.52635 -98.753422)
		(stroke
			(width 0.06985)
			(type default)
		)
		(layer "In5.Cu")
	)
	(gr_line
		(start 223.192848 -90.245438)
		(end 223.38284 -90.285824)
		(stroke
			(width 0.06985)
			(type default)
		)
		(layer "In5.Cu")
	)
	(gr_line
		(start 223.226376 -238.25581)
		(end 223.256348 -238.26216)
		(stroke
			(width 0.060198)
			(type default)
		)
		(layer "In5.Cu")
	)
	(gr_line
		(start 223.256348 -238.26216)
		(end 223.28632 -238.25581)
		(stroke
			(width 0.060198)
			(type default)
		)
		(layer "In5.Cu")
	)
	(gr_line
		(start 223.27108 -89.572846)
		(end 223.611186 -90.096594)
		(stroke
			(width 0.06985)
			(type default)
		)
		(layer "In5.Cu")
	)
	(gr_line
		(start 223.331786 -87.90686)
		(end 223.372172 -87.716868)
		(stroke
			(width 0.06985)
			(type default)
		)
		(layer "In5.Cu")
	)
	(gr_line
		(start 223.331786 -87.90686)
		(end 223.560132 -88.258396)
		(stroke
			(width 0.06985)
			(type default)
		)
		(layer "In5.Cu")
	)
	(gr_line
		(start 223.560132 -88.258396)
		(end 223.750378 -88.298782)
		(stroke
			(width 0.06985)
			(type default)
		)
		(layer "In5.Cu")
	)
	(gr_line
		(start 223.573086 -90.831162)
		(end 223.613472 -90.641424)
		(stroke
			(width 0.06985)
			(type default)
		)
		(layer "In5.Cu")
	)
	(gr_line
		(start 223.573086 -90.831162)
		(end 223.801432 -91.182698)
		(stroke
			(width 0.06985)
			(type default)
		)
		(layer "In5.Cu")
	)
	(gr_line
		(start 223.637348 -87.583772)
		(end 223.979994 -88.111076)
		(stroke
			(width 0.06985)
			(type default)
		)
		(layer "In5.Cu")
	)
	(gr_line
		(start 223.801432 -91.182698)
		(end 223.991424 -91.223084)
		(stroke
			(width 0.06985)
			(type default)
		)
		(layer "In5.Cu")
	)
	(gr_line
		(start 223.87941 -90.509852)
		(end 224.2185 -91.032076)
		(stroke
			(width 0.06985)
			(type default)
		)
		(layer "In5.Cu")
	)
	(gr_line
		(start 223.940624 -88.84412)
		(end 223.98101 -88.654128)
		(stroke
			(width 0.06985)
			(type default)
		)
		(layer "In5.Cu")
	)
	(gr_line
		(start 223.940624 -88.84412)
		(end 224.16897 -89.195656)
		(stroke
			(width 0.06985)
			(type default)
		)
		(layer "In5.Cu")
	)
	(gr_line
		(start 224.16897 -89.195656)
		(end 224.359216 -89.236042)
		(stroke
			(width 0.06985)
			(type default)
		)
		(layer "In5.Cu")
	)
	(gr_line
		(start 224.246694 -88.521794)
		(end 224.588832 -89.048336)
		(stroke
			(width 0.06985)
			(type default)
		)
		(layer "In5.Cu")
	)
	(gr_line
		(start 224.842324 -98.207322)
		(end 224.88271 -98.01733)
		(stroke
			(width 0.06985)
			(type default)
		)
		(layer "In5.Cu")
	)
	(gr_line
		(start 224.842324 -98.207322)
		(end 225.07067 -98.558858)
		(stroke
			(width 0.06985)
			(type default)
		)
		(layer "In5.Cu")
	)
	(gr_line
		(start 225.07067 -98.558858)
		(end 225.260408 -98.599244)
		(stroke
			(width 0.06985)
			(type default)
		)
		(layer "In5.Cu")
	)
	(gr_line
		(start 225.149156 -97.88652)
		(end 225.4885 -98.409252)
		(stroke
			(width 0.06985)
			(type default)
		)
		(layer "In5.Cu")
	)
	(gr_line
		(start 225.404934 -86.435184)
		(end 225.408236 -86.450678)
		(stroke
			(width 0.06985)
			(type default)
		)
		(layer "In5.Cu")
	)
	(gr_line
		(start 225.408236 -86.450678)
		(end 225.416618 -86.463632)
		(stroke
			(width 0.06985)
			(type default)
		)
		(layer "In5.Cu")
	)
	(gr_line
		(start 225.450908 -99.144836)
		(end 225.491294 -98.954844)
		(stroke
			(width 0.06985)
			(type default)
		)
		(layer "In5.Cu")
	)
	(gr_line
		(start 225.450908 -99.144836)
		(end 225.679254 -99.496372)
		(stroke
			(width 0.06985)
			(type default)
		)
		(layer "In5.Cu")
	)
	(gr_line
		(start 225.679254 -99.496372)
		(end 225.868992 -99.536504)
		(stroke
			(width 0.06985)
			(type default)
		)
		(layer "In5.Cu")
	)
	(gr_line
		(start 225.757232 -98.822764)
		(end 226.097084 -99.346512)
		(stroke
			(width 0.06985)
			(type default)
		)
		(layer "In5.Cu")
	)
	(gr_line
		(start 225.872548 -99.537266)
		(end 225.956876 -99.66706)
		(stroke
			(width 0.06985)
			(type default)
		)
		(layer "In5.Cu")
	)
	(gr_line
		(start 226.059492 -100.082096)
		(end 226.099878 -99.892104)
		(stroke
			(width 0.06985)
			(type default)
		)
		(layer "In5.Cu")
	)
	(gr_line
		(start 226.059492 -100.082096)
		(end 226.287838 -100.433632)
		(stroke
			(width 0.06985)
			(type default)
		)
		(layer "In5.Cu")
	)
	(gr_line
		(start 226.114102 -99.373182)
		(end 226.151186 -99.430078)
		(stroke
			(width 0.06985)
			(type default)
		)
		(layer "In5.Cu")
	)
	(gr_line
		(start 226.287838 -100.433632)
		(end 226.477576 -100.474018)
		(stroke
			(width 0.06985)
			(type default)
		)
		(layer "In5.Cu")
	)
	(gr_line
		(start 226.365816 -99.760278)
		(end 226.707192 -100.286058)
		(stroke
			(width 0.06985)
			(type default)
		)
		(layer "In5.Cu")
	)
	(gr_line
		(start 226.668076 -101.01961)
		(end 226.708462 -100.829618)
		(stroke
			(width 0.06985)
			(type default)
		)
		(layer "In5.Cu")
	)
	(gr_line
		(start 226.668076 -101.01961)
		(end 226.896422 -101.371146)
		(stroke
			(width 0.06985)
			(type default)
		)
		(layer "In5.Cu")
	)
	(gr_line
		(start 226.896422 -101.371146)
		(end 227.08616 -101.411278)
		(stroke
			(width 0.06985)
			(type default)
		)
		(layer "In5.Cu")
	)
	(gr_line
		(start 226.9744 -100.697792)
		(end 227.31476 -101.222048)
		(stroke
			(width 0.06985)
			(type default)
		)
		(layer "In5.Cu")
	)
	(gr_line
		(start 229.382574 -102.495858)
		(end 229.42296 -102.305612)
		(stroke
			(width 0.06985)
			(type default)
		)
		(layer "In5.Cu")
	)
	(gr_line
		(start 229.382574 -102.495858)
		(end 229.61092 -102.847394)
		(stroke
			(width 0.06985)
			(type default)
		)
		(layer "In5.Cu")
	)
	(gr_line
		(start 229.61092 -102.847394)
		(end 229.800912 -102.88778)
		(stroke
			(width 0.06985)
			(type default)
		)
		(layer "In5.Cu")
	)
	(gr_line
		(start 229.688898 -102.174294)
		(end 230.02875 -102.697788)
		(stroke
			(width 0.06985)
			(type default)
		)
		(layer "In5.Cu")
	)
	(gr_line
		(start 229.991158 -103.433118)
		(end 230.031544 -103.243126)
		(stroke
			(width 0.06985)
			(type default)
		)
		(layer "In5.Cu")
	)
	(gr_line
		(start 229.991158 -103.433118)
		(end 230.219504 -103.784654)
		(stroke
			(width 0.06985)
			(type default)
		)
		(layer "In5.Cu")
	)
	(gr_line
		(start 230.219504 -103.784654)
		(end 230.409496 -103.82504)
		(stroke
			(width 0.06985)
			(type default)
		)
		(layer "In5.Cu")
	)
	(gr_line
		(start 230.297482 -103.1113)
		(end 230.637334 -103.635048)
		(stroke
			(width 0.06985)
			(type default)
		)
		(layer "In5.Cu")
	)
	(gr_line
		(start 230.599742 -104.370632)
		(end 230.640128 -104.18064)
		(stroke
			(width 0.06985)
			(type default)
		)
		(layer "In5.Cu")
	)
	(gr_line
		(start 230.599742 -104.370632)
		(end 230.828088 -104.722168)
		(stroke
			(width 0.06985)
			(type default)
		)
		(layer "In5.Cu")
	)
	(gr_line
		(start 230.828088 -104.722168)
		(end 231.01808 -104.762808)
		(stroke
			(width 0.06985)
			(type default)
		)
		(layer "In5.Cu")
	)
	(gr_line
		(start 230.906066 -104.048814)
		(end 231.247442 -104.574594)
		(stroke
			(width 0.06985)
			(type default)
		)
		(layer "In5.Cu")
	)
	(gr_line
		(start 230.91267 -94.928944)
		(end 230.925878 -94.949518)
		(stroke
			(width 0.06985)
			(type default)
		)
		(layer "In5.Cu")
	)
	(gr_line
		(start 230.925878 -94.949518)
		(end 230.946452 -94.962726)
		(stroke
			(width 0.06985)
			(type default)
		)
		(layer "In5.Cu")
	)
	(gr_line
		(start 231.208326 -105.307892)
		(end 231.248712 -105.1179)
		(stroke
			(width 0.06985)
			(type default)
		)
		(layer "In5.Cu")
	)
	(gr_line
		(start 231.208326 -105.307892)
		(end 231.436672 -105.659428)
		(stroke
			(width 0.06985)
			(type default)
		)
		(layer "In5.Cu")
	)
	(gr_line
		(start 231.436672 -105.659428)
		(end 231.626664 -105.699814)
		(stroke
			(width 0.06985)
			(type default)
		)
		(layer "In5.Cu")
	)
	(gr_line
		(start 231.51465 -104.986328)
		(end 231.85501 -105.510584)
		(stroke
			(width 0.06985)
			(type default)
		)
		(layer "In5.Cu")
	)
	(gr_line
		(start 231.579928 -114.91595)
		(end 231.593136 -114.936524)
		(stroke
			(width 0.06985)
			(type default)
		)
		(layer "In5.Cu")
	)
	(gr_line
		(start 231.593136 -114.936524)
		(end 231.61371 -114.949732)
		(stroke
			(width 0.06985)
			(type default)
		)
		(layer "In5.Cu")
	)
	(gr_line
		(start 231.87406 -95.568262)
		(end 231.91724 -95.772478)
		(stroke
			(width 0.06985)
			(type default)
		)
		(layer "In5.Cu")
	)
	(gr_line
		(start 231.91724 -95.772478)
		(end 232.268522 -96.000824)
		(stroke
			(width 0.06985)
			(type default)
		)
		(layer "In5.Cu")
	)
	(gr_line
		(start 232.06329 -95.339916)
		(end 232.605072 -95.69196)
		(stroke
			(width 0.06985)
			(type default)
		)
		(layer "In5.Cu")
	)
	(gr_line
		(start 232.268522 -96.000824)
		(end 232.472738 -95.957644)
		(stroke
			(width 0.06985)
			(type default)
		)
		(layer "In5.Cu")
	)
	(gr_line
		(start 232.789984 -113.556542)
		(end 232.803192 -113.577116)
		(stroke
			(width 0.06985)
			(type default)
		)
		(layer "In5.Cu")
	)
	(gr_line
		(start 232.803192 -113.577116)
		(end 232.823766 -113.590324)
		(stroke
			(width 0.06985)
			(type default)
		)
		(layer "In5.Cu")
	)
	(gr_line
		(start 232.828084 -96.188276)
		(end 232.871264 -96.392492)
		(stroke
			(width 0.06985)
			(type default)
		)
		(layer "In5.Cu")
	)
	(gr_line
		(start 232.871264 -96.392492)
		(end 233.2228 -96.620838)
		(stroke
			(width 0.06985)
			(type default)
		)
		(layer "In5.Cu")
	)
	(gr_line
		(start 233.016044 -95.958914)
		(end 233.560366 -96.312482)
		(stroke
			(width 0.06985)
			(type default)
		)
		(layer "In5.Cu")
	)
	(gr_line
		(start 233.2228 -96.620838)
		(end 233.427016 -96.577658)
		(stroke
			(width 0.06985)
			(type default)
		)
		(layer "In5.Cu")
	)
	(gr_line
		(start 233.782362 -96.808544)
		(end 233.825542 -97.012506)
		(stroke
			(width 0.06985)
			(type default)
		)
		(layer "In5.Cu")
	)
	(gr_line
		(start 233.825542 -97.012506)
		(end 234.176824 -97.240852)
		(stroke
			(width 0.06985)
			(type default)
		)
		(layer "In5.Cu")
	)
	(gr_line
		(start 233.970576 -96.579182)
		(end 234.513882 -96.932242)
		(stroke
			(width 0.06985)
			(type default)
		)
		(layer "In5.Cu")
	)
	(gr_line
		(start 234.176824 -97.240852)
		(end 234.38104 -97.197672)
		(stroke
			(width 0.06985)
			(type default)
		)
		(layer "In5.Cu")
	)
	(gr_line
		(start 234.736386 -97.428558)
		(end 234.776772 -97.618804)
		(stroke
			(width 0.06985)
			(type default)
		)
		(layer "In5.Cu")
	)
	(gr_line
		(start 234.759246 -113.225834)
		(end 234.772454 -113.246408)
		(stroke
			(width 0.06985)
			(type default)
		)
		(layer "In5.Cu")
	)
	(gr_line
		(start 234.772454 -113.246408)
		(end 234.793028 -113.259616)
		(stroke
			(width 0.06985)
			(type default)
		)
		(layer "In5.Cu")
	)
	(gr_line
		(start 234.776772 -97.618804)
		(end 235.128054 -97.84715)
		(stroke
			(width 0.06985)
			(type default)
		)
		(layer "In5.Cu")
	)
	(gr_line
		(start 234.923584 -97.19818)
		(end 235.454444 -97.543112)
		(stroke
			(width 0.06985)
			(type default)
		)
		(layer "In5.Cu")
	)
	(gr_line
		(start 235.128054 -97.84715)
		(end 235.318554 -97.806764)
		(stroke
			(width 0.06985)
			(type default)
		)
		(layer "In5.Cu")
	)
	(gr_line
		(start 235.217462 -111.2266)
		(end 235.23067 -111.247174)
		(stroke
			(width 0.06985)
			(type default)
		)
		(layer "In5.Cu")
	)
	(gr_line
		(start 235.23067 -111.247174)
		(end 235.251244 -111.260382)
		(stroke
			(width 0.06985)
			(type default)
		)
		(layer "In5.Cu")
	)
	(gr_line
		(start 236.420914 -110.359698)
		(end 236.434122 -110.380272)
		(stroke
			(width 0.06985)
			(type default)
		)
		(layer "In5.Cu")
	)
	(gr_line
		(start 236.434122 -110.380272)
		(end 236.454696 -110.39348)
		(stroke
			(width 0.06985)
			(type default)
		)
		(layer "In5.Cu")
	)
	(gr_line
		(start 236.962442 -108.631228)
		(end 236.97565 -108.651802)
		(stroke
			(width 0.06985)
			(type default)
		)
		(layer "In5.Cu")
	)
	(gr_line
		(start 236.97565 -108.651802)
		(end 236.996224 -108.66501)
		(stroke
			(width 0.06985)
			(type default)
		)
		(layer "In5.Cu")
	)
	(gr_line
		(start 237.912656 -107.668314)
		(end 237.925864 -107.688888)
		(stroke
			(width 0.06985)
			(type default)
		)
		(layer "In5.Cu")
	)
	(gr_line
		(start 237.925864 -107.688888)
		(end 237.946438 -107.702096)
		(stroke
			(width 0.06985)
			(type default)
		)
		(layer "In5.Cu")
	)
	(gr_line
		(start 240.85042 -229.762558)
		(end 240.880646 -229.756208)
		(stroke
			(width 0.060198)
			(type default)
		)
		(layer "In5.Cu")
	)
	(gr_line
		(start 240.880646 -229.756208)
		(end 240.910872 -229.762558)
		(stroke
			(width 0.060198)
			(type default)
		)
		(layer "In5.Cu")
	)
	(gr_line
		(start 240.96091 -231.372156)
		(end 240.991136 -231.365806)
		(stroke
			(width 0.060198)
			(type default)
		)
		(layer "In5.Cu")
	)
	(gr_line
		(start 240.991136 -231.365806)
		(end 241.021362 -231.372156)
		(stroke
			(width 0.060198)
			(type default)
		)
		(layer "In5.Cu")
	)
	(gr_line
		(start 241.791236 -228.374702)
		(end 241.821462 -228.368352)
		(stroke
			(width 0.060198)
			(type default)
		)
		(layer "In5.Cu")
	)
	(gr_line
		(start 241.821462 -228.368352)
		(end 241.851688 -228.374702)
		(stroke
			(width 0.060198)
			(type default)
		)
		(layer "In5.Cu")
	)
	(gr_line
		(start 244.009418 -236.089698)
		(end 244.042946 -236.081824)
		(stroke
			(width 0.060198)
			(type default)
		)
		(layer "In5.Cu")
	)
	(gr_line
		(start 244.042946 -236.081824)
		(end 244.076728 -236.088936)
		(stroke
			(width 0.060198)
			(type default)
		)
		(layer "In5.Cu")
	)
	(gr_line
		(start 244.191536 -234.889548)
		(end 244.221762 -234.883198)
		(stroke
			(width 0.060198)
			(type default)
		)
		(layer "In5.Cu")
	)
	(gr_line
		(start 244.221762 -234.883198)
		(end 244.251988 -234.889548)
		(stroke
			(width 0.060198)
			(type default)
		)
		(layer "In5.Cu")
	)
	(gr_line
		(start 244.54993 -233.391964)
		(end 244.580156 -233.385614)
		(stroke
			(width 0.060198)
			(type default)
		)
		(layer "In5.Cu")
	)
	(gr_line
		(start 244.580156 -233.385614)
		(end 244.610382 -233.391964)
		(stroke
			(width 0.060198)
			(type default)
		)
		(layer "In5.Cu")
	)
	(gr_line
		(start 251.08662 -165.894766)
		(end 251.112274 -165.91153)
		(stroke
			(width 0.060198)
			(type default)
		)
		(layer "In5.Cu")
	)
	(gr_line
		(start 251.112274 -165.91153)
		(end 251.129038 -165.937184)
		(stroke
			(width 0.060198)
			(type default)
		)
		(layer "In5.Cu")
	)
	(gr_line
		(start 251.742956 -233.995722)
		(end 251.773182 -234.002072)
		(stroke
			(width 0.060198)
			(type default)
		)
		(layer "In5.Cu")
	)
	(gr_line
		(start 251.773182 -234.002072)
		(end 251.803408 -233.995722)
		(stroke
			(width 0.060198)
			(type default)
		)
		(layer "In5.Cu")
	)
	(gr_line
		(start 251.838714 -236.84611)
		(end 251.86894 -236.85246)
		(stroke
			(width 0.060198)
			(type default)
		)
		(layer "In5.Cu")
	)
	(gr_line
		(start 251.86894 -236.85246)
		(end 251.899166 -236.84611)
		(stroke
			(width 0.060198)
			(type default)
		)
		(layer "In5.Cu")
	)
	(gr_line
		(start 252.022864 -235.312204)
		(end 252.05309 -235.318554)
		(stroke
			(width 0.060198)
			(type default)
		)
		(layer "In5.Cu")
	)
	(gr_line
		(start 252.046232 -232.474262)
		(end 252.076458 -232.480612)
		(stroke
			(width 0.060198)
			(type default)
		)
		(layer "In5.Cu")
	)
	(gr_line
		(start 252.05309 -235.318554)
		(end 252.083316 -235.312204)
		(stroke
			(width 0.060198)
			(type default)
		)
		(layer "In5.Cu")
	)
	(gr_line
		(start 252.076458 -232.480612)
		(end 252.106684 -232.474262)
		(stroke
			(width 0.060198)
			(type default)
		)
		(layer "In5.Cu")
	)
	(gr_line
		(start 252.960886 -231.08031)
		(end 252.995938 -231.087676)
		(stroke
			(width 0.060198)
			(type default)
		)
		(layer "In5.Cu")
	)
	(gr_line
		(start 252.995938 -231.087676)
		(end 253.030482 -231.079294)
		(stroke
			(width 0.060198)
			(type default)
		)
		(layer "In5.Cu")
	)
	(gr_line
		(start 253.039372 -165.35146)
		(end 253.065026 -165.368224)
		(stroke
			(width 0.060198)
			(type default)
		)
		(layer "In5.Cu")
	)
	(gr_line
		(start 253.065026 -165.368224)
		(end 253.081028 -165.393116)
		(stroke
			(width 0.060198)
			(type default)
		)
		(layer "In5.Cu")
	)
	(gr_line
		(start 253.259082 -163.683696)
		(end 253.284736 -163.70046)
		(stroke
			(width 0.060198)
			(type default)
		)
		(layer "In5.Cu")
	)
	(gr_line
		(start 253.284736 -163.70046)
		(end 253.3015 -163.726114)
		(stroke
			(width 0.060198)
			(type default)
		)
		(layer "In5.Cu")
	)
	(gr_line
		(start 254.078232 -162.455352)
		(end 254.103124 -162.471354)
		(stroke
			(width 0.060198)
			(type default)
		)
		(layer "In5.Cu")
	)
	(gr_line
		(start 254.103124 -162.471354)
		(end 254.119888 -162.497008)
		(stroke
			(width 0.060198)
			(type default)
		)
		(layer "In5.Cu")
	)
	(gr_line
		(start 254.83693 -160.841944)
		(end 254.862584 -160.858708)
		(stroke
			(width 0.060198)
			(type default)
		)
		(layer "In5.Cu")
	)
	(gr_line
		(start 254.862584 -160.858708)
		(end 254.879348 -160.884362)
		(stroke
			(width 0.060198)
			(type default)
		)
		(layer "In5.Cu")
	)
	(gr_line
		(start 255.665986 -159.47771)
		(end 255.69164 -159.494474)
		(stroke
			(width 0.060198)
			(type default)
		)
		(layer "In5.Cu")
	)
	(gr_line
		(start 255.69164 -159.494474)
		(end 255.708404 -159.520128)
		(stroke
			(width 0.060198)
			(type default)
		)
		(layer "In5.Cu")
	)
	(gr_line
		(start 257.237484 -158.177992)
		(end 257.263138 -158.194756)
		(stroke
			(width 0.060198)
			(type default)
		)
		(layer "In5.Cu")
	)
	(gr_line
		(start 257.263138 -158.194756)
		(end 257.279902 -158.22041)
		(stroke
			(width 0.060198)
			(type default)
		)
		(layer "In5.Cu")
	)
	(gr_line
		(start 264.526776 -215.141048)
		(end 264.543794 -215.152224)
		(stroke
			(width 0.060198)
			(type default)
		)
		(layer "In5.Cu")
	)
	(gr_line
		(start 264.543794 -215.152224)
		(end 264.563606 -215.156288)
		(stroke
			(width 0.060198)
			(type default)
		)
		(layer "In5.Cu")
	)
	(gr_line
		(start 264.596118 -212.621622)
		(end 264.613136 -212.632798)
		(stroke
			(width 0.060198)
			(type default)
		)
		(layer "In5.Cu")
	)
	(gr_line
		(start 264.613136 -212.632798)
		(end 264.632948 -212.636862)
		(stroke
			(width 0.060198)
			(type default)
		)
		(layer "In5.Cu")
	)
	(gr_line
		(start 266.069064 -208.5975)
		(end 266.086082 -208.608676)
		(stroke
			(width 0.060198)
			(type default)
		)
		(layer "In5.Cu")
	)
	(gr_line
		(start 266.086082 -208.608676)
		(end 266.105894 -208.61274)
		(stroke
			(width 0.060198)
			(type default)
		)
		(layer "In5.Cu")
	)
	(gr_line
		(start 266.281154 -211.24799)
		(end 266.298172 -211.259166)
		(stroke
			(width 0.060198)
			(type default)
		)
		(layer "In5.Cu")
	)
	(gr_line
		(start 266.298172 -211.259166)
		(end 266.317984 -211.26323)
		(stroke
			(width 0.060198)
			(type default)
		)
		(layer "In5.Cu")
	)
	(gr_line
		(start 267.676884 -205.974696)
		(end 267.806678 -206.243174)
		(stroke
			(width 0.060198)
			(type default)
		)
		(layer "In5.Cu")
	)
	(gr_line
		(start 267.806678 -206.243174)
		(end 268.148562 -206.362046)
		(stroke
			(width 0.060198)
			(type default)
		)
		(layer "In5.Cu")
	)
	(gr_line
		(start 267.823696 -205.666594)
		(end 268.49324 -205.899512)
		(stroke
			(width 0.060198)
			(type default)
		)
		(layer "In5.Cu")
	)
	(gr_line
		(start 268.148562 -206.362046)
		(end 268.41704 -206.232252)
		(stroke
			(width 0.060198)
			(type default)
		)
		(layer "In5.Cu")
	)
	(gr_line
		(start 268.763496 -206.352902)
		(end 268.89329 -206.62138)
		(stroke
			(width 0.060198)
			(type default)
		)
		(layer "In5.Cu")
	)
	(gr_line
		(start 268.89329 -206.62138)
		(end 269.235174 -206.740252)
		(stroke
			(width 0.060198)
			(type default)
		)
		(layer "In5.Cu")
	)
	(gr_line
		(start 268.909038 -206.044292)
		(end 269.580106 -206.277972)
		(stroke
			(width 0.060198)
			(type default)
		)
		(layer "In5.Cu")
	)
	(gr_line
		(start 269.064994 -188.618622)
		(end 269.081758 -188.644276)
		(stroke
			(width 0.060198)
			(type default)
		)
		(layer "In5.Cu")
	)
	(gr_line
		(start 269.081758 -188.644276)
		(end 269.10665 -188.660278)
		(stroke
			(width 0.060198)
			(type default)
		)
		(layer "In5.Cu")
	)
	(gr_line
		(start 269.196058 -190.831724)
		(end 269.21206 -190.856616)
		(stroke
			(width 0.060198)
			(type default)
		)
		(layer "In5.Cu")
	)
	(gr_line
		(start 269.21206 -190.856616)
		(end 269.237714 -190.87338)
		(stroke
			(width 0.060198)
			(type default)
		)
		(layer "In5.Cu")
	)
	(gr_line
		(start 269.235174 -206.740252)
		(end 269.503652 -206.610458)
		(stroke
			(width 0.060198)
			(type default)
		)
		(layer "In5.Cu")
	)
	(gr_line
		(start 269.850108 -206.731108)
		(end 269.980156 -206.999586)
		(stroke
			(width 0.060198)
			(type default)
		)
		(layer "In5.Cu")
	)
	(gr_line
		(start 269.963646 -187.512706)
		(end 269.98041 -187.53836)
		(stroke
			(width 0.060198)
			(type default)
		)
		(layer "In5.Cu")
	)
	(gr_line
		(start 269.980156 -206.999586)
		(end 270.321786 -207.118458)
		(stroke
			(width 0.060198)
			(type default)
		)
		(layer "In5.Cu")
	)
	(gr_line
		(start 269.98041 -187.53836)
		(end 270.006064 -187.555124)
		(stroke
			(width 0.060198)
			(type default)
		)
		(layer "In5.Cu")
	)
	(gr_line
		(start 269.996412 -206.422498)
		(end 270.668496 -206.656432)
		(stroke
			(width 0.060198)
			(type default)
		)
		(layer "In5.Cu")
	)
	(gr_line
		(start 270.321786 -207.118458)
		(end 270.590518 -206.988664)
		(stroke
			(width 0.060198)
			(type default)
		)
		(layer "In5.Cu")
	)
	(gr_line
		(start 270.632174 -185.759344)
		(end 270.648938 -185.784998)
		(stroke
			(width 0.060198)
			(type default)
		)
		(layer "In5.Cu")
	)
	(gr_line
		(start 270.648938 -185.784998)
		(end 270.674592 -185.801762)
		(stroke
			(width 0.060198)
			(type default)
		)
		(layer "In5.Cu")
	)
	(gr_line
		(start 271.074896 -183.801004)
		(end 271.09166 -183.826658)
		(stroke
			(width 0.060198)
			(type default)
		)
		(layer "In5.Cu")
	)
	(gr_line
		(start 271.09166 -183.826658)
		(end 271.116552 -183.84266)
		(stroke
			(width 0.060198)
			(type default)
		)
		(layer "In5.Cu")
	)
	(gr_line
		(start 272.498566 -182.272432)
		(end 272.51533 -182.298086)
		(stroke
			(width 0.060198)
			(type default)
		)
		(layer "In5.Cu")
	)
	(gr_line
		(start 272.51533 -182.298086)
		(end 272.540222 -182.314088)
		(stroke
			(width 0.060198)
			(type default)
		)
		(layer "In5.Cu")
	)
	(gr_line
		(start 274.647914 -194.387978)
		(end 274.664932 -194.399154)
		(stroke
			(width 0.060198)
			(type default)
		)
		(layer "In5.Cu")
	)
	(gr_line
		(start 274.664932 -194.399154)
		(end 274.684744 -194.403218)
		(stroke
			(width 0.060198)
			(type default)
		)
		(layer "In5.Cu")
	)
	(gr_line
		(start 275.42744 -192.764664)
		(end 275.444458 -192.77584)
		(stroke
			(width 0.060198)
			(type default)
		)
		(layer "In5.Cu")
	)
	(gr_line
		(start 275.444458 -192.77584)
		(end 275.46427 -192.779904)
		(stroke
			(width 0.060198)
			(type default)
		)
		(layer "In5.Cu")
	)
	(gr_line
		(start 275.511006 -191.130682)
		(end 275.560282 -191.162686)
		(stroke
			(width 0.060198)
			(type default)
		)
		(layer "In5.Cu")
	)
	(gr_line
		(start 276.108414 -189.330584)
		(end 276.15769 -189.362588)
		(stroke
			(width 0.060198)
			(type default)
		)
		(layer "In5.Cu")
	)
	(gr_line
		(start 276.20976 -143.914368)
		(end 276.250146 -143.94053)
		(stroke
			(width 0.06985)
			(type default)
		)
		(layer "In5.Cu")
	)
	(gr_line
		(start 276.451568 -140.314426)
		(end 276.491954 -140.340588)
		(stroke
			(width 0.06985)
			(type default)
		)
		(layer "In5.Cu")
	)
	(gr_line
		(start 276.748748 -142.11427)
		(end 276.789134 -142.140432)
		(stroke
			(width 0.06985)
			(type default)
		)
		(layer "In5.Cu")
	)
	(gr_line
		(start 276.795992 -187.53074)
		(end 276.845268 -187.562744)
		(stroke
			(width 0.060198)
			(type default)
		)
		(layer "In5.Cu")
	)
	(gr_line
		(start 276.830282 -209.15757)
		(end 276.845014 -209.16265)
		(stroke
			(width 0.060198)
			(type default)
		)
		(layer "In5.Cu")
	)
	(gr_line
		(start 276.983698 -136.714484)
		(end 277.024084 -136.740646)
		(stroke
			(width 0.06985)
			(type default)
		)
		(layer "In5.Cu")
	)
	(gr_line
		(start 277.077678 -133.114288)
		(end 277.118064 -133.14045)
		(stroke
			(width 0.06985)
			(type default)
		)
		(layer "In5.Cu")
	)
	(gr_line
		(start 277.218902 -138.514328)
		(end 277.259288 -138.54049)
		(stroke
			(width 0.06985)
			(type default)
		)
		(layer "In5.Cu")
	)
	(gr_line
		(start 277.416514 -134.914386)
		(end 277.4569 -134.940548)
		(stroke
			(width 0.06985)
			(type default)
		)
		(layer "In5.Cu")
	)
	(gr_line
		(start 277.421086 -207.041496)
		(end 277.44928 -207.084676)
		(stroke
			(width 0.060198)
			(type default)
		)
		(layer "In5.Cu")
	)
	(gr_line
		(start 277.44928 -207.084676)
		(end 277.495508 -207.10779)
		(stroke
			(width 0.060198)
			(type default)
		)
		(layer "In5.Cu")
	)
	(gr_line
		(start 277.801578 -185.730642)
		(end 277.850854 -185.762646)
		(stroke
			(width 0.060198)
			(type default)
		)
		(layer "In5.Cu")
	)
	(gr_line
		(start 277.972266 -207.345788)
		(end 278.006556 -207.362806)
		(stroke
			(width 0.060198)
			(type default)
		)
		(layer "In5.Cu")
	)
	(gr_line
		(start 285.436564 -236.89437)
		(end 285.805118 -236.89437)
		(stroke
			(width 0.060198)
			(type default)
		)
		(layer "In5.Cu")
	)
	(gr_line
		(start 285.436564 -233.294428)
		(end 285.805118 -233.294428)
		(stroke
			(width 0.060198)
			(type default)
		)
		(layer "In5.Cu")
	)
	(gr_line
		(start 285.436564 -229.694486)
		(end 285.805118 -229.694486)
		(stroke
			(width 0.060198)
			(type default)
		)
		(layer "In5.Cu")
	)
	(gr_line
		(start 285.436564 -226.094544)
		(end 285.72333 -226.094544)
		(stroke
			(width 0.060198)
			(type default)
		)
		(layer "In5.Cu")
	)
	(gr_line
		(start 285.436564 -222.494348)
		(end 285.780734 -222.494348)
		(stroke
			(width 0.060198)
			(type default)
		)
		(layer "In5.Cu")
	)
	(gr_line
		(start 285.436564 -218.894406)
		(end 285.762192 -218.894406)
		(stroke
			(width 0.060198)
			(type default)
		)
		(layer "In5.Cu")
	)
	(gr_line
		(start 285.436564 -215.294464)
		(end 285.805118 -215.294464)
		(stroke
			(width 0.060198)
			(type default)
		)
		(layer "In5.Cu")
	)
	(gr_line
		(start 285.436564 -211.694522)
		(end 285.805118 -211.694522)
		(stroke
			(width 0.060198)
			(type default)
		)
		(layer "In5.Cu")
	)
	(gr_line
		(start 285.436564 -208.09458)
		(end 285.805118 -208.09458)
		(stroke
			(width 0.060198)
			(type default)
		)
		(layer "In5.Cu")
	)
	(gr_line
		(start 285.436564 -204.494384)
		(end 285.743904 -204.494384)
		(stroke
			(width 0.060198)
			(type default)
		)
		(layer "In5.Cu")
	)
	(gr_line
		(start 285.436564 -200.894442)
		(end 285.743904 -200.894442)
		(stroke
			(width 0.060198)
			(type default)
		)
		(layer "In5.Cu")
	)
	(gr_line
		(start 285.436564 -197.2945)
		(end 285.743904 -197.2945)
		(stroke
			(width 0.060198)
			(type default)
		)
		(layer "In5.Cu")
	)
	(gr_line
		(start 285.436564 -193.694558)
		(end 285.805118 -193.694558)
		(stroke
			(width 0.060198)
			(type default)
		)
		(layer "In5.Cu")
	)
	(gr_line
		(start 285.436564 -190.094362)
		(end 285.805118 -190.094362)
		(stroke
			(width 0.060198)
			(type default)
		)
		(layer "In5.Cu")
	)
	(gr_line
		(start 285.436564 -186.49442)
		(end 285.805118 -186.49442)
		(stroke
			(width 0.060198)
			(type default)
		)
		(layer "In5.Cu")
	)
	(gr_line
		(start 285.436564 -182.894478)
		(end 285.77921 -182.894478)
		(stroke
			(width 0.060198)
			(type default)
		)
		(layer "In5.Cu")
	)
	(gr_line
		(start 285.436564 -179.294536)
		(end 285.77921 -179.294536)
		(stroke
			(width 0.060198)
			(type default)
		)
		(layer "In5.Cu")
	)
	(gr_line
		(start 285.436564 -175.694594)
		(end 285.77921 -175.694594)
		(stroke
			(width 0.060198)
			(type default)
		)
		(layer "In5.Cu")
	)
	(gr_line
		(start 285.436564 -142.894304)
		(end 285.771336 -142.894304)
		(stroke
			(width 0.06985)
			(type default)
		)
		(layer "In5.Cu")
	)
	(gr_line
		(start 285.436564 -139.294362)
		(end 285.771336 -139.294362)
		(stroke
			(width 0.06985)
			(type default)
		)
		(layer "In5.Cu")
	)
	(gr_line
		(start 285.436564 -135.69442)
		(end 285.771336 -135.69442)
		(stroke
			(width 0.06985)
			(type default)
		)
		(layer "In5.Cu")
	)
	(gr_line
		(start 285.436564 -132.094478)
		(end 285.771336 -132.094478)
		(stroke
			(width 0.06985)
			(type default)
		)
		(layer "In5.Cu")
	)
	(gr_arc
		(start 285.743904 -204.494384)
		(mid 285.902495 -204.428693)
		(end 285.968186 -204.270102)
		(stroke
			(width 0.060198)
			(type default)
		)
		(layer "In5.Cu")
	)
	(gr_arc
		(start 285.743904 -200.894442)
		(mid 285.902495 -200.828751)
		(end 285.968186 -200.67016)
		(stroke
			(width 0.060198)
			(type default)
		)
		(layer "In5.Cu")
	)
	(gr_arc
		(start 285.743904 -197.2945)
		(mid 285.902495 -197.228809)
		(end 285.968186 -197.070218)
		(stroke
			(width 0.060198)
			(type default)
		)
		(layer "In5.Cu")
	)
	(gr_arc
		(start 285.771336 -142.894304)
		(mid 285.926335 -142.830101)
		(end 285.990538 -142.675102)
		(stroke
			(width 0.06985)
			(type default)
		)
		(layer "In5.Cu")
	)
	(gr_arc
		(start 285.771336 -139.294362)
		(mid 285.926335 -139.230159)
		(end 285.990538 -139.07516)
		(stroke
			(width 0.06985)
			(type default)
		)
		(layer "In5.Cu")
	)
	(gr_arc
		(start 285.771336 -135.69442)
		(mid 285.926335 -135.630217)
		(end 285.990538 -135.475218)
		(stroke
			(width 0.06985)
			(type default)
		)
		(layer "In5.Cu")
	)
	(gr_arc
		(start 285.771336 -132.094478)
		(mid 285.926335 -132.030275)
		(end 285.990538 -131.875276)
		(stroke
			(width 0.06985)
			(type default)
		)
		(layer "In5.Cu")
	)
	(gr_arc
		(start 285.77921 -182.894478)
		(mid 285.912836 -182.839128)
		(end 285.968186 -182.705502)
		(stroke
			(width 0.060198)
			(type default)
		)
		(layer "In5.Cu")
	)
	(gr_arc
		(start 285.77921 -179.294536)
		(mid 285.912836 -179.239186)
		(end 285.968186 -179.10556)
		(stroke
			(width 0.060198)
			(type default)
		)
		(layer "In5.Cu")
	)
	(gr_arc
		(start 285.77921 -175.694594)
		(mid 285.912836 -175.639244)
		(end 285.968186 -175.505618)
		(stroke
			(width 0.060198)
			(type default)
		)
		(layer "In5.Cu")
	)
	(gr_arc
		(start 285.805118 -236.89437)
		(mid 285.920424 -236.846608)
		(end 285.968186 -236.731302)
		(stroke
			(width 0.060198)
			(type default)
		)
		(layer "In5.Cu")
	)
	(gr_arc
		(start 285.805118 -233.294428)
		(mid 285.920424 -233.246666)
		(end 285.968186 -233.13136)
		(stroke
			(width 0.060198)
			(type default)
		)
		(layer "In5.Cu")
	)
	(gr_arc
		(start 285.805118 -229.694486)
		(mid 285.920424 -229.646724)
		(end 285.968186 -229.531418)
		(stroke
			(width 0.060198)
			(type default)
		)
		(layer "In5.Cu")
	)
	(gr_arc
		(start 285.805118 -215.294464)
		(mid 285.920424 -215.246702)
		(end 285.968186 -215.131396)
		(stroke
			(width 0.060198)
			(type default)
		)
		(layer "In5.Cu")
	)
	(gr_arc
		(start 285.805118 -211.694522)
		(mid 285.920424 -211.64676)
		(end 285.968186 -211.531454)
		(stroke
			(width 0.060198)
			(type default)
		)
		(layer "In5.Cu")
	)
	(gr_arc
		(start 285.805118 -208.09458)
		(mid 285.920424 -208.046818)
		(end 285.968186 -207.931512)
		(stroke
			(width 0.060198)
			(type default)
		)
		(layer "In5.Cu")
	)
	(gr_arc
		(start 285.805118 -193.694558)
		(mid 285.920424 -193.646796)
		(end 285.968186 -193.53149)
		(stroke
			(width 0.060198)
			(type default)
		)
		(layer "In5.Cu")
	)
	(gr_arc
		(start 285.805118 -190.094362)
		(mid 285.920424 -190.0466)
		(end 285.968186 -189.931294)
		(stroke
			(width 0.060198)
			(type default)
		)
		(layer "In5.Cu")
	)
	(gr_arc
		(start 285.805118 -186.49442)
		(mid 285.920424 -186.446658)
		(end 285.968186 -186.331352)
		(stroke
			(width 0.060198)
			(type default)
		)
		(layer "In5.Cu")
	)
	(gr_arc
		(start 285.968186 -226.3394)
		(mid 285.896471 -226.16625)
		(end 285.72333 -226.094544)
		(stroke
			(width 0.060198)
			(type default)
		)
		(layer "In5.Cu")
	)
	(gr_arc
		(start 285.968186 -222.6818)
		(mid 285.913285 -222.549239)
		(end 285.780734 -222.494348)
		(stroke
			(width 0.060198)
			(type default)
		)
		(layer "In5.Cu")
	)
	(gr_arc
		(start 285.968186 -219.1004)
		(mid 285.907851 -218.954743)
		(end 285.762192 -218.894406)
		(stroke
			(width 0.060198)
			(type default)
		)
		(layer "In5.Cu")
	)
	(gr_line
		(start 286.224726 -130.76174)
		(end 286.282638 -130.819398)
		(stroke
			(width 0.06985)
			(type default)
		)
		(layer "In5.Cu")
	)
	(gr_arc
		(start 286.282638 -142.675102)
		(mid 286.346844 -142.830086)
		(end 286.50184 -142.894304)
		(stroke
			(width 0.06985)
			(type default)
		)
		(layer "In5.Cu")
	)
	(gr_arc
		(start 286.282638 -139.07516)
		(mid 286.346829 -139.230171)
		(end 286.50184 -139.294362)
		(stroke
			(width 0.06985)
			(type default)
		)
		(layer "In5.Cu")
	)
	(gr_arc
		(start 286.282638 -135.475218)
		(mid 286.34685 -135.630191)
		(end 286.50184 -135.69442)
		(stroke
			(width 0.06985)
			(type default)
		)
		(layer "In5.Cu")
	)
	(gr_arc
		(start 286.282638 -131.875276)
		(mid 286.346835 -132.030277)
		(end 286.50184 -132.094478)
		(stroke
			(width 0.06985)
			(type default)
		)
		(layer "In5.Cu")
	)
	(gr_line
		(start 286.301434 -174.672244)
		(end 286.332422 -174.660814)
		(stroke
			(width 0.060198)
			(type default)
		)
		(layer "In5.Cu")
	)
	(gr_arc
		(start 286.304736 -236.731302)
		(mid 286.352498 -236.846606)
		(end 286.467804 -236.89437)
		(stroke
			(width 0.060198)
			(type default)
		)
		(layer "In5.Cu")
	)
	(gr_arc
		(start 286.304736 -233.13136)
		(mid 286.352484 -233.246691)
		(end 286.467804 -233.294428)
		(stroke
			(width 0.060198)
			(type default)
		)
		(layer "In5.Cu")
	)
	(gr_arc
		(start 286.304736 -229.531418)
		(mid 286.352504 -229.646711)
		(end 286.467804 -229.694486)
		(stroke
			(width 0.060198)
			(type default)
		)
		(layer "In5.Cu")
	)
	(gr_arc
		(start 286.304736 -215.131396)
		(mid 286.352496 -215.246704)
		(end 286.467804 -215.294464)
		(stroke
			(width 0.060198)
			(type default)
		)
		(layer "In5.Cu")
	)
	(gr_arc
		(start 286.304736 -211.531454)
		(mid 286.352481 -211.646789)
		(end 286.467804 -211.694522)
		(stroke
			(width 0.060198)
			(type default)
		)
		(layer "In5.Cu")
	)
	(gr_arc
		(start 286.304736 -207.931512)
		(mid 286.352502 -208.046809)
		(end 286.467804 -208.09458)
		(stroke
			(width 0.060198)
			(type default)
		)
		(layer "In5.Cu")
	)
	(gr_arc
		(start 286.304736 -204.270102)
		(mid 286.370428 -204.428686)
		(end 286.529018 -204.494384)
		(stroke
			(width 0.060198)
			(type default)
		)
		(layer "In5.Cu")
	)
	(gr_arc
		(start 286.304736 -200.67016)
		(mid 286.370414 -200.828771)
		(end 286.529018 -200.894442)
		(stroke
			(width 0.060198)
			(type default)
		)
		(layer "In5.Cu")
	)
	(gr_arc
		(start 286.304736 -197.070218)
		(mid 286.370434 -197.228791)
		(end 286.529018 -197.2945)
		(stroke
			(width 0.060198)
			(type default)
		)
		(layer "In5.Cu")
	)
	(gr_arc
		(start 286.304736 -193.53149)
		(mid 286.352494 -193.646802)
		(end 286.467804 -193.694558)
		(stroke
			(width 0.060198)
			(type default)
		)
		(layer "In5.Cu")
	)
	(gr_arc
		(start 286.304736 -189.931294)
		(mid 286.352496 -190.046603)
		(end 286.467804 -190.094362)
		(stroke
			(width 0.060198)
			(type default)
		)
		(layer "In5.Cu")
	)
	(gr_arc
		(start 286.304736 -186.331352)
		(mid 286.352481 -186.446688)
		(end 286.467804 -186.49442)
		(stroke
			(width 0.060198)
			(type default)
		)
		(layer "In5.Cu")
	)
	(gr_arc
		(start 286.304736 -182.705502)
		(mid 286.360087 -182.839123)
		(end 286.493712 -182.894478)
		(stroke
			(width 0.060198)
			(type default)
		)
		(layer "In5.Cu")
	)
	(gr_arc
		(start 286.304736 -179.10556)
		(mid 286.360072 -179.239208)
		(end 286.493712 -179.294536)
		(stroke
			(width 0.060198)
			(type default)
		)
		(layer "In5.Cu")
	)
	(gr_arc
		(start 286.304736 -175.505618)
		(mid 286.360093 -175.639228)
		(end 286.493712 -175.694594)
		(stroke
			(width 0.060198)
			(type default)
		)
		(layer "In5.Cu")
	)
	(gr_line
		(start 286.436562 -238.694468)
		(end 286.805116 -238.694468)
		(stroke
			(width 0.060198)
			(type default)
		)
		(layer "In5.Cu")
	)
	(gr_line
		(start 286.436562 -235.094526)
		(end 286.805116 -235.094526)
		(stroke
			(width 0.060198)
			(type default)
		)
		(layer "In5.Cu")
	)
	(gr_line
		(start 286.436562 -231.494584)
		(end 286.805116 -231.494584)
		(stroke
			(width 0.060198)
			(type default)
		)
		(layer "In5.Cu")
	)
	(gr_line
		(start 286.436562 -227.894388)
		(end 286.770572 -227.894388)
		(stroke
			(width 0.060198)
			(type default)
		)
		(layer "In5.Cu")
	)
	(gr_line
		(start 286.436562 -224.294446)
		(end 286.777684 -224.294446)
		(stroke
			(width 0.060198)
			(type default)
		)
		(layer "In5.Cu")
	)
	(gr_line
		(start 286.436562 -220.694504)
		(end 286.784288 -220.694504)
		(stroke
			(width 0.060198)
			(type default)
		)
		(layer "In5.Cu")
	)
	(gr_line
		(start 286.436562 -217.094562)
		(end 286.805116 -217.094562)
		(stroke
			(width 0.060198)
			(type default)
		)
		(layer "In5.Cu")
	)
	(gr_line
		(start 286.436562 -213.494366)
		(end 286.805116 -213.494366)
		(stroke
			(width 0.060198)
			(type default)
		)
		(layer "In5.Cu")
	)
	(gr_line
		(start 286.436562 -209.894424)
		(end 286.805116 -209.894424)
		(stroke
			(width 0.060198)
			(type default)
		)
		(layer "In5.Cu")
	)
	(gr_line
		(start 286.436562 -206.294482)
		(end 286.743902 -206.294482)
		(stroke
			(width 0.060198)
			(type default)
		)
		(layer "In5.Cu")
	)
	(gr_line
		(start 286.436562 -202.69454)
		(end 286.743902 -202.69454)
		(stroke
			(width 0.060198)
			(type default)
		)
		(layer "In5.Cu")
	)
	(gr_line
		(start 286.436562 -199.094344)
		(end 286.743902 -199.094344)
		(stroke
			(width 0.060198)
			(type default)
		)
		(layer "In5.Cu")
	)
	(gr_line
		(start 286.436562 -195.494402)
		(end 286.805116 -195.494402)
		(stroke
			(width 0.060198)
			(type default)
		)
		(layer "In5.Cu")
	)
	(gr_line
		(start 286.436562 -191.89446)
		(end 286.805116 -191.89446)
		(stroke
			(width 0.060198)
			(type default)
		)
		(layer "In5.Cu")
	)
	(gr_line
		(start 286.436562 -188.294518)
		(end 286.805116 -188.294518)
		(stroke
			(width 0.060198)
			(type default)
		)
		(layer "In5.Cu")
	)
	(gr_line
		(start 286.436562 -184.694576)
		(end 286.779208 -184.694576)
		(stroke
			(width 0.060198)
			(type default)
		)
		(layer "In5.Cu")
	)
	(gr_line
		(start 286.436562 -181.09438)
		(end 286.779208 -181.09438)
		(stroke
			(width 0.060198)
			(type default)
		)
		(layer "In5.Cu")
	)
	(gr_line
		(start 286.436562 -177.494438)
		(end 286.779208 -177.494438)
		(stroke
			(width 0.060198)
			(type default)
		)
		(layer "In5.Cu")
	)
	(gr_line
		(start 286.436562 -144.694402)
		(end 286.771334 -144.694402)
		(stroke
			(width 0.06985)
			(type default)
		)
		(layer "In5.Cu")
	)
	(gr_line
		(start 286.436562 -141.09446)
		(end 286.771334 -141.09446)
		(stroke
			(width 0.06985)
			(type default)
		)
		(layer "In5.Cu")
	)
	(gr_line
		(start 286.436562 -137.494518)
		(end 286.771334 -137.494518)
		(stroke
			(width 0.06985)
			(type default)
		)
		(layer "In5.Cu")
	)
	(gr_line
		(start 286.436562 -133.894322)
		(end 286.771334 -133.894322)
		(stroke
			(width 0.06985)
			(type default)
		)
		(layer "In5.Cu")
	)
	(gr_line
		(start 286.467804 -236.89437)
		(end 286.836612 -236.89437)
		(stroke
			(width 0.060198)
			(type default)
		)
		(layer "In5.Cu")
	)
	(gr_line
		(start 286.467804 -233.294428)
		(end 286.836612 -233.294428)
		(stroke
			(width 0.060198)
			(type default)
		)
		(layer "In5.Cu")
	)
	(gr_line
		(start 286.467804 -229.694486)
		(end 286.836612 -229.694486)
		(stroke
			(width 0.060198)
			(type default)
		)
		(layer "In5.Cu")
	)
	(gr_line
		(start 286.467804 -215.294464)
		(end 286.836612 -215.294464)
		(stroke
			(width 0.060198)
			(type default)
		)
		(layer "In5.Cu")
	)
	(gr_line
		(start 286.467804 -211.694522)
		(end 286.836612 -211.694522)
		(stroke
			(width 0.060198)
			(type default)
		)
		(layer "In5.Cu")
	)
	(gr_line
		(start 286.467804 -208.09458)
		(end 286.836612 -208.09458)
		(stroke
			(width 0.060198)
			(type default)
		)
		(layer "In5.Cu")
	)
	(gr_line
		(start 286.467804 -193.694558)
		(end 286.836612 -193.694558)
		(stroke
			(width 0.060198)
			(type default)
		)
		(layer "In5.Cu")
	)
	(gr_line
		(start 286.467804 -190.094362)
		(end 286.836612 -190.094362)
		(stroke
			(width 0.060198)
			(type default)
		)
		(layer "In5.Cu")
	)
	(gr_line
		(start 286.467804 -186.49442)
		(end 286.836612 -186.49442)
		(stroke
			(width 0.060198)
			(type default)
		)
		(layer "In5.Cu")
	)
	(gr_arc
		(start 286.492188 -222.494348)
		(mid 286.359639 -222.549251)
		(end 286.304736 -222.6818)
		(stroke
			(width 0.060198)
			(type default)
		)
		(layer "In5.Cu")
	)
	(gr_line
		(start 286.492188 -222.494348)
		(end 286.836612 -222.494348)
		(stroke
			(width 0.060198)
			(type default)
		)
		(layer "In5.Cu")
	)
	(gr_line
		(start 286.493712 -182.894478)
		(end 286.836612 -182.894478)
		(stroke
			(width 0.060198)
			(type default)
		)
		(layer "In5.Cu")
	)
	(gr_line
		(start 286.493712 -179.294536)
		(end 286.836612 -179.294536)
		(stroke
			(width 0.060198)
			(type default)
		)
		(layer "In5.Cu")
	)
	(gr_line
		(start 286.493712 -175.694594)
		(end 286.836612 -175.694594)
		(stroke
			(width 0.060198)
			(type default)
		)
		(layer "In5.Cu")
	)
	(gr_line
		(start 286.50184 -142.894304)
		(end 286.836612 -142.894304)
		(stroke
			(width 0.06985)
			(type default)
		)
		(layer "In5.Cu")
	)
	(gr_line
		(start 286.50184 -139.294362)
		(end 286.836612 -139.294362)
		(stroke
			(width 0.06985)
			(type default)
		)
		(layer "In5.Cu")
	)
	(gr_line
		(start 286.50184 -135.69442)
		(end 286.836612 -135.69442)
		(stroke
			(width 0.06985)
			(type default)
		)
		(layer "In5.Cu")
	)
	(gr_line
		(start 286.50184 -132.094478)
		(end 286.836612 -132.094478)
		(stroke
			(width 0.06985)
			(type default)
		)
		(layer "In5.Cu")
	)
	(gr_arc
		(start 286.51073 -218.894406)
		(mid 286.36507 -218.95474)
		(end 286.304736 -219.1004)
		(stroke
			(width 0.060198)
			(type default)
		)
		(layer "In5.Cu")
	)
	(gr_line
		(start 286.51073 -218.894406)
		(end 286.836612 -218.894406)
		(stroke
			(width 0.060198)
			(type default)
		)
		(layer "In5.Cu")
	)
	(gr_line
		(start 286.529018 -204.494384)
		(end 286.836612 -204.494384)
		(stroke
			(width 0.060198)
			(type default)
		)
		(layer "In5.Cu")
	)
	(gr_line
		(start 286.529018 -200.894442)
		(end 286.836612 -200.894442)
		(stroke
			(width 0.060198)
			(type default)
		)
		(layer "In5.Cu")
	)
	(gr_line
		(start 286.529018 -197.2945)
		(end 286.836612 -197.2945)
		(stroke
			(width 0.060198)
			(type default)
		)
		(layer "In5.Cu")
	)
	(gr_arc
		(start 286.549592 -226.094544)
		(mid 286.376453 -226.166261)
		(end 286.304736 -226.3394)
		(stroke
			(width 0.060198)
			(type default)
		)
		(layer "In5.Cu")
	)
	(gr_line
		(start 286.549592 -226.094544)
		(end 286.836612 -226.094544)
		(stroke
			(width 0.060198)
			(type default)
		)
		(layer "In5.Cu")
	)
	(gr_arc
		(start 286.743902 -206.294482)
		(mid 286.902493 -206.228791)
		(end 286.968184 -206.0702)
		(stroke
			(width 0.060198)
			(type default)
		)
		(layer "In5.Cu")
	)
	(gr_arc
		(start 286.743902 -202.69454)
		(mid 286.902493 -202.628849)
		(end 286.968184 -202.470258)
		(stroke
			(width 0.060198)
			(type default)
		)
		(layer "In5.Cu")
	)
	(gr_arc
		(start 286.743902 -199.094344)
		(mid 286.902493 -199.028653)
		(end 286.968184 -198.870062)
		(stroke
			(width 0.060198)
			(type default)
		)
		(layer "In5.Cu")
	)
	(gr_arc
		(start 286.771334 -144.694402)
		(mid 286.926333 -144.630199)
		(end 286.990536 -144.4752)
		(stroke
			(width 0.06985)
			(type default)
		)
		(layer "In5.Cu")
	)
	(gr_arc
		(start 286.771334 -141.09446)
		(mid 286.926333 -141.030257)
		(end 286.990536 -140.875258)
		(stroke
			(width 0.06985)
			(type default)
		)
		(layer "In5.Cu")
	)
	(gr_arc
		(start 286.771334 -137.494518)
		(mid 286.926333 -137.430315)
		(end 286.990536 -137.275316)
		(stroke
			(width 0.06985)
			(type default)
		)
		(layer "In5.Cu")
	)
	(gr_arc
		(start 286.771334 -133.894322)
		(mid 286.926333 -133.830119)
		(end 286.990536 -133.67512)
		(stroke
			(width 0.06985)
			(type default)
		)
		(layer "In5.Cu")
	)
	(gr_arc
		(start 286.779208 -184.694576)
		(mid 286.912834 -184.639226)
		(end 286.968184 -184.5056)
		(stroke
			(width 0.060198)
			(type default)
		)
		(layer "In5.Cu")
	)
	(gr_arc
		(start 286.779208 -181.09438)
		(mid 286.912834 -181.03903)
		(end 286.968184 -180.905404)
		(stroke
			(width 0.060198)
			(type default)
		)
		(layer "In5.Cu")
	)
	(gr_arc
		(start 286.779208 -177.494438)
		(mid 286.912834 -177.439088)
		(end 286.968184 -177.305462)
		(stroke
			(width 0.060198)
			(type default)
		)
		(layer "In5.Cu")
	)
	(gr_arc
		(start 286.805116 -238.694468)
		(mid 286.920422 -238.646706)
		(end 286.968184 -238.5314)
		(stroke
			(width 0.060198)
			(type default)
		)
		(layer "In5.Cu")
	)
	(gr_arc
		(start 286.805116 -235.094526)
		(mid 286.920422 -235.046764)
		(end 286.968184 -234.931458)
		(stroke
			(width 0.060198)
			(type default)
		)
		(layer "In5.Cu")
	)
	(gr_arc
		(start 286.805116 -231.494584)
		(mid 286.920422 -231.446822)
		(end 286.968184 -231.331516)
		(stroke
			(width 0.060198)
			(type default)
		)
		(layer "In5.Cu")
	)
	(gr_arc
		(start 286.805116 -217.094562)
		(mid 286.920422 -217.0468)
		(end 286.968184 -216.931494)
		(stroke
			(width 0.060198)
			(type default)
		)
		(layer "In5.Cu")
	)
	(gr_arc
		(start 286.805116 -213.494366)
		(mid 286.920422 -213.446604)
		(end 286.968184 -213.331298)
		(stroke
			(width 0.060198)
			(type default)
		)
		(layer "In5.Cu")
	)
	(gr_arc
		(start 286.805116 -209.894424)
		(mid 286.920422 -209.846662)
		(end 286.968184 -209.731356)
		(stroke
			(width 0.060198)
			(type default)
		)
		(layer "In5.Cu")
	)
	(gr_arc
		(start 286.805116 -195.494402)
		(mid 286.920422 -195.44664)
		(end 286.968184 -195.331334)
		(stroke
			(width 0.060198)
			(type default)
		)
		(layer "In5.Cu")
	)
	(gr_arc
		(start 286.805116 -191.89446)
		(mid 286.920422 -191.846698)
		(end 286.968184 -191.731392)
		(stroke
			(width 0.060198)
			(type default)
		)
		(layer "In5.Cu")
	)
	(gr_arc
		(start 286.805116 -188.294518)
		(mid 286.920422 -188.246756)
		(end 286.968184 -188.13145)
		(stroke
			(width 0.060198)
			(type default)
		)
		(layer "In5.Cu")
	)
	(gr_arc
		(start 286.968184 -228.092)
		(mid 286.910303 -227.952277)
		(end 286.770572 -227.894388)
		(stroke
			(width 0.060198)
			(type default)
		)
		(layer "In5.Cu")
	)
	(gr_arc
		(start 286.968184 -224.484946)
		(mid 286.912403 -224.350218)
		(end 286.777684 -224.294446)
		(stroke
			(width 0.060198)
			(type default)
		)
		(layer "In5.Cu")
	)
	(gr_arc
		(start 286.968184 -220.8784)
		(mid 286.914321 -220.74837)
		(end 286.784288 -220.694504)
		(stroke
			(width 0.060198)
			(type default)
		)
		(layer "In5.Cu")
	)
	(gr_arc
		(start 287.282636 -144.4752)
		(mid 287.346841 -144.630186)
		(end 287.501838 -144.694402)
		(stroke
			(width 0.06985)
			(type default)
		)
		(layer "In5.Cu")
	)
	(gr_arc
		(start 287.282636 -140.875258)
		(mid 287.346826 -141.030271)
		(end 287.501838 -141.09446)
		(stroke
			(width 0.06985)
			(type default)
		)
		(layer "In5.Cu")
	)
	(gr_arc
		(start 287.282636 -137.275316)
		(mid 287.346847 -137.430291)
		(end 287.501838 -137.494518)
		(stroke
			(width 0.06985)
			(type default)
		)
		(layer "In5.Cu")
	)
	(gr_arc
		(start 287.282636 -133.67512)
		(mid 287.346848 -133.830093)
		(end 287.501838 -133.894322)
		(stroke
			(width 0.06985)
			(type default)
		)
		(layer "In5.Cu")
	)
	(gr_arc
		(start 287.304734 -238.5314)
		(mid 287.352496 -238.646706)
		(end 287.467802 -238.694468)
		(stroke
			(width 0.060198)
			(type default)
		)
		(layer "In5.Cu")
	)
	(gr_arc
		(start 287.304734 -234.931458)
		(mid 287.352481 -235.046791)
		(end 287.467802 -235.094526)
		(stroke
			(width 0.060198)
			(type default)
		)
		(layer "In5.Cu")
	)
	(gr_arc
		(start 287.304734 -231.331516)
		(mid 287.352501 -231.446811)
		(end 287.467802 -231.494584)
		(stroke
			(width 0.060198)
			(type default)
		)
		(layer "In5.Cu")
	)
	(gr_arc
		(start 287.304734 -216.931494)
		(mid 287.352494 -217.046804)
		(end 287.467802 -217.094562)
		(stroke
			(width 0.060198)
			(type default)
		)
		(layer "In5.Cu")
	)
	(gr_arc
		(start 287.304734 -213.331298)
		(mid 287.352495 -213.446605)
		(end 287.467802 -213.494366)
		(stroke
			(width 0.060198)
			(type default)
		)
		(layer "In5.Cu")
	)
	(gr_arc
		(start 287.304734 -209.731356)
		(mid 287.35248 -209.84669)
		(end 287.467802 -209.894424)
		(stroke
			(width 0.060198)
			(type default)
		)
		(layer "In5.Cu")
	)
	(gr_arc
		(start 287.304734 -206.0702)
		(mid 287.370426 -206.228786)
		(end 287.529016 -206.294482)
		(stroke
			(width 0.060198)
			(type default)
		)
		(layer "In5.Cu")
	)
	(gr_arc
		(start 287.304734 -202.470258)
		(mid 287.370411 -202.628871)
		(end 287.529016 -202.69454)
		(stroke
			(width 0.060198)
			(type default)
		)
		(layer "In5.Cu")
	)
	(gr_arc
		(start 287.304734 -198.870062)
		(mid 287.370412 -199.028672)
		(end 287.529016 -199.094344)
		(stroke
			(width 0.060198)
			(type default)
		)
		(layer "In5.Cu")
	)
	(gr_arc
		(start 287.304734 -195.331334)
		(mid 287.352508 -195.446618)
		(end 287.467802 -195.494402)
		(stroke
			(width 0.060198)
			(type default)
		)
		(layer "In5.Cu")
	)
	(gr_arc
		(start 287.304734 -191.731392)
		(mid 287.352493 -191.846703)
		(end 287.467802 -191.89446)
		(stroke
			(width 0.060198)
			(type default)
		)
		(layer "In5.Cu")
	)
	(gr_arc
		(start 287.304734 -188.13145)
		(mid 287.352513 -188.246723)
		(end 287.467802 -188.294518)
		(stroke
			(width 0.060198)
			(type default)
		)
		(layer "In5.Cu")
	)
	(gr_arc
		(start 287.304734 -184.5056)
		(mid 287.360084 -184.639223)
		(end 287.49371 -184.694576)
		(stroke
			(width 0.060198)
			(type default)
		)
		(layer "In5.Cu")
	)
	(gr_arc
		(start 287.304734 -180.905404)
		(mid 287.360086 -181.039024)
		(end 287.49371 -181.09438)
		(stroke
			(width 0.060198)
			(type default)
		)
		(layer "In5.Cu")
	)
	(gr_arc
		(start 287.304734 -177.305462)
		(mid 287.360071 -177.439109)
		(end 287.49371 -177.494438)
		(stroke
			(width 0.060198)
			(type default)
		)
		(layer "In5.Cu")
	)
	(gr_line
		(start 287.467802 -238.694468)
		(end 287.83661 -238.694468)
		(stroke
			(width 0.060198)
			(type default)
		)
		(layer "In5.Cu")
	)
	(gr_line
		(start 287.467802 -235.094526)
		(end 287.83661 -235.094526)
		(stroke
			(width 0.060198)
			(type default)
		)
		(layer "In5.Cu")
	)
	(gr_line
		(start 287.467802 -231.494584)
		(end 287.83661 -231.494584)
		(stroke
			(width 0.060198)
			(type default)
		)
		(layer "In5.Cu")
	)
	(gr_line
		(start 287.467802 -217.094562)
		(end 287.83661 -217.094562)
		(stroke
			(width 0.060198)
			(type default)
		)
		(layer "In5.Cu")
	)
	(gr_line
		(start 287.467802 -213.494366)
		(end 287.83661 -213.494366)
		(stroke
			(width 0.060198)
			(type default)
		)
		(layer "In5.Cu")
	)
	(gr_line
		(start 287.467802 -209.894424)
		(end 287.83661 -209.894424)
		(stroke
			(width 0.060198)
			(type default)
		)
		(layer "In5.Cu")
	)
	(gr_line
		(start 287.467802 -195.494402)
		(end 287.83661 -195.494402)
		(stroke
			(width 0.060198)
			(type default)
		)
		(layer "In5.Cu")
	)
	(gr_line
		(start 287.467802 -191.89446)
		(end 287.83661 -191.89446)
		(stroke
			(width 0.060198)
			(type default)
		)
		(layer "In5.Cu")
	)
	(gr_line
		(start 287.467802 -188.294518)
		(end 287.83661 -188.294518)
		(stroke
			(width 0.060198)
			(type default)
		)
		(layer "In5.Cu")
	)
	(gr_arc
		(start 287.48863 -220.694504)
		(mid 287.358596 -220.748366)
		(end 287.304734 -220.8784)
		(stroke
			(width 0.060198)
			(type default)
		)
		(layer "In5.Cu")
	)
	(gr_line
		(start 287.48863 -220.694504)
		(end 287.83661 -220.694504)
		(stroke
			(width 0.060198)
			(type default)
		)
		(layer "In5.Cu")
	)
	(gr_line
		(start 287.49371 -184.694576)
		(end 287.83661 -184.694576)
		(stroke
			(width 0.060198)
			(type default)
		)
		(layer "In5.Cu")
	)
	(gr_line
		(start 287.49371 -181.09438)
		(end 287.83661 -181.09438)
		(stroke
			(width 0.060198)
			(type default)
		)
		(layer "In5.Cu")
	)
	(gr_line
		(start 287.49371 -177.494438)
		(end 287.83661 -177.494438)
		(stroke
			(width 0.060198)
			(type default)
		)
		(layer "In5.Cu")
	)
	(gr_arc
		(start 287.495488 -224.294446)
		(mid 287.360605 -224.350317)
		(end 287.304734 -224.4852)
		(stroke
			(width 0.060198)
			(type default)
		)
		(layer "In5.Cu")
	)
	(gr_line
		(start 287.495488 -224.294446)
		(end 287.83661 -224.294446)
		(stroke
			(width 0.060198)
			(type default)
		)
		(layer "In5.Cu")
	)
	(gr_line
		(start 287.501838 -144.694402)
		(end 287.83661 -144.694402)
		(stroke
			(width 0.06985)
			(type default)
		)
		(layer "In5.Cu")
	)
	(gr_line
		(start 287.501838 -141.09446)
		(end 287.83661 -141.09446)
		(stroke
			(width 0.06985)
			(type default)
		)
		(layer "In5.Cu")
	)
	(gr_line
		(start 287.501838 -137.494518)
		(end 287.83661 -137.494518)
		(stroke
			(width 0.06985)
			(type default)
		)
		(layer "In5.Cu")
	)
	(gr_line
		(start 287.501838 -133.894322)
		(end 287.83661 -133.894322)
		(stroke
			(width 0.06985)
			(type default)
		)
		(layer "In5.Cu")
	)
	(gr_arc
		(start 287.502346 -227.894388)
		(mid 287.362613 -227.952267)
		(end 287.304734 -228.092)
		(stroke
			(width 0.060198)
			(type default)
		)
		(layer "In5.Cu")
	)
	(gr_line
		(start 287.502346 -227.894388)
		(end 287.83661 -227.894388)
		(stroke
			(width 0.060198)
			(type default)
		)
		(layer "In5.Cu")
	)
	(gr_line
		(start 287.529016 -206.294482)
		(end 287.83661 -206.294482)
		(stroke
			(width 0.060198)
			(type default)
		)
		(layer "In5.Cu")
	)
	(gr_line
		(start 287.529016 -202.69454)
		(end 287.83661 -202.69454)
		(stroke
			(width 0.060198)
			(type default)
		)
		(layer "In5.Cu")
	)
	(gr_line
		(start 287.529016 -199.094344)
		(end 287.83661 -199.094344)
		(stroke
			(width 0.060198)
			(type default)
		)
		(layer "In5.Cu")
	)
	(gr_line
		(start 288.455608 -176.762664)
		(end 288.504884 -176.73066)
		(stroke
			(width 0.060198)
			(type default)
		)
		(layer "In5.Cu")
	)
	(gr_line
		(start 289.516566 -198.36257)
		(end 289.531806 -198.356982)
		(stroke
			(width 0.060198)
			(type default)
		)
		(layer "In5.Cu")
	)
	(gr_line
		(start 289.969448 -196.562726)
		(end 290.00577 -196.54393)
		(stroke
			(width 0.060198)
			(type default)
		)
		(layer "In5.Cu")
	)
	(gr_line
		(start 290.005008 -178.562762)
		(end 290.054284 -178.530758)
		(stroke
			(width 0.060198)
			(type default)
		)
		(layer "In5.Cu")
	)
	(gr_line
		(start 290.098734 -182.162704)
		(end 290.14801 -182.1307)
		(stroke
			(width 0.060198)
			(type default)
		)
		(layer "In5.Cu")
	)
	(gr_line
		(start 290.18865 -183.962802)
		(end 290.237926 -183.930798)
		(stroke
			(width 0.060198)
			(type default)
		)
		(layer "In5.Cu")
	)
	(gr_line
		(start 290.195508 -180.362606)
		(end 290.244784 -180.330602)
		(stroke
			(width 0.060198)
			(type default)
		)
		(layer "In5.Cu")
	)
	(gr_line
		(start 290.585144 -226.826318)
		(end 290.586668 -226.826572)
		(stroke
			(width 0.060198)
			(type default)
		)
		(layer "In5.Cu")
	)
	(gr_line
		(start 291.04463 -228.626162)
		(end 291.093906 -228.658166)
		(stroke
			(width 0.060198)
			(type default)
		)
		(layer "In5.Cu")
	)
	(gr_line
		(start 295.164256 -170.789854)
		(end 295.189148 -170.773852)
		(stroke
			(width 0.060198)
			(type default)
		)
		(layer "In5.Cu")
	)
	(gr_line
		(start 295.189148 -170.773852)
		(end 295.205912 -170.748198)
		(stroke
			(width 0.060198)
			(type default)
		)
		(layer "In5.Cu")
	)
	(gr_line
		(start 295.436544 -193.734436)
		(end 295.48455 -193.709544)
		(stroke
			(width 0.060198)
			(type default)
		)
		(layer "In5.Cu")
	)
	(gr_line
		(start 295.48455 -193.709544)
		(end 295.512744 -193.664078)
		(stroke
			(width 0.060198)
			(type default)
		)
		(layer "In5.Cu")
	)
	(gr_line
		(start 297.366182 -170.975528)
		(end 297.391836 -170.958764)
		(stroke
			(width 0.060198)
			(type default)
		)
		(layer "In5.Cu")
	)
	(gr_line
		(start 297.391836 -170.958764)
		(end 297.4086 -170.93311)
		(stroke
			(width 0.060198)
			(type default)
		)
		(layer "In5.Cu")
	)
	(gr_line
		(start 300.998636 -161.828734)
		(end 301.013368 -161.805874)
		(stroke
			(width 0.060198)
			(type default)
		)
		(layer "In5.Cu")
	)
	(gr_line
		(start 301.00905 -171.417234)
		(end 301.033942 -171.401232)
		(stroke
			(width 0.060198)
			(type default)
		)
		(layer "In5.Cu")
	)
	(gr_line
		(start 301.013368 -161.805874)
		(end 301.01794 -161.779966)
		(stroke
			(width 0.060198)
			(type default)
		)
		(layer "In5.Cu")
	)
	(gr_line
		(start 301.033942 -171.401232)
		(end 301.049944 -171.37634)
		(stroke
			(width 0.060198)
			(type default)
		)
		(layer "In5.Cu")
	)
	(gr_line
		(start 302.103282 -172.630084)
		(end 302.128682 -172.613574)
		(stroke
			(width 0.060198)
			(type default)
		)
		(layer "In5.Cu")
	)
	(gr_line
		(start 302.128682 -172.613574)
		(end 302.144938 -172.588174)
		(stroke
			(width 0.060198)
			(type default)
		)
		(layer "In5.Cu")
	)
	(gr_line
		(start 303.78654 -161.113216)
		(end 303.797716 -161.096198)
		(stroke
			(width 0.060198)
			(type default)
		)
		(layer "In5.Cu")
	)
	(gr_line
		(start 303.797716 -161.096198)
		(end 303.80178 -161.076386)
		(stroke
			(width 0.060198)
			(type default)
		)
		(layer "In5.Cu")
	)
	(gr_line
		(start 303.904904 -173.19752)
		(end 303.929796 -173.181518)
		(stroke
			(width 0.060198)
			(type default)
		)
		(layer "In5.Cu")
	)
	(gr_line
		(start 303.929796 -173.181518)
		(end 303.945798 -173.156626)
		(stroke
			(width 0.060198)
			(type default)
		)
		(layer "In5.Cu")
	)
	(gr_line
		(start 304.94605 -174.378874)
		(end 304.971704 -174.36211)
		(stroke
			(width 0.060198)
			(type default)
		)
		(layer "In5.Cu")
	)
	(gr_line
		(start 304.971704 -174.36211)
		(end 304.987706 -174.337218)
		(stroke
			(width 0.060198)
			(type default)
		)
		(layer "In5.Cu")
	)
	(gr_line
		(start 305.16576 -165.038024)
		(end 305.176936 -165.021006)
		(stroke
			(width 0.060198)
			(type default)
		)
		(layer "In5.Cu")
	)
	(gr_line
		(start 305.176936 -165.021006)
		(end 305.181 -165.001194)
		(stroke
			(width 0.060198)
			(type default)
		)
		(layer "In5.Cu")
	)
	(gr_line
		(start 306.944522 -165.197028)
		(end 306.955698 -165.18001)
		(stroke
			(width 0.060198)
			(type default)
		)
		(layer "In5.Cu")
	)
	(gr_line
		(start 306.955698 -165.18001)
		(end 306.959762 -165.160198)
		(stroke
			(width 0.060198)
			(type default)
		)
		(layer "In5.Cu")
	)
	(gr_line
		(start 309.475124 -164.642038)
		(end 309.4863 -164.62502)
		(stroke
			(width 0.060198)
			(type default)
		)
		(layer "In5.Cu")
	)
	(gr_line
		(start 309.4863 -164.62502)
		(end 309.490364 -164.605208)
		(stroke
			(width 0.060198)
			(type default)
		)
		(layer "In5.Cu")
	)
	(gr_line
		(start 310.846216 -241.886994)
		(end 311.427368 -242.264438)
		(stroke
			(width 0.060198)
			(type default)
		)
		(layer "In5.Cu")
	)
	(gr_line
		(start 311.001664 -241.58321)
		(end 311.27954 -241.524282)
		(stroke
			(width 0.060198)
			(type default)
		)
		(layer "In5.Cu")
	)
	(gr_line
		(start 311.27954 -241.524282)
		(end 311.58307 -241.721386)
		(stroke
			(width 0.060198)
			(type default)
		)
		(layer "In5.Cu")
	)
	(gr_line
		(start 311.286144 -124.241814)
		(end 311.290208 -124.222002)
		(stroke
			(width 0.060198)
			(type default)
		)
		(layer "In5.Cu")
	)
	(gr_line
		(start 311.290208 -124.222002)
		(end 311.301384 -124.204984)
		(stroke
			(width 0.060198)
			(type default)
		)
		(layer "In5.Cu")
	)
	(gr_line
		(start 311.58307 -241.721386)
		(end 311.641998 -241.999262)
		(stroke
			(width 0.060198)
			(type default)
		)
		(layer "In5.Cu")
	)
	(gr_line
		(start 311.794398 -242.50269)
		(end 312.374788 -242.879626)
		(stroke
			(width 0.060198)
			(type default)
		)
		(layer "In5.Cu")
	)
	(gr_line
		(start 311.908952 -190.36284)
		(end 311.915048 -190.360554)
		(stroke
			(width 0.060198)
			(type default)
		)
		(layer "In5.Cu")
	)
	(gr_line
		(start 311.915048 -190.360554)
		(end 311.920382 -190.356744)
		(stroke
			(width 0.060198)
			(type default)
		)
		(layer "In5.Cu")
	)
	(gr_line
		(start 311.949846 -242.198906)
		(end 312.227468 -242.139978)
		(stroke
			(width 0.060198)
			(type default)
		)
		(layer "In5.Cu")
	)
	(gr_line
		(start 312.227468 -242.139978)
		(end 312.530998 -242.337082)
		(stroke
			(width 0.060198)
			(type default)
		)
		(layer "In5.Cu")
	)
	(gr_line
		(start 312.276236 -163.113212)
		(end 312.287412 -163.096194)
		(stroke
			(width 0.060198)
			(type default)
		)
		(layer "In5.Cu")
	)
	(gr_line
		(start 312.287412 -163.096194)
		(end 312.291476 -163.076382)
		(stroke
			(width 0.060198)
			(type default)
		)
		(layer "In5.Cu")
	)
	(gr_line
		(start 312.530998 -242.337082)
		(end 312.59018 -242.614958)
		(stroke
			(width 0.060198)
			(type default)
		)
		(layer "In5.Cu")
	)
	(gr_line
		(start 312.631836 -128.32461)
		(end 312.636916 -128.300734)
		(stroke
			(width 0.060198)
			(type default)
		)
		(layer "In5.Cu")
	)
	(gr_line
		(start 312.636916 -128.300734)
		(end 312.650632 -128.280414)
		(stroke
			(width 0.060198)
			(type default)
		)
		(layer "In5.Cu")
	)
	(gr_line
		(start 312.74385 -243.119148)
		(end 313.322716 -243.495068)
		(stroke
			(width 0.060198)
			(type default)
		)
		(layer "In5.Cu")
	)
	(gr_line
		(start 312.897774 -242.814602)
		(end 313.175396 -242.75542)
		(stroke
			(width 0.060198)
			(type default)
		)
		(layer "In5.Cu")
	)
	(gr_line
		(start 313.175396 -242.75542)
		(end 313.478926 -242.952778)
		(stroke
			(width 0.060198)
			(type default)
		)
		(layer "In5.Cu")
	)
	(gr_line
		(start 313.478926 -242.952778)
		(end 313.538108 -243.230654)
		(stroke
			(width 0.060198)
			(type default)
		)
		(layer "In5.Cu")
	)
	(gr_line
		(start 313.899804 -188.931042)
		(end 313.908948 -188.924438)
		(stroke
			(width 0.060198)
			(type default)
		)
		(layer "In5.Cu")
	)
	(gr_line
		(start 313.908948 -188.924438)
		(end 313.915806 -188.91504)
		(stroke
			(width 0.060198)
			(type default)
		)
		(layer "In5.Cu")
	)
	(gr_line
		(start 314.315602 -128.934718)
		(end 314.320936 -128.909826)
		(stroke
			(width 0.060198)
			(type default)
		)
		(layer "In5.Cu")
	)
	(gr_line
		(start 314.320936 -128.909826)
		(end 314.33516 -128.888744)
		(stroke
			(width 0.060198)
			(type default)
		)
		(layer "In5.Cu")
	)
	(gr_line
		(start 314.834016 -162.538918)
		(end 314.834778 -162.537648)
		(stroke
			(width 0.060198)
			(type default)
		)
		(layer "In5.Cu")
	)
	(gr_line
		(start 314.834778 -162.537648)
		(end 314.83554 -162.535616)
		(stroke
			(width 0.060198)
			(type default)
		)
		(layer "In5.Cu")
	)
	(gr_line
		(start 316.651132 -129.292604)
		(end 316.658244 -129.258314)
		(stroke
			(width 0.060198)
			(type default)
		)
		(layer "In5.Cu")
	)
	(gr_line
		(start 316.658244 -129.258314)
		(end 316.680342 -129.229866)
		(stroke
			(width 0.060198)
			(type default)
		)
		(layer "In5.Cu")
	)
	(gr_line
		(start 317.606172 -128.039622)
		(end 317.616078 -128.026922)
		(stroke
			(width 0.060198)
			(type default)
		)
		(layer "In5.Cu")
	)
	(gr_line
		(start 317.616078 -128.026922)
		(end 317.629032 -128.01854)
		(stroke
			(width 0.060198)
			(type default)
		)
		(layer "In5.Cu")
	)
	(gr_line
		(start 318.149986 -151.062436)
		(end 318.360806 -150.403306)
		(stroke
			(width 0.060198)
			(type default)
		)
		(layer "In5.Cu")
	)
	(gr_line
		(start 318.46266 -151.199342)
		(end 318.715136 -151.06904)
		(stroke
			(width 0.060198)
			(type default)
		)
		(layer "In5.Cu")
	)
	(gr_line
		(start 318.494664 -149.98446)
		(end 318.704722 -149.32787)
		(stroke
			(width 0.060198)
			(type default)
		)
		(layer "In5.Cu")
	)
	(gr_line
		(start 318.69507 -150.47214)
		(end 318.825118 -150.724362)
		(stroke
			(width 0.060198)
			(type default)
		)
		(layer "In5.Cu")
	)
	(gr_line
		(start 318.715136 -151.06904)
		(end 318.825118 -150.724362)
		(stroke
			(width 0.060198)
			(type default)
		)
		(layer "In5.Cu")
	)
	(gr_line
		(start 318.80683 -150.122636)
		(end 319.059306 -149.992588)
		(stroke
			(width 0.060198)
			(type default)
		)
		(layer "In5.Cu")
	)
	(gr_line
		(start 318.83985 -148.905976)
		(end 319.049146 -148.251164)
		(stroke
			(width 0.060198)
			(type default)
		)
		(layer "In5.Cu")
	)
	(gr_line
		(start 319.03924 -149.395434)
		(end 319.169542 -149.64791)
		(stroke
			(width 0.060198)
			(type default)
		)
		(layer "In5.Cu")
	)
	(gr_line
		(start 319.059306 -149.992588)
		(end 319.169542 -149.64791)
		(stroke
			(width 0.060198)
			(type default)
		)
		(layer "In5.Cu")
	)
	(gr_line
		(start 319.151 -149.046184)
		(end 319.403476 -148.915882)
		(stroke
			(width 0.060198)
			(type default)
		)
		(layer "In5.Cu")
	)
	(gr_line
		(start 319.383664 -148.318728)
		(end 319.513712 -148.571204)
		(stroke
			(width 0.060198)
			(type default)
		)
		(layer "In5.Cu")
	)
	(gr_line
		(start 319.403476 -148.915882)
		(end 319.513712 -148.571204)
		(stroke
			(width 0.060198)
			(type default)
		)
		(layer "In5.Cu")
	)
	(gr_line
		(start 321.051174 -50.910998)
		(end 321.175126 -50.236628)
		(stroke
			(width 0.060198)
			(type default)
		)
		(layer "In5.Cu")
	)
	(gr_line
		(start 321.255136 -49.800002)
		(end 321.379596 -49.123346)
		(stroke
			(width 0.060198)
			(type default)
		)
		(layer "In5.Cu")
	)
	(gr_line
		(start 321.377564 -51.010566)
		(end 321.611244 -50.84953)
		(stroke
			(width 0.060198)
			(type default)
		)
		(layer "In5.Cu")
	)
	(gr_line
		(start 321.459352 -48.690022)
		(end 321.583558 -48.013112)
		(stroke
			(width 0.060198)
			(type default)
		)
		(layer "In5.Cu")
	)
	(gr_line
		(start 321.515486 -50.259742)
		(end 321.676776 -50.493422)
		(stroke
			(width 0.060198)
			(type default)
		)
		(layer "In5.Cu")
	)
	(gr_line
		(start 321.564508 -129.388362)
		(end 321.588892 -129.332482)
		(stroke
			(width 0.060198)
			(type default)
		)
		(layer "In5.Cu")
	)
	(gr_line
		(start 321.58178 -49.898808)
		(end 321.815714 -49.737772)
		(stroke
			(width 0.060198)
			(type default)
		)
		(layer "In5.Cu")
	)
	(gr_line
		(start 321.588892 -129.332482)
		(end 321.639946 -129.299208)
		(stroke
			(width 0.060198)
			(type default)
		)
		(layer "In5.Cu")
	)
	(gr_line
		(start 321.611244 -50.84953)
		(end 321.676776 -50.493422)
		(stroke
			(width 0.060198)
			(type default)
		)
		(layer "In5.Cu")
	)
	(gr_line
		(start 321.624706 -248.886218)
		(end 321.673982 -248.918222)
		(stroke
			(width 0.060198)
			(type default)
		)
		(layer "In5.Cu")
	)
	(gr_line
		(start 321.719956 -49.147984)
		(end 321.880992 -49.381664)
		(stroke
			(width 0.060198)
			(type default)
		)
		(layer "In5.Cu")
	)
	(gr_line
		(start 321.78625 -48.787558)
		(end 322.01993 -48.626014)
		(stroke
			(width 0.060198)
			(type default)
		)
		(layer "In5.Cu")
	)
	(gr_line
		(start 321.815714 -49.737772)
		(end 321.880992 -49.381664)
		(stroke
			(width 0.060198)
			(type default)
		)
		(layer "In5.Cu")
	)
	(gr_line
		(start 321.924172 -48.03648)
		(end 322.085208 -48.27016)
		(stroke
			(width 0.060198)
			(type default)
		)
		(layer "In5.Cu")
	)
	(gr_line
		(start 322.01993 -48.626014)
		(end 322.085208 -48.27016)
		(stroke
			(width 0.060198)
			(type default)
		)
		(layer "In5.Cu")
	)
	(gr_line
		(start 322.6816 -132.437124)
		(end 322.987924 -132.437124)
		(stroke
			(width 0.060198)
			(type default)
		)
		(layer "In5.Cu")
	)
	(gr_line
		(start 322.6816 -17.4371)
		(end 322.9991 -17.4371)
		(stroke
			(width 0.060198)
			(type default)
		)
		(layer "In5.Cu")
	)
	(gr_arc
		(start 323.148198 -132.597398)
		(mid 323.101255 -132.484067)
		(end 322.987924 -132.437124)
		(stroke
			(width 0.060198)
			(type default)
		)
		(layer "In5.Cu")
	)
	(gr_arc
		(start 323.148198 -17.586198)
		(mid 323.104528 -17.48077)
		(end 322.9991 -17.4371)
		(stroke
			(width 0.060198)
			(type default)
		)
		(layer "In5.Cu")
	)
	(gr_arc
		(start 323.469 -248.581672)
		(mid 323.554312 -248.546334)
		(end 323.58965 -248.461022)
		(stroke
			(width 0.060198)
			(type default)
		)
		(layer "In5.Cu")
	)
	(gr_line
		(start 323.481446 -135.49503)
		(end 323.484748 -135.484362)
		(stroke
			(width 0.060198)
			(type default)
		)
		(layer "In5.Cu")
	)
	(gr_arc
		(start 323.58965 -249.038872)
		(mid 323.554303 -248.953578)
		(end 323.469 -248.918222)
		(stroke
			(width 0.060198)
			(type default)
		)
		(layer "In5.Cu")
	)
	(gr_line
		(start 323.58965 -249.038872)
		(end 323.58965 -249.385074)
		(stroke
			(width 0.060198)
			(type default)
		)
		(layer "In5.Cu")
	)
	(gr_line
		(start 323.58965 -248.115074)
		(end 323.58965 -248.461022)
		(stroke
			(width 0.060198)
			(type default)
		)
		(layer "In5.Cu")
	)
	(gr_arc
		(start 323.6341 -17.4371)
		(mid 323.528475 -17.480841)
		(end 323.484748 -17.586452)
		(stroke
			(width 0.060198)
			(type default)
		)
		(layer "In5.Cu")
	)
	(gr_line
		(start 323.6341 -17.4371)
		(end 323.9516 -17.4371)
		(stroke
			(width 0.060198)
			(type default)
		)
		(layer "In5.Cu")
	)
	(gr_arc
		(start 323.645276 -132.437124)
		(mid 323.531764 -132.484147)
		(end 323.484748 -132.597652)
		(stroke
			(width 0.060198)
			(type default)
		)
		(layer "In5.Cu")
	)
	(gr_line
		(start 323.645276 -132.437124)
		(end 323.9516 -132.437124)
		(stroke
			(width 0.060198)
			(type default)
		)
		(layer "In5.Cu")
	)
	(gr_line
		(start 332.127098 -92.137484)
		(end 332.500732 -91.56192)
		(stroke
			(width 0.060198)
			(type default)
		)
		(layer "In5.Cu")
	)
	(gr_line
		(start 332.389734 -92.355162)
		(end 332.66761 -92.29598)
		(stroke
			(width 0.060198)
			(type default)
		)
		(layer "In5.Cu")
	)
	(gr_line
		(start 332.66761 -92.29598)
		(end 332.864714 -91.99245)
		(stroke
			(width 0.060198)
			(type default)
		)
		(layer "In5.Cu")
	)
	(gr_line
		(start 332.742032 -91.190318)
		(end 333.115666 -90.615008)
		(stroke
			(width 0.060198)
			(type default)
		)
		(layer "In5.Cu")
	)
	(gr_line
		(start 332.805786 -91.714828)
		(end 332.864714 -91.99245)
		(stroke
			(width 0.060198)
			(type default)
		)
		(layer "In5.Cu")
	)
	(gr_line
		(start 333.00543 -91.407234)
		(end 333.283052 -91.348052)
		(stroke
			(width 0.060198)
			(type default)
		)
		(layer "In5.Cu")
	)
	(gr_line
		(start 333.283052 -91.348052)
		(end 333.48041 -91.044522)
		(stroke
			(width 0.060198)
			(type default)
		)
		(layer "In5.Cu")
	)
	(gr_line
		(start 333.356966 -90.243406)
		(end 333.731616 -89.666572)
		(stroke
			(width 0.060198)
			(type default)
		)
		(layer "In5.Cu")
	)
	(gr_line
		(start 333.421228 -90.767154)
		(end 333.48041 -91.044522)
		(stroke
			(width 0.060198)
			(type default)
		)
		(layer "In5.Cu")
	)
	(gr_line
		(start 333.621126 -90.459306)
		(end 333.898748 -90.400124)
		(stroke
			(width 0.060198)
			(type default)
		)
		(layer "In5.Cu")
	)
	(gr_line
		(start 333.898748 -90.400124)
		(end 334.095852 -90.096594)
		(stroke
			(width 0.060198)
			(type default)
		)
		(layer "In5.Cu")
	)
	(gr_line
		(start 334.036924 -89.818972)
		(end 334.095852 -90.096594)
		(stroke
			(width 0.060198)
			(type default)
		)
		(layer "In5.Cu")
	)
	(gr_line
		(start 334.169004 -193.03111)
		(end 334.19796 -193.026284)
		(stroke
			(width 0.060198)
			(type default)
		)
		(layer "In5.Cu")
	)
	(gr_line
		(start 334.19796 -193.026284)
		(end 334.222598 -193.010282)
		(stroke
			(width 0.060198)
			(type default)
		)
		(layer "In5.Cu")
	)
	(gr_line
		(start 336.519774 -194.16649)
		(end 336.550508 -194.16141)
		(stroke
			(width 0.060198)
			(type default)
		)
		(layer "In5.Cu")
	)
	(gr_line
		(start 336.550508 -194.16141)
		(end 336.57667 -194.144392)
		(stroke
			(width 0.060198)
			(type default)
		)
		(layer "In5.Cu")
	)
	(gr_line
		(start 342.618822 -76.599796)
		(end 342.629998 -76.582778)
		(stroke
			(width 0.060198)
			(type default)
		)
		(layer "In5.Cu")
	)
	(gr_line
		(start 342.629998 -76.582778)
		(end 342.634062 -76.562966)
		(stroke
			(width 0.060198)
			(type default)
		)
		(layer "In5.Cu")
	)
	(gr_line
		(start 342.841072 -149.310852)
		(end 343.250774 -148.758148)
		(stroke
			(width 0.060198)
			(type default)
		)
		(layer "In5.Cu")
	)
	(gr_line
		(start 343.091262 -149.543262)
		(end 343.372186 -149.501606)
		(stroke
			(width 0.060198)
			(type default)
		)
		(layer "In5.Cu")
	)
	(gr_line
		(start 343.372186 -149.501606)
		(end 343.587578 -149.210776)
		(stroke
			(width 0.060198)
			(type default)
		)
		(layer "In5.Cu")
	)
	(gr_line
		(start 343.513664 -148.403564)
		(end 343.923366 -147.850606)
		(stroke
			(width 0.060198)
			(type default)
		)
		(layer "In5.Cu")
	)
	(gr_line
		(start 343.545668 -148.929852)
		(end 343.587578 -149.210776)
		(stroke
			(width 0.060198)
			(type default)
		)
		(layer "In5.Cu")
	)
	(gr_line
		(start 343.763854 -148.635212)
		(end 344.045032 -148.593302)
		(stroke
			(width 0.060198)
			(type default)
		)
		(layer "In5.Cu")
	)
	(gr_line
		(start 344.045032 -148.593302)
		(end 344.260424 -148.302472)
		(stroke
			(width 0.060198)
			(type default)
		)
		(layer "In5.Cu")
	)
	(gr_line
		(start 344.18778 -147.49399)
		(end 344.596974 -146.94154)
		(stroke
			(width 0.060198)
			(type default)
		)
		(layer "In5.Cu")
	)
	(gr_line
		(start 344.218768 -148.021548)
		(end 344.260424 -148.302472)
		(stroke
			(width 0.060198)
			(type default)
		)
		(layer "In5.Cu")
	)
	(gr_line
		(start 344.42273 -235.336588)
		(end 345.101164 -235.464604)
		(stroke
			(width 0.060198)
			(type default)
		)
		(layer "In5.Cu")
	)
	(gr_line
		(start 344.436954 -147.726908)
		(end 344.717878 -147.685252)
		(stroke
			(width 0.060198)
			(type default)
		)
		(layer "In5.Cu")
	)
	(gr_line
		(start 344.449654 -234.996228)
		(end 344.68435 -234.836208)
		(stroke
			(width 0.060198)
			(type default)
		)
		(layer "In5.Cu")
	)
	(gr_line
		(start 344.68435 -234.836208)
		(end 345.03995 -234.903518)
		(stroke
			(width 0.060198)
			(type default)
		)
		(layer "In5.Cu")
	)
	(gr_line
		(start 344.717878 -147.685252)
		(end 344.93327 -147.394422)
		(stroke
			(width 0.060198)
			(type default)
		)
		(layer "In5.Cu")
	)
	(gr_line
		(start 344.891614 -147.113498)
		(end 344.93327 -147.394422)
		(stroke
			(width 0.060198)
			(type default)
		)
		(layer "In5.Cu")
	)
	(gr_line
		(start 345.03995 -234.903518)
		(end 345.200224 -235.13796)
		(stroke
			(width 0.060198)
			(type default)
		)
		(layer "In5.Cu")
	)
	(gr_line
		(start 345.396312 -245.989094)
		(end 346.029534 -246.267986)
		(stroke
			(width 0.060198)
			(type default)
		)
		(layer "In5.Cu")
	)
	(gr_line
		(start 345.500452 -245.663974)
		(end 345.764866 -245.561104)
		(stroke
			(width 0.060198)
			(type default)
		)
		(layer "In5.Cu")
	)
	(gr_line
		(start 345.533218 -235.546138)
		(end 346.21216 -235.674154)
		(stroke
			(width 0.060198)
			(type default)
		)
		(layer "In5.Cu")
	)
	(gr_line
		(start 345.560396 -235.206032)
		(end 345.795092 -235.045758)
		(stroke
			(width 0.060198)
			(type default)
		)
		(layer "In5.Cu")
	)
	(gr_line
		(start 345.764866 -245.561104)
		(end 346.096082 -245.707154)
		(stroke
			(width 0.060198)
			(type default)
		)
		(layer "In5.Cu")
	)
	(gr_line
		(start 345.795092 -235.045758)
		(end 346.150692 -235.113068)
		(stroke
			(width 0.060198)
			(type default)
		)
		(layer "In5.Cu")
	)
	(gr_line
		(start 346.096082 -245.707154)
		(end 346.198952 -245.971822)
		(stroke
			(width 0.060198)
			(type default)
		)
		(layer "In5.Cu")
	)
	(gr_line
		(start 346.150692 -235.113068)
		(end 346.310966 -235.34751)
		(stroke
			(width 0.060198)
			(type default)
		)
		(layer "In5.Cu")
	)
	(gr_line
		(start 346.431616 -246.445024)
		(end 347.063568 -246.723408)
		(stroke
			(width 0.060198)
			(type default)
		)
		(layer "In5.Cu")
	)
	(gr_line
		(start 346.534486 -246.11965)
		(end 346.799154 -246.01678)
		(stroke
			(width 0.060198)
			(type default)
		)
		(layer "In5.Cu")
	)
	(gr_line
		(start 346.644214 -235.755688)
		(end 347.341952 -235.88726)
		(stroke
			(width 0.060198)
			(type default)
		)
		(layer "In5.Cu")
	)
	(gr_line
		(start 346.670884 -235.415582)
		(end 346.917518 -235.247434)
		(stroke
			(width 0.060198)
			(type default)
		)
		(layer "In5.Cu")
	)
	(gr_line
		(start 346.799154 -246.01678)
		(end 347.13037 -246.16283)
		(stroke
			(width 0.060198)
			(type default)
		)
		(layer "In5.Cu")
	)
	(gr_line
		(start 346.917518 -235.247434)
		(end 347.273372 -235.31449)
		(stroke
			(width 0.060198)
			(type default)
		)
		(layer "In5.Cu")
	)
	(gr_line
		(start 347.13037 -246.16283)
		(end 347.23324 -246.427498)
		(stroke
			(width 0.060198)
			(type default)
		)
		(layer "In5.Cu")
	)
	(gr_line
		(start 347.273372 -235.31449)
		(end 347.44152 -235.56087)
		(stroke
			(width 0.060198)
			(type default)
		)
		(layer "In5.Cu")
	)
	(gr_line
		(start 347.467936 -246.901208)
		(end 348.095316 -247.177814)
		(stroke
			(width 0.060198)
			(type default)
		)
		(layer "In5.Cu")
	)
	(gr_line
		(start 347.568774 -246.575326)
		(end 347.833442 -246.47271)
		(stroke
			(width 0.060198)
			(type default)
		)
		(layer "In5.Cu")
	)
	(gr_line
		(start 347.833442 -246.47271)
		(end 348.164658 -246.618506)
		(stroke
			(width 0.060198)
			(type default)
		)
		(layer "In5.Cu")
	)
	(gr_line
		(start 348.164658 -246.618506)
		(end 348.267528 -246.883174)
		(stroke
			(width 0.060198)
			(type default)
		)
		(layer "In5.Cu")
	)
	(gr_line
		(start 348.942406 -111.569246)
		(end 349.54083 -111.180626)
		(stroke
			(width 0.060198)
			(type default)
		)
		(layer "In5.Cu")
	)
	(gr_line
		(start 349.042482 -194.94373)
		(end 349.062294 -194.939666)
		(stroke
			(width 0.060198)
			(type default)
		)
		(layer "In5.Cu")
	)
	(gr_line
		(start 349.062294 -194.939666)
		(end 349.079312 -194.92849)
		(stroke
			(width 0.060198)
			(type default)
		)
		(layer "In5.Cu")
	)
	(gr_line
		(start 349.0976 -111.872776)
		(end 349.3897 -111.935006)
		(stroke
			(width 0.060198)
			(type default)
		)
		(layer "In5.Cu")
	)
	(gr_line
		(start 349.3897 -111.935006)
		(end 349.69323 -111.737902)
		(stroke
			(width 0.060198)
			(type default)
		)
		(layer "In5.Cu")
	)
	(gr_line
		(start 349.69323 -111.737902)
		(end 349.75546 -111.445802)
		(stroke
			(width 0.060198)
			(type default)
		)
		(layer "In5.Cu")
	)
	(gr_line
		(start 349.907352 -110.942628)
		(end 350.505776 -110.554008)
		(stroke
			(width 0.060198)
			(type default)
		)
		(layer "In5.Cu")
	)
	(gr_line
		(start 350.062546 -111.246158)
		(end 350.354646 -111.308388)
		(stroke
			(width 0.060198)
			(type default)
		)
		(layer "In5.Cu")
	)
	(gr_line
		(start 350.354646 -111.308388)
		(end 350.658176 -111.111284)
		(stroke
			(width 0.060198)
			(type default)
		)
		(layer "In5.Cu")
	)
	(gr_line
		(start 350.658176 -111.111284)
		(end 350.720406 -110.819184)
		(stroke
			(width 0.060198)
			(type default)
		)
		(layer "In5.Cu")
	)
	(gr_line
		(start 350.872552 -110.315756)
		(end 351.469198 -109.928406)
		(stroke
			(width 0.060198)
			(type default)
		)
		(layer "In5.Cu")
	)
	(gr_line
		(start 351.027492 -110.61954)
		(end 351.319592 -110.68177)
		(stroke
			(width 0.060198)
			(type default)
		)
		(layer "In5.Cu")
	)
	(gr_line
		(start 351.319592 -110.68177)
		(end 351.623122 -110.484412)
		(stroke
			(width 0.060198)
			(type default)
		)
		(layer "In5.Cu")
	)
	(gr_line
		(start 351.542096 -195.966334)
		(end 351.562416 -195.962016)
		(stroke
			(width 0.060198)
			(type default)
		)
		(layer "In5.Cu")
	)
	(gr_line
		(start 351.562416 -195.962016)
		(end 351.580196 -195.95084)
		(stroke
			(width 0.060198)
			(type default)
		)
		(layer "In5.Cu")
	)
	(gr_line
		(start 351.623122 -110.484412)
		(end 351.685098 -110.192566)
		(stroke
			(width 0.060198)
			(type default)
		)
		(layer "In5.Cu")
	)
	(gr_line
		(start 352.018854 -248.906538)
		(end 352.04527 -248.918222)
		(stroke
			(width 0.060198)
			(type default)
		)
		(layer "In5.Cu")
	)
	(gr_line
		(start 354.231702 -132.437124)
		(end 354.534724 -132.437124)
		(stroke
			(width 0.060198)
			(type default)
		)
		(layer "In5.Cu")
	)
	(gr_line
		(start 354.231702 -17.4371)
		(end 354.5459 -17.4371)
		(stroke
			(width 0.060198)
			(type default)
		)
		(layer "In5.Cu")
	)
	(gr_arc
		(start 354.6983 -132.6007)
		(mid 354.65039 -132.485034)
		(end 354.534724 -132.437124)
		(stroke
			(width 0.060198)
			(type default)
		)
		(layer "In5.Cu")
	)
	(gr_arc
		(start 354.6983 -17.5895)
		(mid 354.653663 -17.481737)
		(end 354.5459 -17.4371)
		(stroke
			(width 0.060198)
			(type default)
		)
		(layer "In5.Cu")
	)
	(gr_line
		(start 354.993448 -133.475222)
		(end 355.03485 -133.419596)
		(stroke
			(width 0.060198)
			(type default)
		)
		(layer "In5.Cu")
	)
	(gr_arc
		(start 355.019102 -248.581672)
		(mid 355.104414 -248.546334)
		(end 355.139752 -248.461022)
		(stroke
			(width 0.060198)
			(type default)
		)
		(layer "In5.Cu")
	)
	(gr_arc
		(start 355.139752 -249.038872)
		(mid 355.104405 -248.953577)
		(end 355.019102 -248.918222)
		(stroke
			(width 0.060198)
			(type default)
		)
		(layer "In5.Cu")
	)
	(gr_line
		(start 355.139752 -249.038872)
		(end 355.139752 -249.385074)
		(stroke
			(width 0.060198)
			(type default)
		)
		(layer "In5.Cu")
	)
	(gr_line
		(start 355.139752 -248.115074)
		(end 355.139752 -248.461022)
		(stroke
			(width 0.060198)
			(type default)
		)
		(layer "In5.Cu")
	)
	(gr_arc
		(start 355.187504 -17.4371)
		(mid 355.079542 -17.481807)
		(end 355.03485 -17.589754)
		(stroke
			(width 0.060198)
			(type default)
		)
		(layer "In5.Cu")
	)
	(gr_line
		(start 355.187504 -17.4371)
		(end 355.501702 -17.4371)
		(stroke
			(width 0.060198)
			(type default)
		)
		(layer "In5.Cu")
	)
	(gr_arc
		(start 355.19868 -132.437124)
		(mid 355.082831 -132.485113)
		(end 355.03485 -132.600954)
		(stroke
			(width 0.060198)
			(type default)
		)
		(layer "In5.Cu")
	)
	(gr_line
		(start 355.19868 -132.437124)
		(end 355.501702 -132.437124)
		(stroke
			(width 0.060198)
			(type default)
		)
		(layer "In5.Cu")
	)
	(gr_line
		(start 359.129076 -176.836324)
		(end 359.15473 -176.81956)
		(stroke
			(width 0.060198)
			(type default)
		)
		(layer "In5.Cu")
	)
	(gr_line
		(start 359.15473 -176.81956)
		(end 359.170732 -176.794668)
		(stroke
			(width 0.060198)
			(type default)
		)
		(layer "In5.Cu")
	)
	(gr_line
		(start 361.337606 -59.204606)
		(end 361.353354 -59.181492)
		(stroke
			(width 0.060198)
			(type default)
		)
		(layer "In5.Cu")
	)
	(gr_line
		(start 361.353354 -59.181492)
		(end 361.376468 -59.166252)
		(stroke
			(width 0.060198)
			(type default)
		)
		(layer "In5.Cu")
	)
	(gr_line
		(start 366.747806 -164.505132)
		(end 367.121186 -163.930076)
		(stroke
			(width 0.060198)
			(type default)
		)
		(layer "In5.Cu")
	)
	(gr_line
		(start 367.010188 -164.723318)
		(end 367.288064 -164.664136)
		(stroke
			(width 0.060198)
			(type default)
		)
		(layer "In5.Cu")
	)
	(gr_line
		(start 367.288064 -164.664136)
		(end 367.485168 -164.360606)
		(stroke
			(width 0.060198)
			(type default)
		)
		(layer "In5.Cu")
	)
	(gr_line
		(start 367.361724 -163.559236)
		(end 367.736882 -162.981386)
		(stroke
			(width 0.060198)
			(type default)
		)
		(layer "In5.Cu")
	)
	(gr_line
		(start 367.42624 -164.08273)
		(end 367.485168 -164.360606)
		(stroke
			(width 0.060198)
			(type default)
		)
		(layer "In5.Cu")
	)
	(gr_line
		(start 367.625884 -163.775136)
		(end 367.903506 -163.716208)
		(stroke
			(width 0.060198)
			(type default)
		)
		(layer "In5.Cu")
	)
	(gr_line
		(start 367.903506 -163.716208)
		(end 368.10061 -163.412678)
		(stroke
			(width 0.060198)
			(type default)
		)
		(layer "In5.Cu")
	)
	(gr_line
		(start 367.97742 -162.611054)
		(end 368.35207 -162.033712)
		(stroke
			(width 0.060198)
			(type default)
		)
		(layer "In5.Cu")
	)
	(gr_line
		(start 368.041682 -163.134802)
		(end 368.10061 -163.412678)
		(stroke
			(width 0.060198)
			(type default)
		)
		(layer "In5.Cu")
	)
	(gr_line
		(start 368.241072 -162.827208)
		(end 368.518948 -162.768026)
		(stroke
			(width 0.060198)
			(type default)
		)
		(layer "In5.Cu")
	)
	(gr_line
		(start 368.255804 -182.074312)
		(end 368.827304 -181.703218)
		(stroke
			(width 0.060198)
			(type default)
		)
		(layer "In5.Cu")
	)
	(gr_line
		(start 368.406172 -182.380636)
		(end 368.683794 -182.439564)
		(stroke
			(width 0.060198)
			(type default)
		)
		(layer "In5.Cu")
	)
	(gr_line
		(start 368.518948 -162.768026)
		(end 368.716052 -162.464496)
		(stroke
			(width 0.060198)
			(type default)
		)
		(layer "In5.Cu")
	)
	(gr_line
		(start 368.657124 -162.18662)
		(end 368.716052 -162.464496)
		(stroke
			(width 0.060198)
			(type default)
		)
		(layer "In5.Cu")
	)
	(gr_line
		(start 368.683794 -182.439564)
		(end 368.987324 -182.24246)
		(stroke
			(width 0.060198)
			(type default)
		)
		(layer "In5.Cu")
	)
	(gr_line
		(start 368.987324 -182.24246)
		(end 369.046506 -181.964838)
		(stroke
			(width 0.060198)
			(type default)
		)
		(layer "In5.Cu")
	)
	(gr_line
		(start 369.204748 -181.458108)
		(end 369.776248 -181.087014)
		(stroke
			(width 0.060198)
			(type default)
		)
		(layer "In5.Cu")
	)
	(gr_line
		(start 369.354354 -181.76494)
		(end 369.631722 -181.823868)
		(stroke
			(width 0.060198)
			(type default)
		)
		(layer "In5.Cu")
	)
	(gr_line
		(start 369.631722 -181.823868)
		(end 369.935252 -181.626764)
		(stroke
			(width 0.060198)
			(type default)
		)
		(layer "In5.Cu")
	)
	(gr_line
		(start 369.935252 -181.626764)
		(end 369.994434 -181.349142)
		(stroke
			(width 0.060198)
			(type default)
		)
		(layer "In5.Cu")
	)
	(gr_line
		(start 370.111782 -180.868574)
		(end 370.119148 -180.863748)
		(stroke
			(width 0.060198)
			(type default)
		)
		(layer "In5.Cu")
	)
	(gr_line
		(start 370.15166 -180.84292)
		(end 370.724684 -180.47081)
		(stroke
			(width 0.060198)
			(type default)
		)
		(layer "In5.Cu")
	)
	(gr_line
		(start 370.255038 -181.17693)
		(end 370.298726 -181.148482)
		(stroke
			(width 0.060198)
			(type default)
		)
		(layer "In5.Cu")
	)
	(gr_line
		(start 370.302282 -181.149244)
		(end 370.57965 -181.208426)
		(stroke
			(width 0.060198)
			(type default)
		)
		(layer "In5.Cu")
	)
	(gr_line
		(start 370.57965 -181.208426)
		(end 370.883434 -181.011322)
		(stroke
			(width 0.060198)
			(type default)
		)
		(layer "In5.Cu")
	)
	(gr_line
		(start 370.883434 -181.011322)
		(end 370.942362 -180.733446)
		(stroke
			(width 0.060198)
			(type default)
		)
		(layer "In5.Cu")
	)
	(gr_line
		(start 376.823224 -48.890174)
		(end 377.398788 -48.507142)
		(stroke
			(width 0.060198)
			(type default)
		)
		(layer "In5.Cu")
	)
	(gr_line
		(start 376.98045 -49.192688)
		(end 377.259088 -49.248822)
		(stroke
			(width 0.060198)
			(type default)
		)
		(layer "In5.Cu")
	)
	(gr_line
		(start 377.09348 -32.741362)
		(end 377.474988 -32.175958)
		(stroke
			(width 0.060198)
			(type default)
		)
		(layer "In5.Cu")
	)
	(gr_line
		(start 377.259088 -49.248822)
		(end 377.560332 -49.048416)
		(stroke
			(width 0.060198)
			(type default)
		)
		(layer "In5.Cu")
	)
	(gr_line
		(start 377.35129 -32.964882)
		(end 377.630182 -32.91078)
		(stroke
			(width 0.060198)
			(type default)
		)
		(layer "In5.Cu")
	)
	(gr_line
		(start 377.560332 -49.048416)
		(end 377.616466 -48.769778)
		(stroke
			(width 0.060198)
			(type default)
		)
		(layer "In5.Cu")
	)
	(gr_line
		(start 377.630182 -32.91078)
		(end 377.83262 -32.610806)
		(stroke
			(width 0.060198)
			(type default)
		)
		(layer "In5.Cu")
	)
	(gr_line
		(start 377.724416 -31.806134)
		(end 378.107194 -31.238444)
		(stroke
			(width 0.060198)
			(type default)
		)
		(layer "In5.Cu")
	)
	(gr_line
		(start 377.764548 -48.26381)
		(end 378.338588 -47.882048)
		(stroke
			(width 0.060198)
			(type default)
		)
		(layer "In5.Cu")
	)
	(gr_line
		(start 377.778518 -32.331914)
		(end 377.83262 -32.610806)
		(stroke
			(width 0.060198)
			(type default)
		)
		(layer "In5.Cu")
	)
	(gr_line
		(start 377.92152 -48.566578)
		(end 378.200158 -48.622712)
		(stroke
			(width 0.060198)
			(type default)
		)
		(layer "In5.Cu")
	)
	(gr_line
		(start 377.983242 -32.02813)
		(end 378.262134 -31.973774)
		(stroke
			(width 0.060198)
			(type default)
		)
		(layer "In5.Cu")
	)
	(gr_line
		(start 378.200158 -48.622712)
		(end 378.501402 -48.422306)
		(stroke
			(width 0.060198)
			(type default)
		)
		(layer "In5.Cu")
	)
	(gr_line
		(start 378.262134 -31.973774)
		(end 378.464572 -31.673546)
		(stroke
			(width 0.060198)
			(type default)
		)
		(layer "In5.Cu")
	)
	(gr_line
		(start 378.356368 -30.86862)
		(end 378.740416 -30.299406)
		(stroke
			(width 0.060198)
			(type default)
		)
		(layer "In5.Cu")
	)
	(gr_line
		(start 378.41047 -31.394908)
		(end 378.464572 -31.673546)
		(stroke
			(width 0.060198)
			(type default)
		)
		(layer "In5.Cu")
	)
	(gr_line
		(start 378.501402 -48.422306)
		(end 378.557536 -48.143668)
		(stroke
			(width 0.060198)
			(type default)
		)
		(layer "In5.Cu")
	)
	(gr_line
		(start 378.615702 -31.090616)
		(end 378.89434 -31.036768)
		(stroke
			(width 0.060198)
			(type default)
		)
		(layer "In5.Cu")
	)
	(gr_line
		(start 378.706126 -47.637446)
		(end 379.280166 -47.255684)
		(stroke
			(width 0.060198)
			(type default)
		)
		(layer "In5.Cu")
	)
	(gr_line
		(start 378.86259 -47.940468)
		(end 379.141228 -47.996602)
		(stroke
			(width 0.060198)
			(type default)
		)
		(layer "In5.Cu")
	)
	(gr_line
		(start 378.89434 -31.036768)
		(end 379.096778 -30.73654)
		(stroke
			(width 0.060198)
			(type default)
		)
		(layer "In5.Cu")
	)
	(gr_line
		(start 379.042422 -30.457648)
		(end 379.096778 -30.73654)
		(stroke
			(width 0.060198)
			(type default)
		)
		(layer "In5.Cu")
	)
	(gr_line
		(start 379.141228 -47.996602)
		(end 379.442472 -47.796196)
		(stroke
			(width 0.060198)
			(type default)
		)
		(layer "In5.Cu")
	)
	(gr_line
		(start 379.442472 -47.796196)
		(end 379.498606 -47.517558)
		(stroke
			(width 0.060198)
			(type default)
		)
		(layer "In5.Cu")
	)
	(gr_line
		(start 383.267204 -235.426504)
		(end 383.267712 -235.426504)
		(stroke
			(width 0.060198)
			(type default)
		)
		(layer "In5.Cu")
	)
	(gr_line
		(start 383.267712 -235.426504)
		(end 383.268474 -235.426758)
		(stroke
			(width 0.060198)
			(type default)
		)
		(layer "In5.Cu")
	)
	(gr_line
		(start 384.416046 -248.909332)
		(end 384.437636 -248.918222)
		(stroke
			(width 0.060198)
			(type default)
		)
		(layer "In5.Cu")
	)
	(gr_line
		(start 385.78155 -132.437124)
		(end 386.106924 -132.437124)
		(stroke
			(width 0.060198)
			(type default)
		)
		(layer "In5.Cu")
	)
	(gr_line
		(start 385.78155 -17.4371)
		(end 386.108448 -17.4371)
		(stroke
			(width 0.060198)
			(type default)
		)
		(layer "In5.Cu")
	)
	(gr_arc
		(start 386.248148 -132.578348)
		(mid 386.206784 -132.478488)
		(end 386.106924 -132.437124)
		(stroke
			(width 0.060198)
			(type default)
		)
		(layer "In5.Cu")
	)
	(gr_arc
		(start 386.248148 -17.5768)
		(mid 386.207231 -17.478017)
		(end 386.108448 -17.4371)
		(stroke
			(width 0.060198)
			(type default)
		)
		(layer "In5.Cu")
	)
	(gr_line
		(start 386.377942 -19.57832)
		(end 386.39369 -19.554952)
		(stroke
			(width 0.060198)
			(type default)
		)
		(layer "In5.Cu")
	)
	(gr_line
		(start 386.39369 -19.554952)
		(end 386.399024 -19.52752)
		(stroke
			(width 0.060198)
			(type default)
		)
		(layer "In5.Cu")
	)
	(gr_arc
		(start 386.486654 -248.581672)
		(mid 386.630158 -248.52223)
		(end 386.6896 -248.378726)
		(stroke
			(width 0.060198)
			(type default)
		)
		(layer "In5.Cu")
	)
	(gr_line
		(start 386.495798 -134.702804)
		(end 386.506974 -134.685786)
		(stroke
			(width 0.060198)
			(type default)
		)
		(layer "In5.Cu")
	)
	(gr_line
		(start 386.506974 -134.685786)
		(end 386.511038 -134.665974)
		(stroke
			(width 0.060198)
			(type default)
		)
		(layer "In5.Cu")
	)
	(gr_arc
		(start 386.6896 -249.121422)
		(mid 386.630092 -248.977724)
		(end 386.4864 -248.918222)
		(stroke
			(width 0.060198)
			(type default)
		)
		(layer "In5.Cu")
	)
	(gr_line
		(start 386.6896 -249.121422)
		(end 386.6896 -249.385074)
		(stroke
			(width 0.060198)
			(type default)
		)
		(layer "In5.Cu")
	)
	(gr_line
		(start 386.6896 -248.115074)
		(end 386.6896 -248.378726)
		(stroke
			(width 0.060198)
			(type default)
		)
		(layer "In5.Cu")
	)
	(gr_arc
		(start 386.724652 -17.4371)
		(mid 386.625704 -17.478106)
		(end 386.584698 -17.577054)
		(stroke
			(width 0.060198)
			(type default)
		)
		(layer "In5.Cu")
	)
	(gr_line
		(start 386.724652 -17.4371)
		(end 387.05155 -17.4371)
		(stroke
			(width 0.060198)
			(type default)
		)
		(layer "In5.Cu")
	)
	(gr_arc
		(start 386.726176 -132.437124)
		(mid 386.626152 -132.478571)
		(end 386.584698 -132.578602)
		(stroke
			(width 0.060198)
			(type default)
		)
		(layer "In5.Cu")
	)
	(gr_line
		(start 386.726176 -132.437124)
		(end 387.05155 -132.437124)
		(stroke
			(width 0.060198)
			(type default)
		)
		(layer "In5.Cu")
	)
	(gr_line
		(start 399.377154 -79.219044)
		(end 399.402808 -79.20228)
		(stroke
			(width 0.060198)
			(type default)
		)
		(layer "In5.Cu")
	)
	(gr_line
		(start 399.402808 -79.20228)
		(end 399.41881 -79.177388)
		(stroke
			(width 0.060198)
			(type default)
		)
		(layer "In5.Cu")
	)
	(gr_line
		(start 399.693638 -75.126596)
		(end 399.72107 -75.10907)
		(stroke
			(width 0.060198)
			(type default)
		)
		(layer "In5.Cu")
	)
	(gr_line
		(start 399.72107 -75.10907)
		(end 399.739104 -75.08113)
		(stroke
			(width 0.060198)
			(type default)
		)
		(layer "In5.Cu")
	)
	(gr_line
		(start 404.446232 -161.546794)
		(end 404.46325 -161.535618)
		(stroke
			(width 0.060198)
			(type default)
		)
		(layer "In5.Cu")
	)
	(gr_line
		(start 404.46325 -161.535618)
		(end 404.483062 -161.531554)
		(stroke
			(width 0.060198)
			(type default)
		)
		(layer "In5.Cu")
	)
	(gr_line
		(start 404.623778 -149.551898)
		(end 405.201374 -149.176486)
		(stroke
			(width 0.060198)
			(type default)
		)
		(layer "In5.Cu")
	)
	(gr_line
		(start 404.776686 -149.856698)
		(end 405.054562 -149.915626)
		(stroke
			(width 0.060198)
			(type default)
		)
		(layer "In5.Cu")
	)
	(gr_line
		(start 405.054562 -149.915626)
		(end 405.358092 -149.718522)
		(stroke
			(width 0.060198)
			(type default)
		)
		(layer "In5.Cu")
	)
	(gr_line
		(start 405.358092 -149.718522)
		(end 405.417274 -149.440646)
		(stroke
			(width 0.060198)
			(type default)
		)
		(layer "In5.Cu")
	)
	(gr_line
		(start 405.427434 -232.25379)
		(end 405.432768 -232.254298)
		(stroke
			(width 0.060198)
			(type default)
		)
		(layer "In5.Cu")
	)
	(gr_line
		(start 405.432768 -232.254298)
		(end 405.437848 -232.25633)
		(stroke
			(width 0.060198)
			(type default)
		)
		(layer "In5.Cu")
	)
	(gr_line
		(start 405.571706 -148.936202)
		(end 406.149302 -148.56079)
		(stroke
			(width 0.060198)
			(type default)
		)
		(layer "In5.Cu")
	)
	(gr_line
		(start 405.724868 -149.241002)
		(end 406.00249 -149.29993)
		(stroke
			(width 0.060198)
			(type default)
		)
		(layer "In5.Cu")
	)
	(gr_line
		(start 406.00249 -149.29993)
		(end 406.30602 -149.102826)
		(stroke
			(width 0.060198)
			(type default)
		)
		(layer "In5.Cu")
	)
	(gr_line
		(start 406.30602 -149.102826)
		(end 406.365202 -148.82495)
		(stroke
			(width 0.060198)
			(type default)
		)
		(layer "In5.Cu")
	)
	(gr_line
		(start 406.520142 -148.319998)
		(end 407.09723 -147.945348)
		(stroke
			(width 0.060198)
			(type default)
		)
		(layer "In5.Cu")
	)
	(gr_line
		(start 406.61336 -161.078672)
		(end 407.28265 -160.936432)
		(stroke
			(width 0.060198)
			(type default)
		)
		(layer "In5.Cu")
	)
	(gr_line
		(start 406.645618 -161.418524)
		(end 406.883616 -161.572956)
		(stroke
			(width 0.060198)
			(type default)
		)
		(layer "In5.Cu")
	)
	(gr_line
		(start 406.672796 -148.625306)
		(end 406.950418 -148.684234)
		(stroke
			(width 0.060198)
			(type default)
		)
		(layer "In5.Cu")
	)
	(gr_line
		(start 406.883616 -161.572956)
		(end 407.237438 -161.497772)
		(stroke
			(width 0.060198)
			(type default)
		)
		(layer "In5.Cu")
	)
	(gr_line
		(start 406.950418 -148.684234)
		(end 407.253948 -148.48713)
		(stroke
			(width 0.060198)
			(type default)
		)
		(layer "In5.Cu")
	)
	(gr_line
		(start 406.96261 -244.900704)
		(end 407.602436 -245.14683)
		(stroke
			(width 0.060198)
			(type default)
		)
		(layer "In5.Cu")
	)
	(gr_line
		(start 407.047192 -244.57025)
		(end 407.306526 -244.45468)
		(stroke
			(width 0.060198)
			(type default)
		)
		(layer "In5.Cu")
	)
	(gr_line
		(start 407.237438 -161.497772)
		(end 407.392124 -161.259774)
		(stroke
			(width 0.060198)
			(type default)
		)
		(layer "In5.Cu")
	)
	(gr_line
		(start 407.253948 -148.48713)
		(end 407.31313 -148.209508)
		(stroke
			(width 0.060198)
			(type default)
		)
		(layer "In5.Cu")
	)
	(gr_line
		(start 407.306526 -244.45468)
		(end 407.6446 -244.584728)
		(stroke
			(width 0.060198)
			(type default)
		)
		(layer "In5.Cu")
	)
	(gr_line
		(start 407.6446 -244.584728)
		(end 407.759916 -244.844316)
		(stroke
			(width 0.060198)
			(type default)
		)
		(layer "In5.Cu")
	)
	(gr_line
		(start 407.7208 -160.843468)
		(end 408.387804 -160.701736)
		(stroke
			(width 0.060198)
			(type default)
		)
		(layer "In5.Cu")
	)
	(gr_line
		(start 407.751026 -161.18332)
		(end 407.989024 -161.338006)
		(stroke
			(width 0.060198)
			(type default)
		)
		(layer "In5.Cu")
	)
	(gr_line
		(start 407.989024 -161.338006)
		(end 408.3431 -161.262822)
		(stroke
			(width 0.060198)
			(type default)
		)
		(layer "In5.Cu")
	)
	(gr_line
		(start 408.017472 -245.306342)
		(end 408.656028 -245.55196)
		(stroke
			(width 0.060198)
			(type default)
		)
		(layer "In5.Cu")
	)
	(gr_line
		(start 408.102054 -244.975888)
		(end 408.361642 -244.860572)
		(stroke
			(width 0.060198)
			(type default)
		)
		(layer "In5.Cu")
	)
	(gr_line
		(start 408.3431 -161.262822)
		(end 408.497532 -161.024824)
		(stroke
			(width 0.060198)
			(type default)
		)
		(layer "In5.Cu")
	)
	(gr_line
		(start 408.361642 -244.860572)
		(end 408.699462 -244.990366)
		(stroke
			(width 0.060198)
			(type default)
		)
		(layer "In5.Cu")
	)
	(gr_line
		(start 408.699462 -244.990366)
		(end 408.814778 -245.249954)
		(stroke
			(width 0.060198)
			(type default)
		)
		(layer "In5.Cu")
	)
	(gr_line
		(start 408.82316 -160.608772)
		(end 409.495244 -160.466024)
		(stroke
			(width 0.060198)
			(type default)
		)
		(layer "In5.Cu")
	)
	(gr_line
		(start 408.856434 -160.94837)
		(end 409.094686 -161.103056)
		(stroke
			(width 0.060198)
			(type default)
		)
		(layer "In5.Cu")
	)
	(gr_line
		(start 409.073604 -245.712488)
		(end 409.71216 -245.958106)
		(stroke
			(width 0.060198)
			(type default)
		)
		(layer "In5.Cu")
	)
	(gr_line
		(start 409.094686 -161.103056)
		(end 409.448762 -161.027618)
		(stroke
			(width 0.060198)
			(type default)
		)
		(layer "In5.Cu")
	)
	(gr_line
		(start 409.15717 -245.381526)
		(end 409.416504 -245.26621)
		(stroke
			(width 0.060198)
			(type default)
		)
		(layer "In5.Cu")
	)
	(gr_line
		(start 409.416504 -245.26621)
		(end 409.754324 -245.396258)
		(stroke
			(width 0.060198)
			(type default)
		)
		(layer "In5.Cu")
	)
	(gr_line
		(start 409.448762 -161.027618)
		(end 409.603448 -160.78962)
		(stroke
			(width 0.060198)
			(type default)
		)
		(layer "In5.Cu")
	)
	(gr_line
		(start 409.754324 -245.396258)
		(end 409.86964 -245.655592)
		(stroke
			(width 0.060198)
			(type default)
		)
		(layer "In5.Cu")
	)
	(gr_line
		(start 410.334714 -146.24431)
		(end 410.360368 -146.227546)
		(stroke
			(width 0.060198)
			(type default)
		)
		(layer "In5.Cu")
	)
	(gr_line
		(start 410.360368 -146.227546)
		(end 410.37637 -146.202654)
		(stroke
			(width 0.060198)
			(type default)
		)
		(layer "In5.Cu")
	)
	(gr_line
		(start 414.315148 -152.162764)
		(end 414.332166 -152.151588)
		(stroke
			(width 0.060198)
			(type default)
		)
		(layer "In5.Cu")
	)
	(gr_line
		(start 414.332166 -152.151588)
		(end 414.351978 -152.147524)
		(stroke
			(width 0.060198)
			(type default)
		)
		(layer "In5.Cu")
	)
	(gr_line
		(start 414.595056 -24.166576)
		(end 414.619694 -24.15032)
		(stroke
			(width 0.060198)
			(type default)
		)
		(layer "In5.Cu")
	)
	(gr_line
		(start 414.619694 -24.15032)
		(end 414.635696 -24.125428)
		(stroke
			(width 0.060198)
			(type default)
		)
		(layer "In5.Cu")
	)
	(gr_line
		(start 416.681666 -51.973988)
		(end 416.697668 -51.949096)
		(stroke
			(width 0.060198)
			(type default)
		)
		(layer "In5.Cu")
	)
	(gr_line
		(start 416.697668 -51.949096)
		(end 416.723322 -51.932332)
		(stroke
			(width 0.060198)
			(type default)
		)
		(layer "In5.Cu")
	)
	(gr_line
		(start 417.331652 -132.437124)
		(end 417.596574 -132.437124)
		(stroke
			(width 0.060198)
			(type default)
		)
		(layer "In5.Cu")
	)
	(gr_line
		(start 417.331652 -17.4371)
		(end 417.65855 -17.4371)
		(stroke
			(width 0.060198)
			(type default)
		)
		(layer "In5.Cu")
	)
	(gr_line
		(start 417.387532 -248.910602)
		(end 417.407598 -248.918222)
		(stroke
			(width 0.060198)
			(type default)
		)
		(layer "In5.Cu")
	)
	(gr_arc
		(start 417.79825 -132.6388)
		(mid 417.73918 -132.496194)
		(end 417.596574 -132.437124)
		(stroke
			(width 0.060198)
			(type default)
		)
		(layer "In5.Cu")
	)
	(gr_arc
		(start 417.79825 -17.5768)
		(mid 417.757333 -17.478017)
		(end 417.65855 -17.4371)
		(stroke
			(width 0.060198)
			(type default)
		)
		(layer "In5.Cu")
	)
	(gr_line
		(start 418.005006 -18.9357)
		(end 418.016182 -18.918682)
		(stroke
			(width 0.060198)
			(type default)
		)
		(layer "In5.Cu")
	)
	(gr_line
		(start 418.016182 -18.918682)
		(end 418.0205 -18.898362)
		(stroke
			(width 0.060198)
			(type default)
		)
		(layer "In5.Cu")
	)
	(gr_line
		(start 418.102796 -134.298182)
		(end 418.1348 -134.248906)
		(stroke
			(width 0.060198)
			(type default)
		)
		(layer "In5.Cu")
	)
	(gr_arc
		(start 418.119052 -248.581672)
		(mid 418.204364 -248.546334)
		(end 418.239702 -248.461022)
		(stroke
			(width 0.060198)
			(type default)
		)
		(layer "In5.Cu")
	)
	(gr_arc
		(start 418.239702 -249.038872)
		(mid 418.204352 -248.953595)
		(end 418.119052 -248.918222)
		(stroke
			(width 0.060198)
			(type default)
		)
		(layer "In5.Cu")
	)
	(gr_line
		(start 418.239702 -249.038872)
		(end 418.239702 -249.385074)
		(stroke
			(width 0.060198)
			(type default)
		)
		(layer "In5.Cu")
	)
	(gr_line
		(start 418.239702 -248.115074)
		(end 418.239702 -248.461022)
		(stroke
			(width 0.060198)
			(type default)
		)
		(layer "In5.Cu")
	)
	(gr_arc
		(start 418.274754 -17.4371)
		(mid 418.175805 -17.478105)
		(end 418.1348 -17.577054)
		(stroke
			(width 0.060198)
			(type default)
		)
		(layer "In5.Cu")
	)
	(gr_line
		(start 418.274754 -17.4371)
		(end 418.601652 -17.4371)
		(stroke
			(width 0.060198)
			(type default)
		)
		(layer "In5.Cu")
	)
	(gr_arc
		(start 418.336476 -132.437124)
		(mid 418.193885 -132.496202)
		(end 418.1348 -132.6388)
		(stroke
			(width 0.060198)
			(type default)
		)
		(layer "In5.Cu")
	)
	(gr_line
		(start 418.336476 -132.437124)
		(end 418.601652 -132.437124)
		(stroke
			(width 0.060198)
			(type default)
		)
		(layer "In5.Cu")
	)
	(gr_line
		(start 425.68368 -34.343086)
		(end 425.701714 -34.315146)
		(stroke
			(width 0.060198)
			(type default)
		)
		(layer "In5.Cu")
	)
	(gr_line
		(start 425.701714 -34.315146)
		(end 425.729146 -34.29762)
		(stroke
			(width 0.060198)
			(type default)
		)
		(layer "In5.Cu")
	)
	(gr_line
		(start 428.230538 -149.54123)
		(end 428.25035 -149.537166)
		(stroke
			(width 0.060198)
			(type default)
		)
		(layer "In5.Cu")
	)
	(gr_line
		(start 428.25035 -149.537166)
		(end 428.267368 -149.52599)
		(stroke
			(width 0.060198)
			(type default)
		)
		(layer "In5.Cu")
	)
	(gr_line
		(start 432.923442 -29.62529)
		(end 433.503832 -29.248354)
		(stroke
			(width 0.060198)
			(type default)
		)
		(layer "In5.Cu")
	)
	(gr_line
		(start 433.078636 -29.929074)
		(end 433.356766 -29.988002)
		(stroke
			(width 0.060198)
			(type default)
		)
		(layer "In5.Cu")
	)
	(gr_line
		(start 433.2097 -41.226486)
		(end 433.226718 -41.21531)
		(stroke
			(width 0.060198)
			(type default)
		)
		(layer "In5.Cu")
	)
	(gr_line
		(start 433.226718 -41.21531)
		(end 433.24653 -41.211246)
		(stroke
			(width 0.060198)
			(type default)
		)
		(layer "In5.Cu")
	)
	(gr_line
		(start 433.356766 -29.988002)
		(end 433.660296 -29.790898)
		(stroke
			(width 0.060198)
			(type default)
		)
		(layer "In5.Cu")
	)
	(gr_line
		(start 433.660296 -29.790898)
		(end 433.719224 -29.513022)
		(stroke
			(width 0.060198)
			(type default)
		)
		(layer "In5.Cu")
	)
	(gr_line
		(start 433.874164 -29.008324)
		(end 434.450236 -28.633928)
		(stroke
			(width 0.060198)
			(type default)
		)
		(layer "In5.Cu")
	)
	(gr_line
		(start 434.026818 -29.313378)
		(end 434.304694 -29.372306)
		(stroke
			(width 0.060198)
			(type default)
		)
		(layer "In5.Cu")
	)
	(gr_line
		(start 434.304694 -29.372306)
		(end 434.608224 -29.175202)
		(stroke
			(width 0.060198)
			(type default)
		)
		(layer "In5.Cu")
	)
	(gr_line
		(start 434.608224 -29.175202)
		(end 434.667152 -28.897326)
		(stroke
			(width 0.060198)
			(type default)
		)
		(layer "In5.Cu")
	)
	(gr_line
		(start 434.822854 -28.39212)
		(end 435.39918 -28.017724)
		(stroke
			(width 0.060198)
			(type default)
		)
		(layer "In5.Cu")
	)
	(gr_line
		(start 434.974746 -28.697682)
		(end 435.252622 -28.756864)
		(stroke
			(width 0.060198)
			(type default)
		)
		(layer "In5.Cu")
	)
	(gr_line
		(start 435.252622 -28.756864)
		(end 435.556152 -28.559506)
		(stroke
			(width 0.060198)
			(type default)
		)
		(layer "In5.Cu")
	)
	(gr_line
		(start 435.556152 -28.559506)
		(end 435.61508 -28.281884)
		(stroke
			(width 0.060198)
			(type default)
		)
		(layer "In5.Cu")
	)
	(gr_line
		(start 439.652664 -245.48846)
		(end 440.299094 -245.731792)
		(stroke
			(width 0.060198)
			(type default)
		)
		(layer "In5.Cu")
	)
	(gr_line
		(start 439.738008 -245.15826)
		(end 439.99658 -245.040912)
		(stroke
			(width 0.060198)
			(type default)
		)
		(layer "In5.Cu")
	)
	(gr_line
		(start 439.99658 -245.040912)
		(end 440.335416 -245.16842)
		(stroke
			(width 0.060198)
			(type default)
		)
		(layer "In5.Cu")
	)
	(gr_line
		(start 440.335416 -245.16842)
		(end 440.452764 -245.426992)
		(stroke
			(width 0.060198)
			(type default)
		)
		(layer "In5.Cu")
	)
	(gr_line
		(start 440.710574 -245.886478)
		(end 441.357004 -246.12981)
		(stroke
			(width 0.060198)
			(type default)
		)
		(layer "In5.Cu")
	)
	(gr_line
		(start 440.795918 -245.556278)
		(end 441.05449 -245.43893)
		(stroke
			(width 0.060198)
			(type default)
		)
		(layer "In5.Cu")
	)
	(gr_line
		(start 441.05449 -245.43893)
		(end 441.393326 -245.566438)
		(stroke
			(width 0.060198)
			(type default)
		)
		(layer "In5.Cu")
	)
	(gr_line
		(start 441.393326 -245.566438)
		(end 441.510674 -245.82501)
		(stroke
			(width 0.060198)
			(type default)
		)
		(layer "In5.Cu")
	)
	(gr_line
		(start 441.7695 -246.28475)
		(end 442.412628 -246.526812)
		(stroke
			(width 0.060198)
			(type default)
		)
		(layer "In5.Cu")
	)
	(gr_line
		(start 441.853828 -245.954296)
		(end 442.112654 -245.836948)
		(stroke
			(width 0.060198)
			(type default)
		)
		(layer "In5.Cu")
	)
	(gr_line
		(start 442.112654 -245.836948)
		(end 442.451236 -245.964456)
		(stroke
			(width 0.060198)
			(type default)
		)
		(layer "In5.Cu")
	)
	(gr_line
		(start 442.451236 -245.964456)
		(end 442.56833 -246.223028)
		(stroke
			(width 0.060198)
			(type default)
		)
		(layer "In5.Cu")
	)
	(gr_line
		(start 447.03111 -137.341864)
		(end 447.056002 -137.325862)
		(stroke
			(width 0.060198)
			(type default)
		)
		(layer "In5.Cu")
	)
	(gr_line
		(start 447.056002 -137.325862)
		(end 447.072766 -137.300208)
		(stroke
			(width 0.060198)
			(type default)
		)
		(layer "In5.Cu")
	)
	(gr_line
		(start 448.75069 -248.911364)
		(end 448.769232 -248.918222)
		(stroke
			(width 0.060198)
			(type default)
		)
		(layer "In5.Cu")
	)
	(gr_line
		(start 448.8815 -132.437124)
		(end 449.200524 -132.437124)
		(stroke
			(width 0.060198)
			(type default)
		)
		(layer "In5.Cu")
	)
	(gr_line
		(start 448.8815 -17.4371)
		(end 449.208398 -17.4371)
		(stroke
			(width 0.060198)
			(type default)
		)
		(layer "In5.Cu")
	)
	(gr_line
		(start 448.896994 -19.653504)
		(end 448.92341 -19.636486)
		(stroke
			(width 0.060198)
			(type default)
		)
		(layer "In5.Cu")
	)
	(gr_line
		(start 448.92341 -19.636486)
		(end 448.940428 -19.61007)
		(stroke
			(width 0.060198)
			(type default)
		)
		(layer "In5.Cu")
	)
	(gr_arc
		(start 449.348098 -132.584698)
		(mid 449.304875 -132.480347)
		(end 449.200524 -132.437124)
		(stroke
			(width 0.060198)
			(type default)
		)
		(layer "In5.Cu")
	)
	(gr_arc
		(start 449.348098 -17.5768)
		(mid 449.307181 -17.478017)
		(end 449.208398 -17.4371)
		(stroke
			(width 0.060198)
			(type default)
		)
		(layer "In5.Cu")
	)
	(gr_line
		(start 449.652644 -133.329426)
		(end 449.684648 -133.28015)
		(stroke
			(width 0.060198)
			(type default)
		)
		(layer "In5.Cu")
	)
	(gr_line
		(start 449.653406 -18.503646)
		(end 449.684648 -18.455132)
		(stroke
			(width 0.060198)
			(type default)
		)
		(layer "In5.Cu")
	)
	(gr_arc
		(start 449.6689 -248.581672)
		(mid 449.754212 -248.546334)
		(end 449.78955 -248.461022)
		(stroke
			(width 0.060198)
			(type default)
		)
		(layer "In5.Cu")
	)
	(gr_arc
		(start 449.78955 -249.038872)
		(mid 449.754203 -248.953578)
		(end 449.6689 -248.918222)
		(stroke
			(width 0.060198)
			(type default)
		)
		(layer "In5.Cu")
	)
	(gr_line
		(start 449.78955 -249.038872)
		(end 449.78955 -249.385074)
		(stroke
			(width 0.060198)
			(type default)
		)
		(layer "In5.Cu")
	)
	(gr_line
		(start 449.78955 -248.115074)
		(end 449.78955 -248.461022)
		(stroke
			(width 0.060198)
			(type default)
		)
		(layer "In5.Cu")
	)
	(gr_arc
		(start 449.824602 -17.4371)
		(mid 449.725622 -17.478088)
		(end 449.684648 -17.577054)
		(stroke
			(width 0.060198)
			(type default)
		)
		(layer "In5.Cu")
	)
	(gr_line
		(start 449.824602 -17.4371)
		(end 450.1515 -17.4371)
		(stroke
			(width 0.060198)
			(type default)
		)
		(layer "In5.Cu")
	)
	(gr_arc
		(start 449.832476 -132.437124)
		(mid 449.727944 -132.480427)
		(end 449.684648 -132.584952)
		(stroke
			(width 0.060198)
			(type default)
		)
		(layer "In5.Cu")
	)
	(gr_line
		(start 449.832476 -132.437124)
		(end 450.1515 -132.437124)
		(stroke
			(width 0.060198)
			(type default)
		)
		(layer "In5.Cu")
	)
	(gr_line
		(start 462.67116 -149.50694)
		(end 462.690972 -149.502876)
		(stroke
			(width 0.060198)
			(type default)
		)
		(layer "In5.Cu")
	)
	(gr_line
		(start 462.690972 -149.502876)
		(end 462.70799 -149.4917)
		(stroke
			(width 0.060198)
			(type default)
		)
		(layer "In5.Cu")
	)
	(gr_line
		(start 464.025742 -238.1504)
		(end 464.684618 -238.348266)
		(stroke
			(width 0.060198)
			(type default)
		)
		(layer "In5.Cu")
	)
	(gr_line
		(start 464.086956 -237.814866)
		(end 464.337146 -237.680246)
		(stroke
			(width 0.060198)
			(type default)
		)
		(layer "In5.Cu")
	)
	(gr_line
		(start 464.337146 -237.680246)
		(end 464.683856 -237.784386)
		(stroke
			(width 0.060198)
			(type default)
		)
		(layer "In5.Cu")
	)
	(gr_line
		(start 464.683856 -237.784386)
		(end 464.818476 -238.034576)
		(stroke
			(width 0.060198)
			(type default)
		)
		(layer "In5.Cu")
	)
	(gr_line
		(start 465.109052 -238.475774)
		(end 465.766658 -238.673132)
		(stroke
			(width 0.060198)
			(type default)
		)
		(layer "In5.Cu")
	)
	(gr_line
		(start 465.169504 -238.139986)
		(end 465.419694 -238.005366)
		(stroke
			(width 0.060198)
			(type default)
		)
		(layer "In5.Cu")
	)
	(gr_line
		(start 465.419694 -238.005366)
		(end 465.766404 -238.109506)
		(stroke
			(width 0.060198)
			(type default)
		)
		(layer "In5.Cu")
	)
	(gr_line
		(start 465.766404 -238.109506)
		(end 465.901024 -238.359696)
		(stroke
			(width 0.060198)
			(type default)
		)
		(layer "In5.Cu")
	)
	(gr_line
		(start 466.190838 -238.80064)
		(end 466.849714 -238.998506)
		(stroke
			(width 0.060198)
			(type default)
		)
		(layer "In5.Cu")
	)
	(gr_line
		(start 466.252052 -238.465106)
		(end 466.502242 -238.330486)
		(stroke
			(width 0.060198)
			(type default)
		)
		(layer "In5.Cu")
	)
	(gr_line
		(start 466.502242 -238.330486)
		(end 466.848952 -238.434626)
		(stroke
			(width 0.060198)
			(type default)
		)
		(layer "In5.Cu")
	)
	(gr_line
		(start 466.848952 -238.434626)
		(end 466.983572 -238.684816)
		(stroke
			(width 0.060198)
			(type default)
		)
		(layer "In5.Cu")
	)
	(gr_line
		(start 469.097868 -33.934146)
		(end 469.11768 -33.930082)
		(stroke
			(width 0.060198)
			(type default)
		)
		(layer "In5.Cu")
	)
	(gr_line
		(start 469.11768 -33.930082)
		(end 469.134698 -33.918906)
		(stroke
			(width 0.060198)
			(type default)
		)
		(layer "In5.Cu")
	)
	(gr_line
		(start 472.670378 -241.847116)
		(end 472.698318 -241.863118)
		(stroke
			(width 0.060198)
			(type default)
		)
		(layer "In5.Cu")
	)
	(gr_line
		(start 472.698318 -241.863118)
		(end 472.717368 -241.889026)
		(stroke
			(width 0.060198)
			(type default)
		)
		(layer "In5.Cu")
	)
	(gr_line
		(start 474.874082 -30.191964)
		(end 474.899736 -30.1752)
		(stroke
			(width 0.060198)
			(type default)
		)
		(layer "In5.Cu")
	)
	(gr_line
		(start 474.899736 -30.1752)
		(end 474.9165 -30.149546)
		(stroke
			(width 0.060198)
			(type default)
		)
		(layer "In5.Cu")
	)
	(gr_line
		(start 476.392748 -247.474994)
		(end 476.416624 -247.507506)
		(stroke
			(width 0.060198)
			(type default)
		)
		(layer "In5.Cu")
	)
	(gr_line
		(start 476.416624 -247.507506)
		(end 476.452438 -247.525794)
		(stroke
			(width 0.060198)
			(type default)
		)
		(layer "In5.Cu")
	)
	(gr_line
		(start 478.658936 -139.13358)
		(end 478.68459 -139.116816)
		(stroke
			(width 0.060198)
			(type default)
		)
		(layer "In5.Cu")
	)
	(gr_line
		(start 478.68459 -139.116816)
		(end 478.701354 -139.091162)
		(stroke
			(width 0.060198)
			(type default)
		)
		(layer "In5.Cu")
	)
	(gr_line
		(start 479.16465 -248.900442)
		(end 479.199702 -248.918222)
		(stroke
			(width 0.060198)
			(type default)
		)
		(layer "In5.Cu")
	)
	(gr_line
		(start 480.431602 -132.437124)
		(end 480.772724 -132.437124)
		(stroke
			(width 0.060198)
			(type default)
		)
		(layer "In5.Cu")
	)
	(gr_line
		(start 480.431602 -17.4371)
		(end 480.7585 -17.4371)
		(stroke
			(width 0.060198)
			(type default)
		)
		(layer "In5.Cu")
	)
	(gr_line
		(start 480.545394 -21.482558)
		(end 480.55657 -21.46554)
		(stroke
			(width 0.060198)
			(type default)
		)
		(layer "In5.Cu")
	)
	(gr_line
		(start 480.55657 -21.46554)
		(end 480.560634 -21.445728)
		(stroke
			(width 0.060198)
			(type default)
		)
		(layer "In5.Cu")
	)
	(gr_arc
		(start 480.8982 -132.5626)
		(mid 480.861449 -132.473875)
		(end 480.772724 -132.437124)
		(stroke
			(width 0.060198)
			(type default)
		)
		(layer "In5.Cu")
	)
	(gr_arc
		(start 480.8982 -17.5768)
		(mid 480.857283 -17.478017)
		(end 480.7585 -17.4371)
		(stroke
			(width 0.060198)
			(type default)
		)
		(layer "In5.Cu")
	)
	(gr_arc
		(start 481.152454 -248.581672)
		(mid 481.284823 -248.526843)
		(end 481.339652 -248.394474)
		(stroke
			(width 0.060198)
			(type default)
		)
		(layer "In5.Cu")
	)
	(gr_line
		(start 481.202746 -135.239252)
		(end 481.23475 -135.189976)
		(stroke
			(width 0.060198)
			(type default)
		)
		(layer "In5.Cu")
	)
	(gr_arc
		(start 481.339652 -249.105674)
		(mid 481.284739 -248.973142)
		(end 481.1522 -248.918222)
		(stroke
			(width 0.060198)
			(type default)
		)
		(layer "In5.Cu")
	)
	(gr_line
		(start 481.339652 -249.105674)
		(end 481.339652 -249.385074)
		(stroke
			(width 0.060198)
			(type default)
		)
		(layer "In5.Cu")
	)
	(gr_line
		(start 481.339652 -248.115074)
		(end 481.339652 -248.394474)
		(stroke
			(width 0.060198)
			(type default)
		)
		(layer "In5.Cu")
	)
	(gr_arc
		(start 481.36048 -132.437124)
		(mid 481.271572 -132.473954)
		(end 481.23475 -132.562854)
		(stroke
			(width 0.060198)
			(type default)
		)
		(layer "In5.Cu")
	)
	(gr_line
		(start 481.36048 -132.437124)
		(end 481.701602 -132.437124)
		(stroke
			(width 0.060198)
			(type default)
		)
		(layer "In5.Cu")
	)
	(gr_arc
		(start 481.3935 -17.4371)
		(mid 481.281229 -17.483594)
		(end 481.23475 -17.59585)
		(stroke
			(width 0.060198)
			(type default)
		)
		(layer "In5.Cu")
	)
	(gr_line
		(start 481.3935 -17.4371)
		(end 481.701602 -17.4371)
		(stroke
			(width 0.060198)
			(type default)
		)
		(layer "In5.Cu")
	)
	(gr_line
		(start 0 -370.000022)
		(end 0 -0.999998)
		(stroke
			(width 1.524)
			(type default)
		)
		(layer "In6.Cu")
	)
	(gr_arc
		(start 0 -370.000022)
		(mid 0.292893 -370.707127)
		(end 0.999998 -371.00002)
		(stroke
			(width 1.524)
			(type default)
		)
		(layer "In6.Cu")
	)
	(gr_arc
		(start 0.999998 0)
		(mid 0.292893 -0.292893)
		(end 0 -0.999998)
		(stroke
			(width 1.524)
			(type default)
		)
		(layer "In6.Cu")
	)
	(gr_line
		(start 0.999998 0)
		(end 198.000112 0)
		(stroke
			(width 1.524)
			(type default)
		)
		(layer "In6.Cu")
	)
	(gr_line
		(start 1.999996 -371.00002)
		(end 0.999998 -371.00002)
		(stroke
			(width 1.524)
			(type default)
		)
		(layer "In6.Cu")
	)
	(gr_line
		(start 2.999994 -384.999992)
		(end 2.999994 -372.000018)
		(stroke
			(width 1.524)
			(type default)
		)
		(layer "In6.Cu")
	)
	(gr_arc
		(start 2.999994 -384.999992)
		(mid 3.292883 -385.707105)
		(end 3.999992 -385.99999)
		(stroke
			(width 1.524)
			(type default)
		)
		(layer "In6.Cu")
	)
	(gr_arc
		(start 2.999994 -372.000018)
		(mid 2.707101 -371.292913)
		(end 1.999996 -371.00002)
		(stroke
			(width 1.524)
			(type default)
		)
		(layer "In6.Cu")
	)
	(gr_line
		(start 15.249906 -385.99999)
		(end 3.999992 -385.99999)
		(stroke
			(width 1.524)
			(type default)
		)
		(layer "In6.Cu")
	)
	(gr_arc
		(start 15.249906 -385.99999)
		(mid 15.957005 -385.707095)
		(end 16.249904 -384.999992)
		(stroke
			(width 1.524)
			(type default)
		)
		(layer "In6.Cu")
	)
	(gr_line
		(start 16.249904 -383.29997)
		(end 16.249904 -384.999992)
		(stroke
			(width 1.524)
			(type default)
		)
		(layer "In6.Cu")
	)
	(gr_arc
		(start 17.249902 -382.299972)
		(mid 16.542797 -382.592865)
		(end 16.249904 -383.29997)
		(stroke
			(width 1.524)
			(type default)
		)
		(layer "In6.Cu")
	)
	(gr_line
		(start 23.750016 -382.299972)
		(end 17.249902 -382.299972)
		(stroke
			(width 1.524)
			(type default)
		)
		(layer "In6.Cu")
	)
	(gr_line
		(start 24.750014 -384.999992)
		(end 24.750014 -383.29997)
		(stroke
			(width 1.524)
			(type default)
		)
		(layer "In6.Cu")
	)
	(gr_arc
		(start 24.750014 -384.999992)
		(mid 25.042905 -385.707098)
		(end 25.750012 -385.99999)
		(stroke
			(width 1.524)
			(type default)
		)
		(layer "In6.Cu")
	)
	(gr_arc
		(start 24.750014 -383.29997)
		(mid 24.457121 -382.592865)
		(end 23.750016 -382.299972)
		(stroke
			(width 1.524)
			(type default)
		)
		(layer "In6.Cu")
	)
	(gr_arc
		(start 32.023812 -249.385074)
		(mid 32.508952 -249.870214)
		(end 32.994092 -249.385074)
		(stroke
			(width 0.2)
			(type default)
		)
		(layer "In6.Cu")
	)
	(gr_line
		(start 32.023812 -248.115074)
		(end 32.023812 -249.385074)
		(stroke
			(width 0.2)
			(type default)
		)
		(layer "In6.Cu")
	)
	(gr_arc
		(start 32.023812 -134.384796)
		(mid 32.508825 -134.87019)
		(end 32.994092 -134.38505)
		(stroke
			(width 0.2)
			(type default)
		)
		(layer "In6.Cu")
	)
	(gr_line
		(start 32.023812 -133.11505)
		(end 32.023812 -134.384796)
		(stroke
			(width 0.2)
			(type default)
		)
		(layer "In6.Cu")
	)
	(gr_arc
		(start 32.023812 -19.385026)
		(mid 32.508952 -19.870166)
		(end 32.994092 -19.385026)
		(stroke
			(width 0.2)
			(type default)
		)
		(layer "In6.Cu")
	)
	(gr_line
		(start 32.023812 -18.115026)
		(end 32.023812 -19.385026)
		(stroke
			(width 0.2)
			(type default)
		)
		(layer "In6.Cu")
	)
	(gr_line
		(start 32.994092 -249.385074)
		(end 32.994092 -248.115328)
		(stroke
			(width 0.2)
			(type default)
		)
		(layer "In6.Cu")
	)
	(gr_arc
		(start 32.994092 -248.115328)
		(mid 32.509079 -247.629934)
		(end 32.023812 -248.115074)
		(stroke
			(width 0.2)
			(type default)
		)
		(layer "In6.Cu")
	)
	(gr_line
		(start 32.994092 -134.38505)
		(end 32.994092 -133.11505)
		(stroke
			(width 0.2)
			(type default)
		)
		(layer "In6.Cu")
	)
	(gr_arc
		(start 32.994092 -133.11505)
		(mid 32.508952 -132.62991)
		(end 32.023812 -133.11505)
		(stroke
			(width 0.2)
			(type default)
		)
		(layer "In6.Cu")
	)
	(gr_line
		(start 32.994092 -19.385026)
		(end 32.994092 -18.11528)
		(stroke
			(width 0.2)
			(type default)
		)
		(layer "In6.Cu")
	)
	(gr_arc
		(start 32.994092 -18.11528)
		(mid 32.509079 -17.629886)
		(end 32.023812 -18.115026)
		(stroke
			(width 0.2)
			(type default)
		)
		(layer "In6.Cu")
	)
	(gr_arc
		(start 33.800542 -245.56212)
		(mid 34.285555 -246.047514)
		(end 34.770822 -245.562374)
		(stroke
			(width 0.2)
			(type default)
		)
		(layer "In6.Cu")
	)
	(gr_line
		(start 33.800542 -244.419374)
		(end 33.800542 -245.56212)
		(stroke
			(width 0.2)
			(type default)
		)
		(layer "In6.Cu")
	)
	(gr_arc
		(start 33.800542 -130.56235)
		(mid 34.285682 -131.04749)
		(end 34.770822 -130.56235)
		(stroke
			(width 0.2)
			(type default)
		)
		(layer "In6.Cu")
	)
	(gr_line
		(start 33.800542 -129.41935)
		(end 33.800542 -130.56235)
		(stroke
			(width 0.2)
			(type default)
		)
		(layer "In6.Cu")
	)
	(gr_arc
		(start 33.800542 -15.562326)
		(mid 34.285682 -16.047466)
		(end 34.770822 -15.562326)
		(stroke
			(width 0.2)
			(type default)
		)
		(layer "In6.Cu")
	)
	(gr_line
		(start 33.800542 -14.419326)
		(end 33.800542 -15.562326)
		(stroke
			(width 0.2)
			(type default)
		)
		(layer "In6.Cu")
	)
	(gr_line
		(start 34.770822 -245.562374)
		(end 34.770822 -244.419374)
		(stroke
			(width 0.2)
			(type default)
		)
		(layer "In6.Cu")
	)
	(gr_arc
		(start 34.770822 -244.419374)
		(mid 34.285682 -243.934234)
		(end 33.800542 -244.419374)
		(stroke
			(width 0.2)
			(type default)
		)
		(layer "In6.Cu")
	)
	(gr_line
		(start 34.770822 -130.56235)
		(end 34.770822 -129.419604)
		(stroke
			(width 0.2)
			(type default)
		)
		(layer "In6.Cu")
	)
	(gr_arc
		(start 34.770822 -129.419604)
		(mid 34.285809 -128.93421)
		(end 33.800542 -129.41935)
		(stroke
			(width 0.2)
			(type default)
		)
		(layer "In6.Cu")
	)
	(gr_line
		(start 34.770822 -15.562326)
		(end 34.770822 -14.41958)
		(stroke
			(width 0.2)
			(type default)
		)
		(layer "In6.Cu")
	)
	(gr_arc
		(start 34.770822 -14.41958)
		(mid 34.285809 -13.934186)
		(end 33.800542 -14.419326)
		(stroke
			(width 0.2)
			(type default)
		)
		(layer "In6.Cu")
	)
	(gr_arc
		(start 63.57366 -249.385074)
		(mid 64.0588 -249.870214)
		(end 64.54394 -249.385074)
		(stroke
			(width 0.2)
			(type default)
		)
		(layer "In6.Cu")
	)
	(gr_line
		(start 63.57366 -248.115074)
		(end 63.57366 -249.385074)
		(stroke
			(width 0.2)
			(type default)
		)
		(layer "In6.Cu")
	)
	(gr_arc
		(start 63.57366 -134.384796)
		(mid 64.058673 -134.87019)
		(end 64.54394 -134.38505)
		(stroke
			(width 0.2)
			(type default)
		)
		(layer "In6.Cu")
	)
	(gr_line
		(start 63.57366 -133.11505)
		(end 63.57366 -134.384796)
		(stroke
			(width 0.2)
			(type default)
		)
		(layer "In6.Cu")
	)
	(gr_arc
		(start 63.57366 -19.385026)
		(mid 64.0588 -19.870166)
		(end 64.54394 -19.385026)
		(stroke
			(width 0.2)
			(type default)
		)
		(layer "In6.Cu")
	)
	(gr_line
		(start 63.57366 -18.115026)
		(end 63.57366 -19.385026)
		(stroke
			(width 0.2)
			(type default)
		)
		(layer "In6.Cu")
	)
	(gr_line
		(start 64.54394 -249.385074)
		(end 64.54394 -248.115328)
		(stroke
			(width 0.2)
			(type default)
		)
		(layer "In6.Cu")
	)
	(gr_arc
		(start 64.54394 -248.115328)
		(mid 64.058927 -247.629934)
		(end 63.57366 -248.115074)
		(stroke
			(width 0.2)
			(type default)
		)
		(layer "In6.Cu")
	)
	(gr_line
		(start 64.54394 -134.38505)
		(end 64.54394 -133.11505)
		(stroke
			(width 0.2)
			(type default)
		)
		(layer "In6.Cu")
	)
	(gr_arc
		(start 64.54394 -133.11505)
		(mid 64.0588 -132.62991)
		(end 63.57366 -133.11505)
		(stroke
			(width 0.2)
			(type default)
		)
		(layer "In6.Cu")
	)
	(gr_line
		(start 64.54394 -19.385026)
		(end 64.54394 -18.11528)
		(stroke
			(width 0.2)
			(type default)
		)
		(layer "In6.Cu")
	)
	(gr_arc
		(start 64.54394 -18.11528)
		(mid 64.058927 -17.629886)
		(end 63.57366 -18.115026)
		(stroke
			(width 0.2)
			(type default)
		)
		(layer "In6.Cu")
	)
	(gr_arc
		(start 65.35039 -245.56212)
		(mid 65.835403 -246.047514)
		(end 66.32067 -245.562374)
		(stroke
			(width 0.2)
			(type default)
		)
		(layer "In6.Cu")
	)
	(gr_line
		(start 65.35039 -244.419374)
		(end 65.35039 -245.56212)
		(stroke
			(width 0.2)
			(type default)
		)
		(layer "In6.Cu")
	)
	(gr_arc
		(start 65.35039 -130.56235)
		(mid 65.83553 -131.04749)
		(end 66.32067 -130.56235)
		(stroke
			(width 0.2)
			(type default)
		)
		(layer "In6.Cu")
	)
	(gr_line
		(start 65.35039 -129.41935)
		(end 65.35039 -130.56235)
		(stroke
			(width 0.2)
			(type default)
		)
		(layer "In6.Cu")
	)
	(gr_arc
		(start 65.35039 -15.562326)
		(mid 65.83553 -16.047466)
		(end 66.32067 -15.562326)
		(stroke
			(width 0.2)
			(type default)
		)
		(layer "In6.Cu")
	)
	(gr_line
		(start 65.35039 -14.419326)
		(end 65.35039 -15.562326)
		(stroke
			(width 0.2)
			(type default)
		)
		(layer "In6.Cu")
	)
	(gr_line
		(start 66.32067 -245.562374)
		(end 66.32067 -244.419374)
		(stroke
			(width 0.2)
			(type default)
		)
		(layer "In6.Cu")
	)
	(gr_arc
		(start 66.32067 -244.419374)
		(mid 65.83553 -243.934234)
		(end 65.35039 -244.419374)
		(stroke
			(width 0.2)
			(type default)
		)
		(layer "In6.Cu")
	)
	(gr_line
		(start 66.32067 -130.56235)
		(end 66.32067 -129.419604)
		(stroke
			(width 0.2)
			(type default)
		)
		(layer "In6.Cu")
	)
	(gr_arc
		(start 66.32067 -129.419604)
		(mid 65.835657 -128.93421)
		(end 65.35039 -129.41935)
		(stroke
			(width 0.2)
			(type default)
		)
		(layer "In6.Cu")
	)
	(gr_line
		(start 66.32067 -15.562326)
		(end 66.32067 -14.41958)
		(stroke
			(width 0.2)
			(type default)
		)
		(layer "In6.Cu")
	)
	(gr_arc
		(start 66.32067 -14.41958)
		(mid 65.835657 -13.934186)
		(end 65.35039 -14.419326)
		(stroke
			(width 0.2)
			(type default)
		)
		(layer "In6.Cu")
	)
	(gr_line
		(start 71.300086 -385.99999)
		(end 25.750012 -385.99999)
		(stroke
			(width 1.524)
			(type default)
		)
		(layer "In6.Cu")
	)
	(gr_arc
		(start 71.300086 -385.99999)
		(mid 72.007198 -385.707102)
		(end 72.300084 -384.999992)
		(stroke
			(width 1.524)
			(type default)
		)
		(layer "In6.Cu")
	)
	(gr_line
		(start 72.300084 -381)
		(end 72.300084 -384.999992)
		(stroke
			(width 1.524)
			(type default)
		)
		(layer "In6.Cu")
	)
	(gr_arc
		(start 73.300082 -380.000002)
		(mid 72.592977 -380.292895)
		(end 72.300084 -381)
		(stroke
			(width 1.524)
			(type default)
		)
		(layer "In6.Cu")
	)
	(gr_arc
		(start 95.123762 -249.385074)
		(mid 95.608902 -249.870214)
		(end 96.094042 -249.385074)
		(stroke
			(width 0.2)
			(type default)
		)
		(layer "In6.Cu")
	)
	(gr_line
		(start 95.123762 -248.115074)
		(end 95.123762 -249.385074)
		(stroke
			(width 0.2)
			(type default)
		)
		(layer "In6.Cu")
	)
	(gr_arc
		(start 95.123762 -134.384796)
		(mid 95.608775 -134.87019)
		(end 96.094042 -134.38505)
		(stroke
			(width 0.2)
			(type default)
		)
		(layer "In6.Cu")
	)
	(gr_line
		(start 95.123762 -133.11505)
		(end 95.123762 -134.384796)
		(stroke
			(width 0.2)
			(type default)
		)
		(layer "In6.Cu")
	)
	(gr_arc
		(start 95.123762 -19.385026)
		(mid 95.608902 -19.870166)
		(end 96.094042 -19.385026)
		(stroke
			(width 0.2)
			(type default)
		)
		(layer "In6.Cu")
	)
	(gr_line
		(start 95.123762 -18.115026)
		(end 95.123762 -19.385026)
		(stroke
			(width 0.2)
			(type default)
		)
		(layer "In6.Cu")
	)
	(gr_line
		(start 96.094042 -249.385074)
		(end 96.094042 -248.115328)
		(stroke
			(width 0.2)
			(type default)
		)
		(layer "In6.Cu")
	)
	(gr_arc
		(start 96.094042 -248.115328)
		(mid 95.609029 -247.629934)
		(end 95.123762 -248.115074)
		(stroke
			(width 0.2)
			(type default)
		)
		(layer "In6.Cu")
	)
	(gr_line
		(start 96.094042 -134.38505)
		(end 96.094042 -133.11505)
		(stroke
			(width 0.2)
			(type default)
		)
		(layer "In6.Cu")
	)
	(gr_arc
		(start 96.094042 -133.11505)
		(mid 95.608902 -132.62991)
		(end 95.123762 -133.11505)
		(stroke
			(width 0.2)
			(type default)
		)
		(layer "In6.Cu")
	)
	(gr_line
		(start 96.094042 -19.385026)
		(end 96.094042 -18.11528)
		(stroke
			(width 0.2)
			(type default)
		)
		(layer "In6.Cu")
	)
	(gr_arc
		(start 96.094042 -18.11528)
		(mid 95.609029 -17.629886)
		(end 95.123762 -18.115026)
		(stroke
			(width 0.2)
			(type default)
		)
		(layer "In6.Cu")
	)
	(gr_arc
		(start 96.900492 -245.56212)
		(mid 97.385505 -246.047514)
		(end 97.870772 -245.562374)
		(stroke
			(width 0.2)
			(type default)
		)
		(layer "In6.Cu")
	)
	(gr_line
		(start 96.900492 -244.419374)
		(end 96.900492 -245.56212)
		(stroke
			(width 0.2)
			(type default)
		)
		(layer "In6.Cu")
	)
	(gr_arc
		(start 96.900492 -130.56235)
		(mid 97.385632 -131.04749)
		(end 97.870772 -130.56235)
		(stroke
			(width 0.2)
			(type default)
		)
		(layer "In6.Cu")
	)
	(gr_line
		(start 96.900492 -129.41935)
		(end 96.900492 -130.56235)
		(stroke
			(width 0.2)
			(type default)
		)
		(layer "In6.Cu")
	)
	(gr_arc
		(start 96.900492 -15.562326)
		(mid 97.385632 -16.047466)
		(end 97.870772 -15.562326)
		(stroke
			(width 0.2)
			(type default)
		)
		(layer "In6.Cu")
	)
	(gr_line
		(start 96.900492 -14.419326)
		(end 96.900492 -15.562326)
		(stroke
			(width 0.2)
			(type default)
		)
		(layer "In6.Cu")
	)
	(gr_line
		(start 97.870772 -245.562374)
		(end 97.870772 -244.419374)
		(stroke
			(width 0.2)
			(type default)
		)
		(layer "In6.Cu")
	)
	(gr_arc
		(start 97.870772 -244.419374)
		(mid 97.385632 -243.934234)
		(end 96.900492 -244.419374)
		(stroke
			(width 0.2)
			(type default)
		)
		(layer "In6.Cu")
	)
	(gr_line
		(start 97.870772 -130.56235)
		(end 97.870772 -129.419604)
		(stroke
			(width 0.2)
			(type default)
		)
		(layer "In6.Cu")
	)
	(gr_arc
		(start 97.870772 -129.419604)
		(mid 97.385759 -128.93421)
		(end 96.900492 -129.41935)
		(stroke
			(width 0.2)
			(type default)
		)
		(layer "In6.Cu")
	)
	(gr_line
		(start 97.870772 -15.562326)
		(end 97.870772 -14.41958)
		(stroke
			(width 0.2)
			(type default)
		)
		(layer "In6.Cu")
	)
	(gr_arc
		(start 97.870772 -14.41958)
		(mid 97.385759 -13.934186)
		(end 96.900492 -14.419326)
		(stroke
			(width 0.2)
			(type default)
		)
		(layer "In6.Cu")
	)
	(gr_line
		(start 102.743 -346.202)
		(end 103.632 -347.091)
		(stroke
			(width 0.381)
			(type default)
		)
		(layer "In6.Cu")
	)
	(gr_line
		(start 102.743 -332.613)
		(end 102.743 -346.202)
		(stroke
			(width 0.381)
			(type default)
		)
		(layer "In6.Cu")
	)
	(gr_line
		(start 103.632 -364.269782)
		(end 104.043988 -364.68177)
		(stroke
			(width 0.381)
			(type default)
		)
		(layer "In6.Cu")
	)
	(gr_line
		(start 103.632 -347.091)
		(end 103.632 -364.269782)
		(stroke
			(width 0.381)
			(type default)
		)
		(layer "In6.Cu")
	)
	(gr_line
		(start 104.043988 -364.68177)
		(end 109.290612 -364.68177)
		(stroke
			(width 0.381)
			(type default)
		)
		(layer "In6.Cu")
	)
	(gr_line
		(start 104.146604 -331.209396)
		(end 102.743 -332.613)
		(stroke
			(width 0.381)
			(type default)
		)
		(layer "In6.Cu")
	)
	(gr_line
		(start 109.290612 -364.68177)
		(end 112.207802 -361.76458)
		(stroke
			(width 0.381)
			(type default)
		)
		(layer "In6.Cu")
	)
	(gr_line
		(start 112.207802 -361.76458)
		(end 123.074938 -361.76458)
		(stroke
			(width 0.381)
			(type default)
		)
		(layer "In6.Cu")
	)
	(gr_line
		(start 123.074938 -361.76458)
		(end 126.445518 -358.394)
		(stroke
			(width 0.381)
			(type default)
		)
		(layer "In6.Cu")
	)
	(gr_line
		(start 125.299978 -380.000002)
		(end 73.300082 -380.000002)
		(stroke
			(width 1.524)
			(type default)
		)
		(layer "In6.Cu")
	)
	(gr_line
		(start 126.299976 -384.999992)
		(end 126.299976 -381)
		(stroke
			(width 1.524)
			(type default)
		)
		(layer "In6.Cu")
	)
	(gr_arc
		(start 126.299976 -384.999992)
		(mid 126.592864 -385.707112)
		(end 127.299974 -385.99999)
		(stroke
			(width 1.524)
			(type default)
		)
		(layer "In6.Cu")
	)
	(gr_arc
		(start 126.299976 -381)
		(mid 126.007083 -380.292895)
		(end 125.299978 -380.000002)
		(stroke
			(width 1.524)
			(type default)
		)
		(layer "In6.Cu")
	)
	(gr_line
		(start 126.445518 -358.394)
		(end 160.782 -358.394)
		(stroke
			(width 0.381)
			(type default)
		)
		(layer "In6.Cu")
	)
	(gr_arc
		(start 126.67361 -249.385074)
		(mid 127.15875 -249.870214)
		(end 127.64389 -249.385074)
		(stroke
			(width 0.2)
			(type default)
		)
		(layer "In6.Cu")
	)
	(gr_line
		(start 126.67361 -248.115074)
		(end 126.67361 -249.385074)
		(stroke
			(width 0.2)
			(type default)
		)
		(layer "In6.Cu")
	)
	(gr_arc
		(start 126.67361 -134.384796)
		(mid 127.158623 -134.87019)
		(end 127.64389 -134.38505)
		(stroke
			(width 0.2)
			(type default)
		)
		(layer "In6.Cu")
	)
	(gr_line
		(start 126.67361 -133.11505)
		(end 126.67361 -134.384796)
		(stroke
			(width 0.2)
			(type default)
		)
		(layer "In6.Cu")
	)
	(gr_arc
		(start 126.67361 -19.385026)
		(mid 127.15875 -19.870166)
		(end 127.64389 -19.385026)
		(stroke
			(width 0.2)
			(type default)
		)
		(layer "In6.Cu")
	)
	(gr_line
		(start 126.67361 -18.115026)
		(end 126.67361 -19.385026)
		(stroke
			(width 0.2)
			(type default)
		)
		(layer "In6.Cu")
	)
	(gr_line
		(start 127.64389 -249.385074)
		(end 127.64389 -248.115328)
		(stroke
			(width 0.2)
			(type default)
		)
		(layer "In6.Cu")
	)
	(gr_arc
		(start 127.64389 -248.115328)
		(mid 127.158877 -247.629934)
		(end 126.67361 -248.115074)
		(stroke
			(width 0.2)
			(type default)
		)
		(layer "In6.Cu")
	)
	(gr_line
		(start 127.64389 -134.38505)
		(end 127.64389 -133.11505)
		(stroke
			(width 0.2)
			(type default)
		)
		(layer "In6.Cu")
	)
	(gr_arc
		(start 127.64389 -133.11505)
		(mid 127.15875 -132.62991)
		(end 126.67361 -133.11505)
		(stroke
			(width 0.2)
			(type default)
		)
		(layer "In6.Cu")
	)
	(gr_line
		(start 127.64389 -19.385026)
		(end 127.64389 -18.11528)
		(stroke
			(width 0.2)
			(type default)
		)
		(layer "In6.Cu")
	)
	(gr_arc
		(start 127.64389 -18.11528)
		(mid 127.158877 -17.629886)
		(end 126.67361 -18.115026)
		(stroke
			(width 0.2)
			(type default)
		)
		(layer "In6.Cu")
	)
	(gr_arc
		(start 128.45034 -245.56212)
		(mid 128.935353 -246.047514)
		(end 129.42062 -245.562374)
		(stroke
			(width 0.2)
			(type default)
		)
		(layer "In6.Cu")
	)
	(gr_line
		(start 128.45034 -244.419374)
		(end 128.45034 -245.56212)
		(stroke
			(width 0.2)
			(type default)
		)
		(layer "In6.Cu")
	)
	(gr_arc
		(start 128.45034 -130.56235)
		(mid 128.93548 -131.04749)
		(end 129.42062 -130.56235)
		(stroke
			(width 0.2)
			(type default)
		)
		(layer "In6.Cu")
	)
	(gr_line
		(start 128.45034 -129.41935)
		(end 128.45034 -130.56235)
		(stroke
			(width 0.2)
			(type default)
		)
		(layer "In6.Cu")
	)
	(gr_arc
		(start 128.45034 -15.562326)
		(mid 128.93548 -16.047466)
		(end 129.42062 -15.562326)
		(stroke
			(width 0.2)
			(type default)
		)
		(layer "In6.Cu")
	)
	(gr_line
		(start 128.45034 -14.419326)
		(end 128.45034 -15.562326)
		(stroke
			(width 0.2)
			(type default)
		)
		(layer "In6.Cu")
	)
	(gr_line
		(start 129.42062 -245.562374)
		(end 129.42062 -244.419374)
		(stroke
			(width 0.2)
			(type default)
		)
		(layer "In6.Cu")
	)
	(gr_arc
		(start 129.42062 -244.419374)
		(mid 128.93548 -243.934234)
		(end 128.45034 -244.419374)
		(stroke
			(width 0.2)
			(type default)
		)
		(layer "In6.Cu")
	)
	(gr_line
		(start 129.42062 -130.56235)
		(end 129.42062 -129.419604)
		(stroke
			(width 0.2)
			(type default)
		)
		(layer "In6.Cu")
	)
	(gr_arc
		(start 129.42062 -129.419604)
		(mid 128.935607 -128.93421)
		(end 128.45034 -129.41935)
		(stroke
			(width 0.2)
			(type default)
		)
		(layer "In6.Cu")
	)
	(gr_line
		(start 129.42062 -15.562326)
		(end 129.42062 -14.41958)
		(stroke
			(width 0.2)
			(type default)
		)
		(layer "In6.Cu")
	)
	(gr_arc
		(start 129.42062 -14.41958)
		(mid 128.935607 -13.934186)
		(end 128.45034 -14.419326)
		(stroke
			(width 0.2)
			(type default)
		)
		(layer "In6.Cu")
	)
	(gr_line
		(start 151.263604 -331.209396)
		(end 104.146604 -331.209396)
		(stroke
			(width 0.381)
			(type default)
		)
		(layer "In6.Cu")
	)
	(gr_line
		(start 151.638 -330.835)
		(end 151.263604 -331.209396)
		(stroke
			(width 0.381)
			(type default)
		)
		(layer "In6.Cu")
	)
	(gr_line
		(start 151.638 -327.66)
		(end 151.638 -330.835)
		(stroke
			(width 0.381)
			(type default)
		)
		(layer "In6.Cu")
	)
	(gr_line
		(start 152.273 -327.025)
		(end 151.638 -327.66)
		(stroke
			(width 0.381)
			(type default)
		)
		(layer "In6.Cu")
	)
	(gr_line
		(start 157.353 -327.025)
		(end 152.273 -327.025)
		(stroke
			(width 0.381)
			(type default)
		)
		(layer "In6.Cu")
	)
	(gr_line
		(start 157.607 -328.549)
		(end 157.607 -327.279)
		(stroke
			(width 0.381)
			(type default)
		)
		(layer "In6.Cu")
	)
	(gr_line
		(start 157.607 -327.279)
		(end 157.353 -327.025)
		(stroke
			(width 0.381)
			(type default)
		)
		(layer "In6.Cu")
	)
	(gr_line
		(start 157.988 -328.93)
		(end 157.607 -328.549)
		(stroke
			(width 0.381)
			(type default)
		)
		(layer "In6.Cu")
	)
	(gr_arc
		(start 158.223712 -249.38482)
		(mid 158.708725 -249.870214)
		(end 159.193992 -249.385074)
		(stroke
			(width 0.2)
			(type default)
		)
		(layer "In6.Cu")
	)
	(gr_line
		(start 158.223712 -248.115074)
		(end 158.223712 -249.38482)
		(stroke
			(width 0.2)
			(type default)
		)
		(layer "In6.Cu")
	)
	(gr_arc
		(start 158.223712 -134.384796)
		(mid 158.708725 -134.87019)
		(end 159.193992 -134.38505)
		(stroke
			(width 0.2)
			(type default)
		)
		(layer "In6.Cu")
	)
	(gr_line
		(start 158.223712 -133.11505)
		(end 158.223712 -134.384796)
		(stroke
			(width 0.2)
			(type default)
		)
		(layer "In6.Cu")
	)
	(gr_arc
		(start 158.223712 -19.385026)
		(mid 158.708852 -19.870166)
		(end 159.193992 -19.385026)
		(stroke
			(width 0.2)
			(type default)
		)
		(layer "In6.Cu")
	)
	(gr_line
		(start 158.223712 -18.115026)
		(end 158.223712 -19.385026)
		(stroke
			(width 0.2)
			(type default)
		)
		(layer "In6.Cu")
	)
	(gr_line
		(start 159.193992 -249.385074)
		(end 159.193992 -248.115074)
		(stroke
			(width 0.2)
			(type default)
		)
		(layer "In6.Cu")
	)
	(gr_arc
		(start 159.193992 -248.115074)
		(mid 158.708852 -247.629934)
		(end 158.223712 -248.115074)
		(stroke
			(width 0.2)
			(type default)
		)
		(layer "In6.Cu")
	)
	(gr_line
		(start 159.193992 -134.38505)
		(end 159.193992 -133.11505)
		(stroke
			(width 0.2)
			(type default)
		)
		(layer "In6.Cu")
	)
	(gr_arc
		(start 159.193992 -133.11505)
		(mid 158.708852 -132.62991)
		(end 158.223712 -133.11505)
		(stroke
			(width 0.2)
			(type default)
		)
		(layer "In6.Cu")
	)
	(gr_line
		(start 159.193992 -19.385026)
		(end 159.193992 -18.11528)
		(stroke
			(width 0.2)
			(type default)
		)
		(layer "In6.Cu")
	)
	(gr_arc
		(start 159.193992 -18.11528)
		(mid 158.708979 -17.629886)
		(end 158.223712 -18.115026)
		(stroke
			(width 0.2)
			(type default)
		)
		(layer "In6.Cu")
	)
	(gr_arc
		(start 160.000442 -245.56212)
		(mid 160.485455 -246.047514)
		(end 160.970722 -245.562374)
		(stroke
			(width 0.2)
			(type default)
		)
		(layer "In6.Cu")
	)
	(gr_line
		(start 160.000442 -244.419374)
		(end 160.000442 -245.56212)
		(stroke
			(width 0.2)
			(type default)
		)
		(layer "In6.Cu")
	)
	(gr_arc
		(start 160.000442 -130.56235)
		(mid 160.485582 -131.04749)
		(end 160.970722 -130.56235)
		(stroke
			(width 0.2)
			(type default)
		)
		(layer "In6.Cu")
	)
	(gr_line
		(start 160.000442 -129.41935)
		(end 160.000442 -130.56235)
		(stroke
			(width 0.2)
			(type default)
		)
		(layer "In6.Cu")
	)
	(gr_arc
		(start 160.000442 -15.562326)
		(mid 160.485582 -16.047466)
		(end 160.970722 -15.562326)
		(stroke
			(width 0.2)
			(type default)
		)
		(layer "In6.Cu")
	)
	(gr_line
		(start 160.000442 -14.419326)
		(end 160.000442 -15.562326)
		(stroke
			(width 0.2)
			(type default)
		)
		(layer "In6.Cu")
	)
	(gr_line
		(start 160.782 -358.394)
		(end 160.782 -328.93)
		(stroke
			(width 0.381)
			(type default)
		)
		(layer "In6.Cu")
	)
	(gr_line
		(start 160.782 -328.93)
		(end 157.988 -328.93)
		(stroke
			(width 0.381)
			(type default)
		)
		(layer "In6.Cu")
	)
	(gr_line
		(start 160.970722 -245.562374)
		(end 160.970722 -244.419374)
		(stroke
			(width 0.2)
			(type default)
		)
		(layer "In6.Cu")
	)
	(gr_arc
		(start 160.970722 -244.419374)
		(mid 160.485582 -243.934234)
		(end 160.000442 -244.419374)
		(stroke
			(width 0.2)
			(type default)
		)
		(layer "In6.Cu")
	)
	(gr_line
		(start 160.970722 -130.56235)
		(end 160.970722 -129.419604)
		(stroke
			(width 0.2)
			(type default)
		)
		(layer "In6.Cu")
	)
	(gr_arc
		(start 160.970722 -129.419604)
		(mid 160.485709 -128.93421)
		(end 160.000442 -129.41935)
		(stroke
			(width 0.2)
			(type default)
		)
		(layer "In6.Cu")
	)
	(gr_line
		(start 160.970722 -15.562326)
		(end 160.970722 -14.41958)
		(stroke
			(width 0.2)
			(type default)
		)
		(layer "In6.Cu")
	)
	(gr_arc
		(start 160.970722 -14.41958)
		(mid 160.485709 -13.934186)
		(end 160.000442 -14.419326)
		(stroke
			(width 0.2)
			(type default)
		)
		(layer "In6.Cu")
	)
	(gr_line
		(start 166.2049 -358.394)
		(end 204.1906 -358.394)
		(stroke
			(width 0.381)
			(type default)
		)
		(layer "In6.Cu")
	)
	(gr_line
		(start 166.2049 -328.93)
		(end 166.2049 -358.394)
		(stroke
			(width 0.381)
			(type default)
		)
		(layer "In6.Cu")
	)
	(gr_line
		(start 166.5859 -328.93)
		(end 166.2049 -328.93)
		(stroke
			(width 0.381)
			(type default)
		)
		(layer "In6.Cu")
	)
	(gr_line
		(start 172.850048 -385.99999)
		(end 127.299974 -385.99999)
		(stroke
			(width 1.524)
			(type default)
		)
		(layer "In6.Cu")
	)
	(gr_arc
		(start 172.850048 -385.99999)
		(mid 173.55712 -385.70708)
		(end 173.850046 -384.999992)
		(stroke
			(width 1.524)
			(type default)
		)
		(layer "In6.Cu")
	)
	(gr_line
		(start 173.850046 -383.29997)
		(end 173.850046 -384.999992)
		(stroke
			(width 1.524)
			(type default)
		)
		(layer "In6.Cu")
	)
	(gr_arc
		(start 174.850044 -382.299972)
		(mid 174.142939 -382.592865)
		(end 173.850046 -383.29997)
		(stroke
			(width 1.524)
			(type default)
		)
		(layer "In6.Cu")
	)
	(gr_line
		(start 181.349904 -382.299972)
		(end 174.850044 -382.299972)
		(stroke
			(width 1.524)
			(type default)
		)
		(layer "In6.Cu")
	)
	(gr_line
		(start 182.349902 -384.999992)
		(end 182.349902 -383.29997)
		(stroke
			(width 1.524)
			(type default)
		)
		(layer "In6.Cu")
	)
	(gr_arc
		(start 182.349902 -384.999992)
		(mid 182.642792 -385.707103)
		(end 183.3499 -385.99999)
		(stroke
			(width 1.524)
			(type default)
		)
		(layer "In6.Cu")
	)
	(gr_arc
		(start 182.349902 -383.29997)
		(mid 182.057009 -382.592865)
		(end 181.349904 -382.299972)
		(stroke
			(width 1.524)
			(type default)
		)
		(layer "In6.Cu")
	)
	(gr_arc
		(start 189.773814 -249.385074)
		(mid 190.258954 -249.870214)
		(end 190.744094 -249.385074)
		(stroke
			(width 0.2)
			(type default)
		)
		(layer "In6.Cu")
	)
	(gr_line
		(start 189.773814 -248.115074)
		(end 189.773814 -249.385074)
		(stroke
			(width 0.2)
			(type default)
		)
		(layer "In6.Cu")
	)
	(gr_arc
		(start 189.773814 -134.38505)
		(mid 190.258954 -134.87019)
		(end 190.744094 -134.38505)
		(stroke
			(width 0.2)
			(type default)
		)
		(layer "In6.Cu")
	)
	(gr_line
		(start 189.773814 -133.11505)
		(end 189.773814 -134.38505)
		(stroke
			(width 0.2)
			(type default)
		)
		(layer "In6.Cu")
	)
	(gr_arc
		(start 189.773814 -19.385026)
		(mid 190.258954 -19.870166)
		(end 190.744094 -19.385026)
		(stroke
			(width 0.2)
			(type default)
		)
		(layer "In6.Cu")
	)
	(gr_line
		(start 189.773814 -18.115026)
		(end 189.773814 -19.385026)
		(stroke
			(width 0.2)
			(type default)
		)
		(layer "In6.Cu")
	)
	(gr_line
		(start 190.744094 -249.385074)
		(end 190.744094 -248.115328)
		(stroke
			(width 0.2)
			(type default)
		)
		(layer "In6.Cu")
	)
	(gr_arc
		(start 190.744094 -248.115328)
		(mid 190.259081 -247.629934)
		(end 189.773814 -248.115074)
		(stroke
			(width 0.2)
			(type default)
		)
		(layer "In6.Cu")
	)
	(gr_line
		(start 190.744094 -134.38505)
		(end 190.744094 -133.115304)
		(stroke
			(width 0.2)
			(type default)
		)
		(layer "In6.Cu")
	)
	(gr_arc
		(start 190.744094 -133.115304)
		(mid 190.259081 -132.62991)
		(end 189.773814 -133.11505)
		(stroke
			(width 0.2)
			(type default)
		)
		(layer "In6.Cu")
	)
	(gr_line
		(start 190.744094 -19.385026)
		(end 190.744094 -18.11528)
		(stroke
			(width 0.2)
			(type default)
		)
		(layer "In6.Cu")
	)
	(gr_arc
		(start 190.744094 -18.11528)
		(mid 190.259081 -17.629886)
		(end 189.773814 -18.115026)
		(stroke
			(width 0.2)
			(type default)
		)
		(layer "In6.Cu")
	)
	(gr_arc
		(start 191.550544 -245.56212)
		(mid 192.035557 -246.047514)
		(end 192.520824 -245.562374)
		(stroke
			(width 0.2)
			(type default)
		)
		(layer "In6.Cu")
	)
	(gr_line
		(start 191.550544 -244.419374)
		(end 191.550544 -245.56212)
		(stroke
			(width 0.2)
			(type default)
		)
		(layer "In6.Cu")
	)
	(gr_arc
		(start 191.550544 -130.56235)
		(mid 192.035684 -131.04749)
		(end 192.520824 -130.56235)
		(stroke
			(width 0.2)
			(type default)
		)
		(layer "In6.Cu")
	)
	(gr_line
		(start 191.550544 -129.41935)
		(end 191.550544 -130.56235)
		(stroke
			(width 0.2)
			(type default)
		)
		(layer "In6.Cu")
	)
	(gr_arc
		(start 191.550544 -15.562326)
		(mid 192.035684 -16.047466)
		(end 192.520824 -15.562326)
		(stroke
			(width 0.2)
			(type default)
		)
		(layer "In6.Cu")
	)
	(gr_line
		(start 191.550544 -14.419326)
		(end 191.550544 -15.562326)
		(stroke
			(width 0.2)
			(type default)
		)
		(layer "In6.Cu")
	)
	(gr_line
		(start 192.520824 -245.562374)
		(end 192.520824 -244.419374)
		(stroke
			(width 0.2)
			(type default)
		)
		(layer "In6.Cu")
	)
	(gr_arc
		(start 192.520824 -244.419374)
		(mid 192.035684 -243.934234)
		(end 191.550544 -244.419374)
		(stroke
			(width 0.2)
			(type default)
		)
		(layer "In6.Cu")
	)
	(gr_line
		(start 192.520824 -130.56235)
		(end 192.520824 -129.419604)
		(stroke
			(width 0.2)
			(type default)
		)
		(layer "In6.Cu")
	)
	(gr_arc
		(start 192.520824 -129.419604)
		(mid 192.035811 -128.93421)
		(end 191.550544 -129.41935)
		(stroke
			(width 0.2)
			(type default)
		)
		(layer "In6.Cu")
	)
	(gr_line
		(start 192.520824 -15.562326)
		(end 192.520824 -14.41958)
		(stroke
			(width 0.2)
			(type default)
		)
		(layer "In6.Cu")
	)
	(gr_arc
		(start 192.520824 -14.41958)
		(mid 192.035811 -13.934186)
		(end 191.550544 -14.419326)
		(stroke
			(width 0.2)
			(type default)
		)
		(layer "In6.Cu")
	)
	(gr_line
		(start 197.000114 -385.99999)
		(end 183.3499 -385.99999)
		(stroke
			(width 1.524)
			(type default)
		)
		(layer "In6.Cu")
	)
	(gr_arc
		(start 197.000114 -385.99999)
		(mid 197.707207 -385.707092)
		(end 198.000112 -384.999992)
		(stroke
			(width 1.524)
			(type default)
		)
		(layer "In6.Cu")
	)
	(gr_line
		(start 198.000112 -381)
		(end 198.000112 -384.999992)
		(stroke
			(width 1.524)
			(type default)
		)
		(layer "In6.Cu")
	)
	(gr_arc
		(start 199.00011 -380.000002)
		(mid 198.293005 -380.292895)
		(end 198.000112 -381)
		(stroke
			(width 1.524)
			(type default)
		)
		(layer "In6.Cu")
	)
	(gr_arc
		(start 199.00011 -47.200058)
		(mid 199.293003 -47.907163)
		(end 200.000108 -48.200056)
		(stroke
			(width 1.524)
			(type default)
		)
		(layer "In6.Cu")
	)
	(gr_arc
		(start 199.00011 -0.999998)
		(mid 198.707217 -0.29289)
		(end 198.000112 0)
		(stroke
			(width 1.524)
			(type default)
		)
		(layer "In6.Cu")
	)
	(gr_line
		(start 199.00011 -0.999998)
		(end 199.00011 -47.200058)
		(stroke
			(width 1.524)
			(type default)
		)
		(layer "In6.Cu")
	)
	(gr_line
		(start 200.000108 -48.200056)
		(end 206.000096 -48.200056)
		(stroke
			(width 1.524)
			(type default)
		)
		(layer "In6.Cu")
	)
	(gr_line
		(start 204.1906 -358.394)
		(end 204.6351 -357.9495)
		(stroke
			(width 0.381)
			(type default)
		)
		(layer "In6.Cu")
	)
	(gr_line
		(start 204.2287 -328.93)
		(end 166.5859 -328.93)
		(stroke
			(width 0.381)
			(type default)
		)
		(layer "In6.Cu")
	)
	(gr_line
		(start 204.6351 -357.9495)
		(end 204.6351 -329.3364)
		(stroke
			(width 0.381)
			(type default)
		)
		(layer "In6.Cu")
	)
	(gr_line
		(start 204.6351 -329.3364)
		(end 204.2287 -328.93)
		(stroke
			(width 0.381)
			(type default)
		)
		(layer "In6.Cu")
	)
	(gr_arc
		(start 207.000094 -61.999876)
		(mid 207.292987 -62.706981)
		(end 208.000092 -62.999874)
		(stroke
			(width 1.524)
			(type default)
		)
		(layer "In6.Cu")
	)
	(gr_arc
		(start 207.000094 -49.200054)
		(mid 206.707185 -48.49298)
		(end 206.000096 -48.200056)
		(stroke
			(width 1.524)
			(type default)
		)
		(layer "In6.Cu")
	)
	(gr_line
		(start 207.000094 -49.200054)
		(end 207.000094 -61.999876)
		(stroke
			(width 1.524)
			(type default)
		)
		(layer "In6.Cu")
	)
	(gr_line
		(start 208.000092 -62.999874)
		(end 267.999972 -62.999874)
		(stroke
			(width 1.524)
			(type default)
		)
		(layer "In6.Cu")
	)
	(gr_arc
		(start 209.451448 -78.999842)
		(mid 210.000088 -79.548482)
		(end 210.548728 -78.999842)
		(stroke
			(width 0.2)
			(type default)
		)
		(layer "In6.Cu")
	)
	(gr_line
		(start 209.451448 -77.600048)
		(end 209.451448 -78.999842)
		(stroke
			(width 0.2)
			(type default)
		)
		(layer "In6.Cu")
	)
	(gr_arc
		(start 209.451448 -75.399646)
		(mid 209.999961 -75.94854)
		(end 210.548728 -75.3999)
		(stroke
			(width 0.2)
			(type default)
		)
		(layer "In6.Cu")
	)
	(gr_line
		(start 209.451448 -73.999852)
		(end 209.451448 -75.399646)
		(stroke
			(width 0.2)
			(type default)
		)
		(layer "In6.Cu")
	)
	(gr_arc
		(start 209.451448 -71.799704)
		(mid 209.999961 -72.348598)
		(end 210.548728 -71.799958)
		(stroke
			(width 0.2)
			(type default)
		)
		(layer "In6.Cu")
	)
	(gr_line
		(start 209.451448 -70.39991)
		(end 209.451448 -71.799704)
		(stroke
			(width 0.2)
			(type default)
		)
		(layer "In6.Cu")
	)
	(gr_line
		(start 210.548728 -78.999842)
		(end 210.548728 -77.600302)
		(stroke
			(width 0.2)
			(type default)
		)
		(layer "In6.Cu")
	)
	(gr_arc
		(start 210.548728 -77.600302)
		(mid 210.000215 -77.051408)
		(end 209.451448 -77.600048)
		(stroke
			(width 0.2)
			(type default)
		)
		(layer "In6.Cu")
	)
	(gr_line
		(start 210.548728 -75.3999)
		(end 210.548728 -73.999852)
		(stroke
			(width 0.2)
			(type default)
		)
		(layer "In6.Cu")
	)
	(gr_arc
		(start 210.548728 -73.999852)
		(mid 210.000088 -73.451212)
		(end 209.451448 -73.999852)
		(stroke
			(width 0.2)
			(type default)
		)
		(layer "In6.Cu")
	)
	(gr_line
		(start 210.548728 -71.799958)
		(end 210.548728 -70.39991)
		(stroke
			(width 0.2)
			(type default)
		)
		(layer "In6.Cu")
	)
	(gr_arc
		(start 210.548728 -70.39991)
		(mid 210.000088 -69.85127)
		(end 209.451448 -70.39991)
		(stroke
			(width 0.2)
			(type default)
		)
		(layer "In6.Cu")
	)
	(gr_arc
		(start 211.251546 -77.799692)
		(mid 211.800059 -78.348586)
		(end 212.348826 -77.799946)
		(stroke
			(width 0.2)
			(type default)
		)
		(layer "In6.Cu")
	)
	(gr_line
		(start 211.251546 -76.399898)
		(end 211.251546 -77.799692)
		(stroke
			(width 0.2)
			(type default)
		)
		(layer "In6.Cu")
	)
	(gr_arc
		(start 211.251546 -66.999612)
		(mid 211.800059 -67.548506)
		(end 212.348826 -66.999866)
		(stroke
			(width 0.2)
			(type default)
		)
		(layer "In6.Cu")
	)
	(gr_line
		(start 211.251546 -65.600072)
		(end 211.251546 -66.999612)
		(stroke
			(width 0.2)
			(type default)
		)
		(layer "In6.Cu")
	)
	(gr_line
		(start 212.348826 -77.799946)
		(end 212.348826 -76.399898)
		(stroke
			(width 0.2)
			(type default)
		)
		(layer "In6.Cu")
	)
	(gr_arc
		(start 212.348826 -76.399898)
		(mid 211.800186 -75.851258)
		(end 211.251546 -76.399898)
		(stroke
			(width 0.2)
			(type default)
		)
		(layer "In6.Cu")
	)
	(gr_line
		(start 212.348826 -66.999866)
		(end 212.348826 -65.600072)
		(stroke
			(width 0.2)
			(type default)
		)
		(layer "In6.Cu")
	)
	(gr_arc
		(start 212.348826 -65.600072)
		(mid 211.800186 -65.051432)
		(end 211.251546 -65.600072)
		(stroke
			(width 0.2)
			(type default)
		)
		(layer "In6.Cu")
	)
	(gr_arc
		(start 213.05139 -78.999842)
		(mid 213.60003 -79.548482)
		(end 214.14867 -78.999842)
		(stroke
			(width 0.2)
			(type default)
		)
		(layer "In6.Cu")
	)
	(gr_line
		(start 213.05139 -77.600048)
		(end 213.05139 -78.999842)
		(stroke
			(width 0.2)
			(type default)
		)
		(layer "In6.Cu")
	)
	(gr_arc
		(start 213.05139 -71.799704)
		(mid 213.599903 -72.348598)
		(end 214.14867 -71.799958)
		(stroke
			(width 0.2)
			(type default)
		)
		(layer "In6.Cu")
	)
	(gr_line
		(start 213.05139 -70.39991)
		(end 213.05139 -71.799704)
		(stroke
			(width 0.2)
			(type default)
		)
		(layer "In6.Cu")
	)
	(gr_line
		(start 214.14867 -78.999842)
		(end 214.14867 -77.600302)
		(stroke
			(width 0.2)
			(type default)
		)
		(layer "In6.Cu")
	)
	(gr_arc
		(start 214.14867 -77.600302)
		(mid 213.600157 -77.051408)
		(end 213.05139 -77.600048)
		(stroke
			(width 0.2)
			(type default)
		)
		(layer "In6.Cu")
	)
	(gr_line
		(start 214.14867 -71.799958)
		(end 214.14867 -70.39991)
		(stroke
			(width 0.2)
			(type default)
		)
		(layer "In6.Cu")
	)
	(gr_arc
		(start 214.14867 -70.39991)
		(mid 213.60003 -69.85127)
		(end 213.05139 -70.39991)
		(stroke
			(width 0.2)
			(type default)
		)
		(layer "In6.Cu")
	)
	(gr_arc
		(start 214.851488 -77.799692)
		(mid 215.400001 -78.348586)
		(end 215.948768 -77.799946)
		(stroke
			(width 0.2)
			(type default)
		)
		(layer "In6.Cu")
	)
	(gr_line
		(start 214.851488 -76.399898)
		(end 214.851488 -77.799692)
		(stroke
			(width 0.2)
			(type default)
		)
		(layer "In6.Cu")
	)
	(gr_arc
		(start 214.851488 -66.999612)
		(mid 215.400001 -67.548506)
		(end 215.948768 -66.999866)
		(stroke
			(width 0.2)
			(type default)
		)
		(layer "In6.Cu")
	)
	(gr_line
		(start 214.851488 -65.600072)
		(end 214.851488 -66.999612)
		(stroke
			(width 0.2)
			(type default)
		)
		(layer "In6.Cu")
	)
	(gr_line
		(start 215.948768 -77.799946)
		(end 215.948768 -76.399898)
		(stroke
			(width 0.2)
			(type default)
		)
		(layer "In6.Cu")
	)
	(gr_arc
		(start 215.948768 -76.399898)
		(mid 215.400128 -75.851258)
		(end 214.851488 -76.399898)
		(stroke
			(width 0.2)
			(type default)
		)
		(layer "In6.Cu")
	)
	(gr_line
		(start 215.948768 -66.999866)
		(end 215.948768 -65.600072)
		(stroke
			(width 0.2)
			(type default)
		)
		(layer "In6.Cu")
	)
	(gr_arc
		(start 215.948768 -65.600072)
		(mid 215.400128 -65.051432)
		(end 214.851488 -65.600072)
		(stroke
			(width 0.2)
			(type default)
		)
		(layer "In6.Cu")
	)
	(gr_arc
		(start 216.651332 -78.999842)
		(mid 217.199972 -79.548482)
		(end 217.748612 -78.999842)
		(stroke
			(width 0.2)
			(type default)
		)
		(layer "In6.Cu")
	)
	(gr_line
		(start 216.651332 -77.600048)
		(end 216.651332 -78.999842)
		(stroke
			(width 0.2)
			(type default)
		)
		(layer "In6.Cu")
	)
	(gr_arc
		(start 216.651332 -71.799704)
		(mid 217.199845 -72.348598)
		(end 217.748612 -71.799958)
		(stroke
			(width 0.2)
			(type default)
		)
		(layer "In6.Cu")
	)
	(gr_line
		(start 216.651332 -70.39991)
		(end 216.651332 -71.799704)
		(stroke
			(width 0.2)
			(type default)
		)
		(layer "In6.Cu")
	)
	(gr_line
		(start 217.748612 -78.999842)
		(end 217.748612 -77.600302)
		(stroke
			(width 0.2)
			(type default)
		)
		(layer "In6.Cu")
	)
	(gr_arc
		(start 217.748612 -77.600302)
		(mid 217.200099 -77.051408)
		(end 216.651332 -77.600048)
		(stroke
			(width 0.2)
			(type default)
		)
		(layer "In6.Cu")
	)
	(gr_line
		(start 217.748612 -71.799958)
		(end 217.748612 -70.39991)
		(stroke
			(width 0.2)
			(type default)
		)
		(layer "In6.Cu")
	)
	(gr_arc
		(start 217.748612 -70.39991)
		(mid 217.199972 -69.85127)
		(end 216.651332 -70.39991)
		(stroke
			(width 0.2)
			(type default)
		)
		(layer "In6.Cu")
	)
	(gr_arc
		(start 218.45143 -77.799692)
		(mid 218.999943 -78.348586)
		(end 219.54871 -77.799946)
		(stroke
			(width 0.2)
			(type default)
		)
		(layer "In6.Cu")
	)
	(gr_line
		(start 218.45143 -76.399898)
		(end 218.45143 -77.799692)
		(stroke
			(width 0.2)
			(type default)
		)
		(layer "In6.Cu")
	)
	(gr_arc
		(start 218.45143 -66.999612)
		(mid 218.999943 -67.548506)
		(end 219.54871 -66.999866)
		(stroke
			(width 0.2)
			(type default)
		)
		(layer "In6.Cu")
	)
	(gr_line
		(start 218.45143 -65.600072)
		(end 218.45143 -66.999612)
		(stroke
			(width 0.2)
			(type default)
		)
		(layer "In6.Cu")
	)
	(gr_line
		(start 219.54871 -77.799946)
		(end 219.54871 -76.399898)
		(stroke
			(width 0.2)
			(type default)
		)
		(layer "In6.Cu")
	)
	(gr_arc
		(start 219.54871 -76.399898)
		(mid 219.00007 -75.851258)
		(end 218.45143 -76.399898)
		(stroke
			(width 0.2)
			(type default)
		)
		(layer "In6.Cu")
	)
	(gr_line
		(start 219.54871 -66.999866)
		(end 219.54871 -65.600072)
		(stroke
			(width 0.2)
			(type default)
		)
		(layer "In6.Cu")
	)
	(gr_arc
		(start 219.54871 -65.600072)
		(mid 219.00007 -65.051432)
		(end 218.45143 -65.600072)
		(stroke
			(width 0.2)
			(type default)
		)
		(layer "In6.Cu")
	)
	(gr_arc
		(start 220.251528 -78.999842)
		(mid 220.800168 -79.548482)
		(end 221.348808 -78.999842)
		(stroke
			(width 0.2)
			(type default)
		)
		(layer "In6.Cu")
	)
	(gr_line
		(start 220.251528 -77.600048)
		(end 220.251528 -78.999842)
		(stroke
			(width 0.2)
			(type default)
		)
		(layer "In6.Cu")
	)
	(gr_arc
		(start 220.251528 -71.799704)
		(mid 220.800041 -72.348598)
		(end 221.348808 -71.799958)
		(stroke
			(width 0.2)
			(type default)
		)
		(layer "In6.Cu")
	)
	(gr_line
		(start 220.251528 -70.39991)
		(end 220.251528 -71.799704)
		(stroke
			(width 0.2)
			(type default)
		)
		(layer "In6.Cu")
	)
	(gr_line
		(start 221.348808 -78.999842)
		(end 221.348808 -77.600302)
		(stroke
			(width 0.2)
			(type default)
		)
		(layer "In6.Cu")
	)
	(gr_arc
		(start 221.348808 -77.600302)
		(mid 220.800295 -77.051408)
		(end 220.251528 -77.600048)
		(stroke
			(width 0.2)
			(type default)
		)
		(layer "In6.Cu")
	)
	(gr_line
		(start 221.348808 -71.799958)
		(end 221.348808 -70.39991)
		(stroke
			(width 0.2)
			(type default)
		)
		(layer "In6.Cu")
	)
	(gr_arc
		(start 221.348808 -70.39991)
		(mid 220.800168 -69.85127)
		(end 220.251528 -70.39991)
		(stroke
			(width 0.2)
			(type default)
		)
		(layer "In6.Cu")
	)
	(gr_arc
		(start 222.051372 -77.799692)
		(mid 222.599885 -78.348586)
		(end 223.148652 -77.799946)
		(stroke
			(width 0.2)
			(type default)
		)
		(layer "In6.Cu")
	)
	(gr_line
		(start 222.051372 -76.399898)
		(end 222.051372 -77.799692)
		(stroke
			(width 0.2)
			(type default)
		)
		(layer "In6.Cu")
	)
	(gr_arc
		(start 222.051372 -66.999866)
		(mid 222.600012 -67.548506)
		(end 223.148652 -66.999866)
		(stroke
			(width 0.2)
			(type default)
		)
		(layer "In6.Cu")
	)
	(gr_line
		(start 222.051372 -65.600072)
		(end 222.051372 -66.999866)
		(stroke
			(width 0.2)
			(type default)
		)
		(layer "In6.Cu")
	)
	(gr_line
		(start 223.148652 -77.799946)
		(end 223.148652 -76.399898)
		(stroke
			(width 0.2)
			(type default)
		)
		(layer "In6.Cu")
	)
	(gr_arc
		(start 223.148652 -76.399898)
		(mid 222.600012 -75.851258)
		(end 222.051372 -76.399898)
		(stroke
			(width 0.2)
			(type default)
		)
		(layer "In6.Cu")
	)
	(gr_line
		(start 223.148652 -66.999866)
		(end 223.148652 -65.600326)
		(stroke
			(width 0.2)
			(type default)
		)
		(layer "In6.Cu")
	)
	(gr_arc
		(start 223.148652 -65.600326)
		(mid 222.600139 -65.051432)
		(end 222.051372 -65.600072)
		(stroke
			(width 0.2)
			(type default)
		)
		(layer "In6.Cu")
	)
	(gr_line
		(start 251.000006 -380.000002)
		(end 199.00011 -380.000002)
		(stroke
			(width 1.524)
			(type default)
		)
		(layer "In6.Cu")
	)
	(gr_line
		(start 252.000004 -384.999992)
		(end 252.000004 -381)
		(stroke
			(width 1.524)
			(type default)
		)
		(layer "In6.Cu")
	)
	(gr_arc
		(start 252.000004 -384.999992)
		(mid 252.292894 -385.707102)
		(end 253.000002 -385.99999)
		(stroke
			(width 1.524)
			(type default)
		)
		(layer "In6.Cu")
	)
	(gr_arc
		(start 252.000004 -381)
		(mid 251.707111 -380.292895)
		(end 251.000006 -380.000002)
		(stroke
			(width 1.524)
			(type default)
		)
		(layer "In6.Cu")
	)
	(gr_arc
		(start 267.999972 -62.999874)
		(mid 268.707077 -62.706981)
		(end 268.99997 -61.999876)
		(stroke
			(width 1.524)
			(type default)
		)
		(layer "In6.Cu")
	)
	(gr_line
		(start 268.99997 -61.999876)
		(end 268.99997 -49.200054)
		(stroke
			(width 1.524)
			(type default)
		)
		(layer "In6.Cu")
	)
	(gr_line
		(start 269.035784 -385.99999)
		(end 253.000002 -385.99999)
		(stroke
			(width 1.524)
			(type default)
		)
		(layer "In6.Cu")
	)
	(gr_arc
		(start 269.035784 -385.99999)
		(mid 269.41848 -385.923895)
		(end 269.74292 -385.707128)
		(stroke
			(width 1.524)
			(type default)
		)
		(layer "In6.Cu")
	)
	(gr_arc
		(start 269.999968 -48.200056)
		(mid 269.292867 -48.492957)
		(end 268.99997 -49.200054)
		(stroke
			(width 1.524)
			(type default)
		)
		(layer "In6.Cu")
	)
	(gr_line
		(start 269.999968 -48.200056)
		(end 309.999888 -48.200056)
		(stroke
			(width 1.524)
			(type default)
		)
		(layer "In6.Cu")
	)
	(gr_line
		(start 272.15719 -383.292858)
		(end 269.74292 -385.707128)
		(stroke
			(width 1.524)
			(type default)
		)
		(layer "In6.Cu")
	)
	(gr_arc
		(start 272.15719 -383.292858)
		(mid 272.373925 -382.968408)
		(end 272.450052 -382.585722)
		(stroke
			(width 1.524)
			(type default)
		)
		(layer "In6.Cu")
	)
	(gr_line
		(start 272.450052 -361.00004)
		(end 272.450052 -382.585722)
		(stroke
			(width 1.524)
			(type default)
		)
		(layer "In6.Cu")
	)
	(gr_arc
		(start 273.45005 -360.000042)
		(mid 272.742945 -360.292935)
		(end 272.450052 -361.00004)
		(stroke
			(width 1.524)
			(type default)
		)
		(layer "In6.Cu")
	)
	(gr_line
		(start 275.75002 -360.000042)
		(end 273.45005 -360.000042)
		(stroke
			(width 1.524)
			(type default)
		)
		(layer "In6.Cu")
	)
	(gr_line
		(start 276.750018 -382.585722)
		(end 276.750018 -361.00004)
		(stroke
			(width 1.524)
			(type default)
		)
		(layer "In6.Cu")
	)
	(gr_arc
		(start 276.750018 -382.585722)
		(mid 276.826093 -382.96843)
		(end 277.04288 -383.292858)
		(stroke
			(width 1.524)
			(type default)
		)
		(layer "In6.Cu")
	)
	(gr_arc
		(start 276.750018 -361.00004)
		(mid 276.457125 -360.292935)
		(end 275.75002 -360.000042)
		(stroke
			(width 1.524)
			(type default)
		)
		(layer "In6.Cu")
	)
	(gr_line
		(start 278.23668 -237.44301)
		(end 279.636728 -237.44301)
		(stroke
			(width 0.2)
			(type default)
		)
		(layer "In6.Cu")
	)
	(gr_arc
		(start 278.23668 -236.34573)
		(mid 277.68804 -236.89437)
		(end 278.23668 -237.44301)
		(stroke
			(width 0.2)
			(type default)
		)
		(layer "In6.Cu")
	)
	(gr_line
		(start 278.23668 -233.843068)
		(end 279.636728 -233.843068)
		(stroke
			(width 0.2)
			(type default)
		)
		(layer "In6.Cu")
	)
	(gr_arc
		(start 278.23668 -232.745788)
		(mid 277.68804 -233.294428)
		(end 278.23668 -233.843068)
		(stroke
			(width 0.2)
			(type default)
		)
		(layer "In6.Cu")
	)
	(gr_line
		(start 278.23668 -230.243126)
		(end 279.636728 -230.243126)
		(stroke
			(width 0.2)
			(type default)
		)
		(layer "In6.Cu")
	)
	(gr_arc
		(start 278.23668 -229.145846)
		(mid 277.68804 -229.694486)
		(end 278.23668 -230.243126)
		(stroke
			(width 0.2)
			(type default)
		)
		(layer "In6.Cu")
	)
	(gr_line
		(start 278.23668 -226.643184)
		(end 279.636728 -226.643184)
		(stroke
			(width 0.2)
			(type default)
		)
		(layer "In6.Cu")
	)
	(gr_arc
		(start 278.23668 -225.545904)
		(mid 277.68804 -226.094544)
		(end 278.23668 -226.643184)
		(stroke
			(width 0.2)
			(type default)
		)
		(layer "In6.Cu")
	)
	(gr_line
		(start 278.23668 -223.042988)
		(end 279.636728 -223.042988)
		(stroke
			(width 0.2)
			(type default)
		)
		(layer "In6.Cu")
	)
	(gr_arc
		(start 278.23668 -221.945708)
		(mid 277.68804 -222.494348)
		(end 278.23668 -223.042988)
		(stroke
			(width 0.2)
			(type default)
		)
		(layer "In6.Cu")
	)
	(gr_line
		(start 278.23668 -219.443046)
		(end 279.636728 -219.443046)
		(stroke
			(width 0.2)
			(type default)
		)
		(layer "In6.Cu")
	)
	(gr_arc
		(start 278.23668 -218.345766)
		(mid 277.68804 -218.894406)
		(end 278.23668 -219.443046)
		(stroke
			(width 0.2)
			(type default)
		)
		(layer "In6.Cu")
	)
	(gr_line
		(start 278.23668 -215.843104)
		(end 279.636728 -215.843104)
		(stroke
			(width 0.2)
			(type default)
		)
		(layer "In6.Cu")
	)
	(gr_arc
		(start 278.23668 -214.745824)
		(mid 277.68804 -215.294464)
		(end 278.23668 -215.843104)
		(stroke
			(width 0.2)
			(type default)
		)
		(layer "In6.Cu")
	)
	(gr_line
		(start 278.23668 -212.243162)
		(end 279.636728 -212.243162)
		(stroke
			(width 0.2)
			(type default)
		)
		(layer "In6.Cu")
	)
	(gr_arc
		(start 278.23668 -211.145882)
		(mid 277.68804 -211.694522)
		(end 278.23668 -212.243162)
		(stroke
			(width 0.2)
			(type default)
		)
		(layer "In6.Cu")
	)
	(gr_line
		(start 278.23668 -208.64322)
		(end 279.636728 -208.64322)
		(stroke
			(width 0.2)
			(type default)
		)
		(layer "In6.Cu")
	)
	(gr_arc
		(start 278.23668 -207.54594)
		(mid 277.68804 -208.09458)
		(end 278.23668 -208.64322)
		(stroke
			(width 0.2)
			(type default)
		)
		(layer "In6.Cu")
	)
	(gr_line
		(start 278.23668 -205.043024)
		(end 279.636728 -205.043024)
		(stroke
			(width 0.2)
			(type default)
		)
		(layer "In6.Cu")
	)
	(gr_arc
		(start 278.23668 -203.945744)
		(mid 277.68804 -204.494384)
		(end 278.23668 -205.043024)
		(stroke
			(width 0.2)
			(type default)
		)
		(layer "In6.Cu")
	)
	(gr_line
		(start 278.23668 -201.443082)
		(end 279.636728 -201.443082)
		(stroke
			(width 0.2)
			(type default)
		)
		(layer "In6.Cu")
	)
	(gr_arc
		(start 278.23668 -200.345802)
		(mid 277.68804 -200.894442)
		(end 278.23668 -201.443082)
		(stroke
			(width 0.2)
			(type default)
		)
		(layer "In6.Cu")
	)
	(gr_line
		(start 278.23668 -197.84314)
		(end 279.636728 -197.84314)
		(stroke
			(width 0.2)
			(type default)
		)
		(layer "In6.Cu")
	)
	(gr_arc
		(start 278.23668 -196.74586)
		(mid 277.68804 -197.2945)
		(end 278.23668 -197.84314)
		(stroke
			(width 0.2)
			(type default)
		)
		(layer "In6.Cu")
	)
	(gr_line
		(start 278.23668 -194.243198)
		(end 279.636728 -194.243198)
		(stroke
			(width 0.2)
			(type default)
		)
		(layer "In6.Cu")
	)
	(gr_arc
		(start 278.23668 -193.145918)
		(mid 277.68804 -193.694558)
		(end 278.23668 -194.243198)
		(stroke
			(width 0.2)
			(type default)
		)
		(layer "In6.Cu")
	)
	(gr_line
		(start 278.23668 -190.643002)
		(end 279.636728 -190.643002)
		(stroke
			(width 0.2)
			(type default)
		)
		(layer "In6.Cu")
	)
	(gr_arc
		(start 278.23668 -189.545722)
		(mid 277.68804 -190.094362)
		(end 278.23668 -190.643002)
		(stroke
			(width 0.2)
			(type default)
		)
		(layer "In6.Cu")
	)
	(gr_line
		(start 278.23668 -187.04306)
		(end 279.636728 -187.04306)
		(stroke
			(width 0.2)
			(type default)
		)
		(layer "In6.Cu")
	)
	(gr_arc
		(start 278.23668 -185.94578)
		(mid 277.68804 -186.49442)
		(end 278.23668 -187.04306)
		(stroke
			(width 0.2)
			(type default)
		)
		(layer "In6.Cu")
	)
	(gr_line
		(start 278.23668 -183.443118)
		(end 279.636728 -183.443118)
		(stroke
			(width 0.2)
			(type default)
		)
		(layer "In6.Cu")
	)
	(gr_arc
		(start 278.23668 -182.345838)
		(mid 277.68804 -182.894478)
		(end 278.23668 -183.443118)
		(stroke
			(width 0.2)
			(type default)
		)
		(layer "In6.Cu")
	)
	(gr_line
		(start 278.23668 -179.843176)
		(end 279.636728 -179.843176)
		(stroke
			(width 0.2)
			(type default)
		)
		(layer "In6.Cu")
	)
	(gr_arc
		(start 278.23668 -178.745896)
		(mid 277.68804 -179.294536)
		(end 278.23668 -179.843176)
		(stroke
			(width 0.2)
			(type default)
		)
		(layer "In6.Cu")
	)
	(gr_line
		(start 278.23668 -176.243234)
		(end 279.636728 -176.243234)
		(stroke
			(width 0.2)
			(type default)
		)
		(layer "In6.Cu")
	)
	(gr_arc
		(start 278.23668 -175.145954)
		(mid 277.68804 -175.694594)
		(end 278.23668 -176.243234)
		(stroke
			(width 0.2)
			(type default)
		)
		(layer "In6.Cu")
	)
	(gr_line
		(start 278.23668 -143.442944)
		(end 279.636728 -143.442944)
		(stroke
			(width 0.2)
			(type default)
		)
		(layer "In6.Cu")
	)
	(gr_arc
		(start 278.23668 -142.345664)
		(mid 277.68804 -142.894304)
		(end 278.23668 -143.442944)
		(stroke
			(width 0.2)
			(type default)
		)
		(layer "In6.Cu")
	)
	(gr_line
		(start 278.23668 -139.843002)
		(end 279.636728 -139.843002)
		(stroke
			(width 0.2)
			(type default)
		)
		(layer "In6.Cu")
	)
	(gr_arc
		(start 278.23668 -138.745722)
		(mid 277.68804 -139.294362)
		(end 278.23668 -139.843002)
		(stroke
			(width 0.2)
			(type default)
		)
		(layer "In6.Cu")
	)
	(gr_line
		(start 278.23668 -136.24306)
		(end 279.636728 -136.24306)
		(stroke
			(width 0.2)
			(type default)
		)
		(layer "In6.Cu")
	)
	(gr_arc
		(start 278.23668 -135.14578)
		(mid 277.68804 -135.69442)
		(end 278.23668 -136.24306)
		(stroke
			(width 0.2)
			(type default)
		)
		(layer "In6.Cu")
	)
	(gr_line
		(start 278.23668 -132.643118)
		(end 279.636728 -132.643118)
		(stroke
			(width 0.2)
			(type default)
		)
		(layer "In6.Cu")
	)
	(gr_arc
		(start 278.23668 -131.545838)
		(mid 277.68804 -132.094478)
		(end 278.23668 -132.643118)
		(stroke
			(width 0.2)
			(type default)
		)
		(layer "In6.Cu")
	)
	(gr_line
		(start 279.236678 -239.243108)
		(end 280.636726 -239.243108)
		(stroke
			(width 0.2)
			(type default)
		)
		(layer "In6.Cu")
	)
	(gr_arc
		(start 279.236678 -238.145828)
		(mid 278.688038 -238.694468)
		(end 279.236678 -239.243108)
		(stroke
			(width 0.2)
			(type default)
		)
		(layer "In6.Cu")
	)
	(gr_line
		(start 279.236678 -235.643166)
		(end 280.636726 -235.643166)
		(stroke
			(width 0.2)
			(type default)
		)
		(layer "In6.Cu")
	)
	(gr_arc
		(start 279.236678 -234.545886)
		(mid 278.688038 -235.094526)
		(end 279.236678 -235.643166)
		(stroke
			(width 0.2)
			(type default)
		)
		(layer "In6.Cu")
	)
	(gr_line
		(start 279.236678 -232.043224)
		(end 280.636726 -232.043224)
		(stroke
			(width 0.2)
			(type default)
		)
		(layer "In6.Cu")
	)
	(gr_arc
		(start 279.236678 -230.945944)
		(mid 278.688038 -231.494584)
		(end 279.236678 -232.043224)
		(stroke
			(width 0.2)
			(type default)
		)
		(layer "In6.Cu")
	)
	(gr_line
		(start 279.236678 -228.443028)
		(end 280.636726 -228.443028)
		(stroke
			(width 0.2)
			(type default)
		)
		(layer "In6.Cu")
	)
	(gr_arc
		(start 279.236678 -227.345748)
		(mid 278.688038 -227.894388)
		(end 279.236678 -228.443028)
		(stroke
			(width 0.2)
			(type default)
		)
		(layer "In6.Cu")
	)
	(gr_line
		(start 279.236678 -224.843086)
		(end 280.636726 -224.843086)
		(stroke
			(width 0.2)
			(type default)
		)
		(layer "In6.Cu")
	)
	(gr_arc
		(start 279.236678 -223.745806)
		(mid 278.688038 -224.294446)
		(end 279.236678 -224.843086)
		(stroke
			(width 0.2)
			(type default)
		)
		(layer "In6.Cu")
	)
	(gr_line
		(start 279.236678 -221.243144)
		(end 280.636726 -221.243144)
		(stroke
			(width 0.2)
			(type default)
		)
		(layer "In6.Cu")
	)
	(gr_arc
		(start 279.236678 -220.145864)
		(mid 278.688038 -220.694504)
		(end 279.236678 -221.243144)
		(stroke
			(width 0.2)
			(type default)
		)
		(layer "In6.Cu")
	)
	(gr_line
		(start 279.236678 -217.643202)
		(end 280.636726 -217.643202)
		(stroke
			(width 0.2)
			(type default)
		)
		(layer "In6.Cu")
	)
	(gr_arc
		(start 279.236678 -216.545922)
		(mid 278.688038 -217.094562)
		(end 279.236678 -217.643202)
		(stroke
			(width 0.2)
			(type default)
		)
		(layer "In6.Cu")
	)
	(gr_line
		(start 279.236678 -214.043006)
		(end 280.636726 -214.043006)
		(stroke
			(width 0.2)
			(type default)
		)
		(layer "In6.Cu")
	)
	(gr_arc
		(start 279.236678 -212.945726)
		(mid 278.688038 -213.494366)
		(end 279.236678 -214.043006)
		(stroke
			(width 0.2)
			(type default)
		)
		(layer "In6.Cu")
	)
	(gr_line
		(start 279.236678 -210.443064)
		(end 280.636726 -210.443064)
		(stroke
			(width 0.2)
			(type default)
		)
		(layer "In6.Cu")
	)
	(gr_arc
		(start 279.236678 -209.345784)
		(mid 278.688038 -209.894424)
		(end 279.236678 -210.443064)
		(stroke
			(width 0.2)
			(type default)
		)
		(layer "In6.Cu")
	)
	(gr_line
		(start 279.236678 -206.843122)
		(end 280.636726 -206.843122)
		(stroke
			(width 0.2)
			(type default)
		)
		(layer "In6.Cu")
	)
	(gr_arc
		(start 279.236678 -205.745842)
		(mid 278.688038 -206.294482)
		(end 279.236678 -206.843122)
		(stroke
			(width 0.2)
			(type default)
		)
		(layer "In6.Cu")
	)
	(gr_line
		(start 279.236678 -203.24318)
		(end 280.636726 -203.24318)
		(stroke
			(width 0.2)
			(type default)
		)
		(layer "In6.Cu")
	)
	(gr_arc
		(start 279.236678 -202.1459)
		(mid 278.688038 -202.69454)
		(end 279.236678 -203.24318)
		(stroke
			(width 0.2)
			(type default)
		)
		(layer "In6.Cu")
	)
	(gr_line
		(start 279.236678 -199.642984)
		(end 280.636726 -199.642984)
		(stroke
			(width 0.2)
			(type default)
		)
		(layer "In6.Cu")
	)
	(gr_arc
		(start 279.236678 -198.545704)
		(mid 278.688038 -199.094344)
		(end 279.236678 -199.642984)
		(stroke
			(width 0.2)
			(type default)
		)
		(layer "In6.Cu")
	)
	(gr_line
		(start 279.236678 -196.043042)
		(end 280.636726 -196.043042)
		(stroke
			(width 0.2)
			(type default)
		)
		(layer "In6.Cu")
	)
	(gr_arc
		(start 279.236678 -194.945762)
		(mid 278.688038 -195.494402)
		(end 279.236678 -196.043042)
		(stroke
			(width 0.2)
			(type default)
		)
		(layer "In6.Cu")
	)
	(gr_line
		(start 279.236678 -192.4431)
		(end 280.636726 -192.4431)
		(stroke
			(width 0.2)
			(type default)
		)
		(layer "In6.Cu")
	)
	(gr_arc
		(start 279.236678 -191.34582)
		(mid 278.688038 -191.89446)
		(end 279.236678 -192.4431)
		(stroke
			(width 0.2)
			(type default)
		)
		(layer "In6.Cu")
	)
	(gr_line
		(start 279.236678 -188.843158)
		(end 280.636726 -188.843158)
		(stroke
			(width 0.2)
			(type default)
		)
		(layer "In6.Cu")
	)
	(gr_arc
		(start 279.236678 -187.745878)
		(mid 278.688038 -188.294518)
		(end 279.236678 -188.843158)
		(stroke
			(width 0.2)
			(type default)
		)
		(layer "In6.Cu")
	)
	(gr_line
		(start 279.236678 -185.243216)
		(end 280.636726 -185.243216)
		(stroke
			(width 0.2)
			(type default)
		)
		(layer "In6.Cu")
	)
	(gr_arc
		(start 279.236678 -184.145936)
		(mid 278.688038 -184.694576)
		(end 279.236678 -185.243216)
		(stroke
			(width 0.2)
			(type default)
		)
		(layer "In6.Cu")
	)
	(gr_line
		(start 279.236678 -181.64302)
		(end 280.636726 -181.64302)
		(stroke
			(width 0.2)
			(type default)
		)
		(layer "In6.Cu")
	)
	(gr_arc
		(start 279.236678 -180.54574)
		(mid 278.688038 -181.09438)
		(end 279.236678 -181.64302)
		(stroke
			(width 0.2)
			(type default)
		)
		(layer "In6.Cu")
	)
	(gr_line
		(start 279.236678 -178.043078)
		(end 280.636726 -178.043078)
		(stroke
			(width 0.2)
			(type default)
		)
		(layer "In6.Cu")
	)
	(gr_arc
		(start 279.236678 -176.945798)
		(mid 278.688038 -177.494438)
		(end 279.236678 -178.043078)
		(stroke
			(width 0.2)
			(type default)
		)
		(layer "In6.Cu")
	)
	(gr_line
		(start 279.236678 -145.243042)
		(end 280.636726 -145.243042)
		(stroke
			(width 0.2)
			(type default)
		)
		(layer "In6.Cu")
	)
	(gr_arc
		(start 279.236678 -144.145762)
		(mid 278.688038 -144.694402)
		(end 279.236678 -145.243042)
		(stroke
			(width 0.2)
			(type default)
		)
		(layer "In6.Cu")
	)
	(gr_line
		(start 279.236678 -141.6431)
		(end 280.636726 -141.6431)
		(stroke
			(width 0.2)
			(type default)
		)
		(layer "In6.Cu")
	)
	(gr_arc
		(start 279.236678 -140.54582)
		(mid 278.688038 -141.09446)
		(end 279.236678 -141.6431)
		(stroke
			(width 0.2)
			(type default)
		)
		(layer "In6.Cu")
	)
	(gr_line
		(start 279.236678 -138.045698)
		(end 280.636726 -138.045698)
		(stroke
			(width 0.2)
			(type default)
		)
		(layer "In6.Cu")
	)
	(gr_arc
		(start 279.236678 -136.943338)
		(mid 278.685498 -137.494518)
		(end 279.236678 -138.045698)
		(stroke
			(width 0.2)
			(type default)
		)
		(layer "In6.Cu")
	)
	(gr_line
		(start 279.236678 -134.442962)
		(end 280.636726 -134.442962)
		(stroke
			(width 0.2)
			(type default)
		)
		(layer "In6.Cu")
	)
	(gr_arc
		(start 279.236678 -133.345682)
		(mid 278.688038 -133.894322)
		(end 279.236678 -134.442962)
		(stroke
			(width 0.2)
			(type default)
		)
		(layer "In6.Cu")
	)
	(gr_line
		(start 279.236932 -136.943338)
		(end 279.236678 -136.943338)
		(stroke
			(width 0.2)
			(type default)
		)
		(layer "In6.Cu")
	)
	(gr_line
		(start 279.45715 -385.707128)
		(end 277.04288 -383.292858)
		(stroke
			(width 1.524)
			(type default)
		)
		(layer "In6.Cu")
	)
	(gr_arc
		(start 279.45715 -385.707128)
		(mid 279.781602 -385.923853)
		(end 280.164286 -385.99999)
		(stroke
			(width 1.524)
			(type default)
		)
		(layer "In6.Cu")
	)
	(gr_arc
		(start 279.636728 -237.44301)
		(mid 280.185368 -236.89437)
		(end 279.636728 -236.34573)
		(stroke
			(width 0.2)
			(type default)
		)
		(layer "In6.Cu")
	)
	(gr_line
		(start 279.636728 -236.34573)
		(end 278.23668 -236.34573)
		(stroke
			(width 0.2)
			(type default)
		)
		(layer "In6.Cu")
	)
	(gr_arc
		(start 279.636728 -233.843068)
		(mid 280.185368 -233.294428)
		(end 279.636728 -232.745788)
		(stroke
			(width 0.2)
			(type default)
		)
		(layer "In6.Cu")
	)
	(gr_line
		(start 279.636728 -232.745788)
		(end 278.23668 -232.745788)
		(stroke
			(width 0.2)
			(type default)
		)
		(layer "In6.Cu")
	)
	(gr_arc
		(start 279.636728 -230.243126)
		(mid 280.185368 -229.694486)
		(end 279.636728 -229.145846)
		(stroke
			(width 0.2)
			(type default)
		)
		(layer "In6.Cu")
	)
	(gr_line
		(start 279.636728 -229.145846)
		(end 278.23668 -229.145846)
		(stroke
			(width 0.2)
			(type default)
		)
		(layer "In6.Cu")
	)
	(gr_arc
		(start 279.636728 -226.643184)
		(mid 280.185368 -226.094544)
		(end 279.636728 -225.545904)
		(stroke
			(width 0.2)
			(type default)
		)
		(layer "In6.Cu")
	)
	(gr_line
		(start 279.636728 -225.545904)
		(end 278.23668 -225.545904)
		(stroke
			(width 0.2)
			(type default)
		)
		(layer "In6.Cu")
	)
	(gr_arc
		(start 279.636728 -223.042988)
		(mid 280.185368 -222.494348)
		(end 279.636728 -221.945708)
		(stroke
			(width 0.2)
			(type default)
		)
		(layer "In6.Cu")
	)
	(gr_line
		(start 279.636728 -221.945708)
		(end 278.23668 -221.945708)
		(stroke
			(width 0.2)
			(type default)
		)
		(layer "In6.Cu")
	)
	(gr_arc
		(start 279.636728 -219.443046)
		(mid 280.185368 -218.894406)
		(end 279.636728 -218.345766)
		(stroke
			(width 0.2)
			(type default)
		)
		(layer "In6.Cu")
	)
	(gr_line
		(start 279.636728 -218.345766)
		(end 278.23668 -218.345766)
		(stroke
			(width 0.2)
			(type default)
		)
		(layer "In6.Cu")
	)
	(gr_arc
		(start 279.636728 -215.843104)
		(mid 280.185368 -215.294464)
		(end 279.636728 -214.745824)
		(stroke
			(width 0.2)
			(type default)
		)
		(layer "In6.Cu")
	)
	(gr_line
		(start 279.636728 -214.745824)
		(end 278.23668 -214.745824)
		(stroke
			(width 0.2)
			(type default)
		)
		(layer "In6.Cu")
	)
	(gr_arc
		(start 279.636728 -212.243162)
		(mid 280.185368 -211.694522)
		(end 279.636728 -211.145882)
		(stroke
			(width 0.2)
			(type default)
		)
		(layer "In6.Cu")
	)
	(gr_line
		(start 279.636728 -211.145882)
		(end 278.23668 -211.145882)
		(stroke
			(width 0.2)
			(type default)
		)
		(layer "In6.Cu")
	)
	(gr_arc
		(start 279.636728 -208.64322)
		(mid 280.185368 -208.09458)
		(end 279.636728 -207.54594)
		(stroke
			(width 0.2)
			(type default)
		)
		(layer "In6.Cu")
	)
	(gr_line
		(start 279.636728 -207.54594)
		(end 278.23668 -207.54594)
		(stroke
			(width 0.2)
			(type default)
		)
		(layer "In6.Cu")
	)
	(gr_arc
		(start 279.636728 -205.043024)
		(mid 280.185368 -204.494384)
		(end 279.636728 -203.945744)
		(stroke
			(width 0.2)
			(type default)
		)
		(layer "In6.Cu")
	)
	(gr_line
		(start 279.636728 -203.945744)
		(end 278.23668 -203.945744)
		(stroke
			(width 0.2)
			(type default)
		)
		(layer "In6.Cu")
	)
	(gr_arc
		(start 279.636728 -201.443082)
		(mid 280.185368 -200.894442)
		(end 279.636728 -200.345802)
		(stroke
			(width 0.2)
			(type default)
		)
		(layer "In6.Cu")
	)
	(gr_line
		(start 279.636728 -200.345802)
		(end 278.23668 -200.345802)
		(stroke
			(width 0.2)
			(type default)
		)
		(layer "In6.Cu")
	)
	(gr_arc
		(start 279.636728 -197.84314)
		(mid 280.185368 -197.2945)
		(end 279.636728 -196.74586)
		(stroke
			(width 0.2)
			(type default)
		)
		(layer "In6.Cu")
	)
	(gr_line
		(start 279.636728 -196.74586)
		(end 278.23668 -196.74586)
		(stroke
			(width 0.2)
			(type default)
		)
		(layer "In6.Cu")
	)
	(gr_arc
		(start 279.636728 -194.243198)
		(mid 280.185368 -193.694558)
		(end 279.636728 -193.145918)
		(stroke
			(width 0.2)
			(type default)
		)
		(layer "In6.Cu")
	)
	(gr_line
		(start 279.636728 -193.145918)
		(end 278.23668 -193.145918)
		(stroke
			(width 0.2)
			(type default)
		)
		(layer "In6.Cu")
	)
	(gr_arc
		(start 279.636728 -190.643002)
		(mid 280.185368 -190.094362)
		(end 279.636728 -189.545722)
		(stroke
			(width 0.2)
			(type default)
		)
		(layer "In6.Cu")
	)
	(gr_line
		(start 279.636728 -189.545722)
		(end 278.23668 -189.545722)
		(stroke
			(width 0.2)
			(type default)
		)
		(layer "In6.Cu")
	)
	(gr_arc
		(start 279.636728 -187.04306)
		(mid 280.185368 -186.49442)
		(end 279.636728 -185.94578)
		(stroke
			(width 0.2)
			(type default)
		)
		(layer "In6.Cu")
	)
	(gr_line
		(start 279.636728 -185.94578)
		(end 278.23668 -185.94578)
		(stroke
			(width 0.2)
			(type default)
		)
		(layer "In6.Cu")
	)
	(gr_arc
		(start 279.636728 -183.443118)
		(mid 280.185368 -182.894478)
		(end 279.636728 -182.345838)
		(stroke
			(width 0.2)
			(type default)
		)
		(layer "In6.Cu")
	)
	(gr_line
		(start 279.636728 -182.345838)
		(end 278.23668 -182.345838)
		(stroke
			(width 0.2)
			(type default)
		)
		(layer "In6.Cu")
	)
	(gr_arc
		(start 279.636728 -179.843176)
		(mid 280.185368 -179.294536)
		(end 279.636728 -178.745896)
		(stroke
			(width 0.2)
			(type default)
		)
		(layer "In6.Cu")
	)
	(gr_line
		(start 279.636728 -178.745896)
		(end 278.23668 -178.745896)
		(stroke
			(width 0.2)
			(type default)
		)
		(layer "In6.Cu")
	)
	(gr_arc
		(start 279.636728 -176.243234)
		(mid 280.185368 -175.694594)
		(end 279.636728 -175.145954)
		(stroke
			(width 0.2)
			(type default)
		)
		(layer "In6.Cu")
	)
	(gr_line
		(start 279.636728 -175.145954)
		(end 278.23668 -175.145954)
		(stroke
			(width 0.2)
			(type default)
		)
		(layer "In6.Cu")
	)
	(gr_arc
		(start 279.636728 -143.442944)
		(mid 280.185368 -142.894304)
		(end 279.636728 -142.345664)
		(stroke
			(width 0.2)
			(type default)
		)
		(layer "In6.Cu")
	)
	(gr_line
		(start 279.636728 -142.345664)
		(end 278.23668 -142.345664)
		(stroke
			(width 0.2)
			(type default)
		)
		(layer "In6.Cu")
	)
	(gr_arc
		(start 279.636728 -139.843002)
		(mid 280.185368 -139.294362)
		(end 279.636728 -138.745722)
		(stroke
			(width 0.2)
			(type default)
		)
		(layer "In6.Cu")
	)
	(gr_line
		(start 279.636728 -138.745722)
		(end 278.23668 -138.745722)
		(stroke
			(width 0.2)
			(type default)
		)
		(layer "In6.Cu")
	)
	(gr_arc
		(start 279.636728 -136.24306)
		(mid 280.185368 -135.69442)
		(end 279.636728 -135.14578)
		(stroke
			(width 0.2)
			(type default)
		)
		(layer "In6.Cu")
	)
	(gr_line
		(start 279.636728 -135.14578)
		(end 278.23668 -135.14578)
		(stroke
			(width 0.2)
			(type default)
		)
		(layer "In6.Cu")
	)
	(gr_arc
		(start 279.636728 -132.643118)
		(mid 280.185368 -132.094478)
		(end 279.636728 -131.545838)
		(stroke
			(width 0.2)
			(type default)
		)
		(layer "In6.Cu")
	)
	(gr_line
		(start 279.636728 -131.545838)
		(end 278.23668 -131.545838)
		(stroke
			(width 0.2)
			(type default)
		)
		(layer "In6.Cu")
	)
	(gr_arc
		(start 280.636726 -239.243108)
		(mid 281.185366 -238.694468)
		(end 280.636726 -238.145828)
		(stroke
			(width 0.2)
			(type default)
		)
		(layer "In6.Cu")
	)
	(gr_line
		(start 280.636726 -238.145828)
		(end 279.236678 -238.145828)
		(stroke
			(width 0.2)
			(type default)
		)
		(layer "In6.Cu")
	)
	(gr_arc
		(start 280.636726 -235.643166)
		(mid 281.185366 -235.094526)
		(end 280.636726 -234.545886)
		(stroke
			(width 0.2)
			(type default)
		)
		(layer "In6.Cu")
	)
	(gr_line
		(start 280.636726 -234.545886)
		(end 279.236678 -234.545886)
		(stroke
			(width 0.2)
			(type default)
		)
		(layer "In6.Cu")
	)
	(gr_arc
		(start 280.636726 -232.043224)
		(mid 281.185366 -231.494584)
		(end 280.636726 -230.945944)
		(stroke
			(width 0.2)
			(type default)
		)
		(layer "In6.Cu")
	)
	(gr_line
		(start 280.636726 -230.945944)
		(end 279.236678 -230.945944)
		(stroke
			(width 0.2)
			(type default)
		)
		(layer "In6.Cu")
	)
	(gr_arc
		(start 280.636726 -228.443028)
		(mid 281.185366 -227.894388)
		(end 280.636726 -227.345748)
		(stroke
			(width 0.2)
			(type default)
		)
		(layer "In6.Cu")
	)
	(gr_line
		(start 280.636726 -227.345748)
		(end 279.236678 -227.345748)
		(stroke
			(width 0.2)
			(type default)
		)
		(layer "In6.Cu")
	)
	(gr_arc
		(start 280.636726 -224.843086)
		(mid 281.185366 -224.294446)
		(end 280.636726 -223.745806)
		(stroke
			(width 0.2)
			(type default)
		)
		(layer "In6.Cu")
	)
	(gr_line
		(start 280.636726 -223.745806)
		(end 279.236678 -223.745806)
		(stroke
			(width 0.2)
			(type default)
		)
		(layer "In6.Cu")
	)
	(gr_arc
		(start 280.636726 -221.243144)
		(mid 281.185366 -220.694504)
		(end 280.636726 -220.145864)
		(stroke
			(width 0.2)
			(type default)
		)
		(layer "In6.Cu")
	)
	(gr_line
		(start 280.636726 -220.145864)
		(end 279.236678 -220.145864)
		(stroke
			(width 0.2)
			(type default)
		)
		(layer "In6.Cu")
	)
	(gr_arc
		(start 280.636726 -217.643202)
		(mid 281.185366 -217.094562)
		(end 280.636726 -216.545922)
		(stroke
			(width 0.2)
			(type default)
		)
		(layer "In6.Cu")
	)
	(gr_line
		(start 280.636726 -216.545922)
		(end 279.236678 -216.545922)
		(stroke
			(width 0.2)
			(type default)
		)
		(layer "In6.Cu")
	)
	(gr_arc
		(start 280.636726 -214.043006)
		(mid 281.185366 -213.494366)
		(end 280.636726 -212.945726)
		(stroke
			(width 0.2)
			(type default)
		)
		(layer "In6.Cu")
	)
	(gr_line
		(start 280.636726 -212.945726)
		(end 279.236678 -212.945726)
		(stroke
			(width 0.2)
			(type default)
		)
		(layer "In6.Cu")
	)
	(gr_arc
		(start 280.636726 -210.443064)
		(mid 281.185366 -209.894424)
		(end 280.636726 -209.345784)
		(stroke
			(width 0.2)
			(type default)
		)
		(layer "In6.Cu")
	)
	(gr_line
		(start 280.636726 -209.345784)
		(end 279.236678 -209.345784)
		(stroke
			(width 0.2)
			(type default)
		)
		(layer "In6.Cu")
	)
	(gr_arc
		(start 280.636726 -206.843122)
		(mid 281.185366 -206.294482)
		(end 280.636726 -205.745842)
		(stroke
			(width 0.2)
			(type default)
		)
		(layer "In6.Cu")
	)
	(gr_line
		(start 280.636726 -205.745842)
		(end 279.236678 -205.745842)
		(stroke
			(width 0.2)
			(type default)
		)
		(layer "In6.Cu")
	)
	(gr_arc
		(start 280.636726 -203.24318)
		(mid 281.185366 -202.69454)
		(end 280.636726 -202.1459)
		(stroke
			(width 0.2)
			(type default)
		)
		(layer "In6.Cu")
	)
	(gr_line
		(start 280.636726 -202.1459)
		(end 279.236678 -202.1459)
		(stroke
			(width 0.2)
			(type default)
		)
		(layer "In6.Cu")
	)
	(gr_arc
		(start 280.636726 -199.642984)
		(mid 281.185366 -199.094344)
		(end 280.636726 -198.545704)
		(stroke
			(width 0.2)
			(type default)
		)
		(layer "In6.Cu")
	)
	(gr_line
		(start 280.636726 -198.545704)
		(end 279.236678 -198.545704)
		(stroke
			(width 0.2)
			(type default)
		)
		(layer "In6.Cu")
	)
	(gr_arc
		(start 280.636726 -196.043042)
		(mid 281.185366 -195.494402)
		(end 280.636726 -194.945762)
		(stroke
			(width 0.2)
			(type default)
		)
		(layer "In6.Cu")
	)
	(gr_line
		(start 280.636726 -194.945762)
		(end 279.236678 -194.945762)
		(stroke
			(width 0.2)
			(type default)
		)
		(layer "In6.Cu")
	)
	(gr_arc
		(start 280.636726 -192.4431)
		(mid 281.185366 -191.89446)
		(end 280.636726 -191.34582)
		(stroke
			(width 0.2)
			(type default)
		)
		(layer "In6.Cu")
	)
	(gr_line
		(start 280.636726 -191.34582)
		(end 279.236678 -191.34582)
		(stroke
			(width 0.2)
			(type default)
		)
		(layer "In6.Cu")
	)
	(gr_arc
		(start 280.636726 -188.843158)
		(mid 281.185366 -188.294518)
		(end 280.636726 -187.745878)
		(stroke
			(width 0.2)
			(type default)
		)
		(layer "In6.Cu")
	)
	(gr_line
		(start 280.636726 -187.745878)
		(end 279.236678 -187.745878)
		(stroke
			(width 0.2)
			(type default)
		)
		(layer "In6.Cu")
	)
	(gr_arc
		(start 280.636726 -185.243216)
		(mid 281.185366 -184.694576)
		(end 280.636726 -184.145936)
		(stroke
			(width 0.2)
			(type default)
		)
		(layer "In6.Cu")
	)
	(gr_line
		(start 280.636726 -184.145936)
		(end 279.236678 -184.145936)
		(stroke
			(width 0.2)
			(type default)
		)
		(layer "In6.Cu")
	)
	(gr_arc
		(start 280.636726 -181.64302)
		(mid 281.185366 -181.09438)
		(end 280.636726 -180.54574)
		(stroke
			(width 0.2)
			(type default)
		)
		(layer "In6.Cu")
	)
	(gr_line
		(start 280.636726 -180.54574)
		(end 279.236678 -180.54574)
		(stroke
			(width 0.2)
			(type default)
		)
		(layer "In6.Cu")
	)
	(gr_arc
		(start 280.636726 -178.043078)
		(mid 281.185366 -177.494438)
		(end 280.636726 -176.945798)
		(stroke
			(width 0.2)
			(type default)
		)
		(layer "In6.Cu")
	)
	(gr_line
		(start 280.636726 -176.945798)
		(end 279.236678 -176.945798)
		(stroke
			(width 0.2)
			(type default)
		)
		(layer "In6.Cu")
	)
	(gr_arc
		(start 280.636726 -145.243042)
		(mid 281.185366 -144.694402)
		(end 280.636726 -144.145762)
		(stroke
			(width 0.2)
			(type default)
		)
		(layer "In6.Cu")
	)
	(gr_line
		(start 280.636726 -144.145762)
		(end 279.236678 -144.145762)
		(stroke
			(width 0.2)
			(type default)
		)
		(layer "In6.Cu")
	)
	(gr_arc
		(start 280.636726 -141.6431)
		(mid 281.185366 -141.09446)
		(end 280.636726 -140.54582)
		(stroke
			(width 0.2)
			(type default)
		)
		(layer "In6.Cu")
	)
	(gr_line
		(start 280.636726 -140.54582)
		(end 279.236678 -140.54582)
		(stroke
			(width 0.2)
			(type default)
		)
		(layer "In6.Cu")
	)
	(gr_arc
		(start 280.636726 -138.045698)
		(mid 281.187906 -137.494518)
		(end 280.636726 -136.943338)
		(stroke
			(width 0.2)
			(type default)
		)
		(layer "In6.Cu")
	)
	(gr_line
		(start 280.636726 -136.943338)
		(end 279.236932 -136.943338)
		(stroke
			(width 0.2)
			(type default)
		)
		(layer "In6.Cu")
	)
	(gr_arc
		(start 280.636726 -134.442962)
		(mid 281.185366 -133.894322)
		(end 280.636726 -133.345682)
		(stroke
			(width 0.2)
			(type default)
		)
		(layer "In6.Cu")
	)
	(gr_line
		(start 280.636726 -133.345682)
		(end 279.236678 -133.345682)
		(stroke
			(width 0.2)
			(type default)
		)
		(layer "In6.Cu")
	)
	(gr_line
		(start 282.83662 -145.243042)
		(end 284.236668 -145.243042)
		(stroke
			(width 0.2)
			(type default)
		)
		(layer "In6.Cu")
	)
	(gr_arc
		(start 282.83662 -144.145762)
		(mid 282.28798 -144.694402)
		(end 282.83662 -145.243042)
		(stroke
			(width 0.2)
			(type default)
		)
		(layer "In6.Cu")
	)
	(gr_arc
		(start 284.236668 -145.243042)
		(mid 284.785308 -144.694402)
		(end 284.236668 -144.145762)
		(stroke
			(width 0.2)
			(type default)
		)
		(layer "In6.Cu")
	)
	(gr_line
		(start 284.236668 -144.145762)
		(end 282.83662 -144.145762)
		(stroke
			(width 0.2)
			(type default)
		)
		(layer "In6.Cu")
	)
	(gr_line
		(start 285.436564 -237.44301)
		(end 286.836612 -237.44301)
		(stroke
			(width 0.2)
			(type default)
		)
		(layer "In6.Cu")
	)
	(gr_arc
		(start 285.436564 -236.34573)
		(mid 284.887924 -236.89437)
		(end 285.436564 -237.44301)
		(stroke
			(width 0.2)
			(type default)
		)
		(layer "In6.Cu")
	)
	(gr_line
		(start 285.436564 -233.843068)
		(end 286.836612 -233.843068)
		(stroke
			(width 0.2)
			(type default)
		)
		(layer "In6.Cu")
	)
	(gr_arc
		(start 285.436564 -232.745788)
		(mid 284.887924 -233.294428)
		(end 285.436564 -233.843068)
		(stroke
			(width 0.2)
			(type default)
		)
		(layer "In6.Cu")
	)
	(gr_line
		(start 285.436564 -230.243126)
		(end 286.836612 -230.243126)
		(stroke
			(width 0.2)
			(type default)
		)
		(layer "In6.Cu")
	)
	(gr_arc
		(start 285.436564 -229.145846)
		(mid 284.887924 -229.694486)
		(end 285.436564 -230.243126)
		(stroke
			(width 0.2)
			(type default)
		)
		(layer "In6.Cu")
	)
	(gr_line
		(start 285.436564 -226.643184)
		(end 286.836612 -226.643184)
		(stroke
			(width 0.2)
			(type default)
		)
		(layer "In6.Cu")
	)
	(gr_arc
		(start 285.436564 -225.545904)
		(mid 284.887924 -226.094544)
		(end 285.436564 -226.643184)
		(stroke
			(width 0.2)
			(type default)
		)
		(layer "In6.Cu")
	)
	(gr_line
		(start 285.436564 -223.042988)
		(end 286.836612 -223.042988)
		(stroke
			(width 0.2)
			(type default)
		)
		(layer "In6.Cu")
	)
	(gr_arc
		(start 285.436564 -221.945708)
		(mid 284.887924 -222.494348)
		(end 285.436564 -223.042988)
		(stroke
			(width 0.2)
			(type default)
		)
		(layer "In6.Cu")
	)
	(gr_line
		(start 285.436564 -219.443046)
		(end 286.836612 -219.443046)
		(stroke
			(width 0.2)
			(type default)
		)
		(layer "In6.Cu")
	)
	(gr_arc
		(start 285.436564 -218.345766)
		(mid 284.887924 -218.894406)
		(end 285.436564 -219.443046)
		(stroke
			(width 0.2)
			(type default)
		)
		(layer "In6.Cu")
	)
	(gr_line
		(start 285.436564 -215.843104)
		(end 286.836612 -215.843104)
		(stroke
			(width 0.2)
			(type default)
		)
		(layer "In6.Cu")
	)
	(gr_arc
		(start 285.436564 -214.745824)
		(mid 284.887924 -215.294464)
		(end 285.436564 -215.843104)
		(stroke
			(width 0.2)
			(type default)
		)
		(layer "In6.Cu")
	)
	(gr_line
		(start 285.436564 -212.243162)
		(end 286.836612 -212.243162)
		(stroke
			(width 0.2)
			(type default)
		)
		(layer "In6.Cu")
	)
	(gr_arc
		(start 285.436564 -211.145882)
		(mid 284.887924 -211.694522)
		(end 285.436564 -212.243162)
		(stroke
			(width 0.2)
			(type default)
		)
		(layer "In6.Cu")
	)
	(gr_line
		(start 285.436564 -208.64322)
		(end 286.836612 -208.64322)
		(stroke
			(width 0.2)
			(type default)
		)
		(layer "In6.Cu")
	)
	(gr_arc
		(start 285.436564 -207.54594)
		(mid 284.887924 -208.09458)
		(end 285.436564 -208.64322)
		(stroke
			(width 0.2)
			(type default)
		)
		(layer "In6.Cu")
	)
	(gr_line
		(start 285.436564 -205.043024)
		(end 286.836612 -205.043024)
		(stroke
			(width 0.2)
			(type default)
		)
		(layer "In6.Cu")
	)
	(gr_arc
		(start 285.436564 -203.945744)
		(mid 284.887924 -204.494384)
		(end 285.436564 -205.043024)
		(stroke
			(width 0.2)
			(type default)
		)
		(layer "In6.Cu")
	)
	(gr_line
		(start 285.436564 -201.443082)
		(end 286.836612 -201.443082)
		(stroke
			(width 0.2)
			(type default)
		)
		(layer "In6.Cu")
	)
	(gr_arc
		(start 285.436564 -200.345802)
		(mid 284.887924 -200.894442)
		(end 285.436564 -201.443082)
		(stroke
			(width 0.2)
			(type default)
		)
		(layer "In6.Cu")
	)
	(gr_line
		(start 285.436564 -197.84314)
		(end 286.836612 -197.84314)
		(stroke
			(width 0.2)
			(type default)
		)
		(layer "In6.Cu")
	)
	(gr_arc
		(start 285.436564 -196.74586)
		(mid 284.887924 -197.2945)
		(end 285.436564 -197.84314)
		(stroke
			(width 0.2)
			(type default)
		)
		(layer "In6.Cu")
	)
	(gr_line
		(start 285.436564 -194.243198)
		(end 286.836612 -194.243198)
		(stroke
			(width 0.2)
			(type default)
		)
		(layer "In6.Cu")
	)
	(gr_arc
		(start 285.436564 -193.145918)
		(mid 284.887924 -193.694558)
		(end 285.436564 -194.243198)
		(stroke
			(width 0.2)
			(type default)
		)
		(layer "In6.Cu")
	)
	(gr_line
		(start 285.436564 -190.643002)
		(end 286.836612 -190.643002)
		(stroke
			(width 0.2)
			(type default)
		)
		(layer "In6.Cu")
	)
	(gr_arc
		(start 285.436564 -189.545722)
		(mid 284.887924 -190.094362)
		(end 285.436564 -190.643002)
		(stroke
			(width 0.2)
			(type default)
		)
		(layer "In6.Cu")
	)
	(gr_line
		(start 285.436564 -187.04306)
		(end 286.836612 -187.04306)
		(stroke
			(width 0.2)
			(type default)
		)
		(layer "In6.Cu")
	)
	(gr_arc
		(start 285.436564 -185.94578)
		(mid 284.887924 -186.49442)
		(end 285.436564 -187.04306)
		(stroke
			(width 0.2)
			(type default)
		)
		(layer "In6.Cu")
	)
	(gr_line
		(start 285.436564 -183.443118)
		(end 286.836612 -183.443118)
		(stroke
			(width 0.2)
			(type default)
		)
		(layer "In6.Cu")
	)
	(gr_arc
		(start 285.436564 -182.345838)
		(mid 284.887924 -182.894478)
		(end 285.436564 -183.443118)
		(stroke
			(width 0.2)
			(type default)
		)
		(layer "In6.Cu")
	)
	(gr_line
		(start 285.436564 -179.843176)
		(end 286.836612 -179.843176)
		(stroke
			(width 0.2)
			(type default)
		)
		(layer "In6.Cu")
	)
	(gr_arc
		(start 285.436564 -178.745896)
		(mid 284.887924 -179.294536)
		(end 285.436564 -179.843176)
		(stroke
			(width 0.2)
			(type default)
		)
		(layer "In6.Cu")
	)
	(gr_line
		(start 285.436564 -176.243234)
		(end 286.836612 -176.243234)
		(stroke
			(width 0.2)
			(type default)
		)
		(layer "In6.Cu")
	)
	(gr_arc
		(start 285.436564 -175.145954)
		(mid 284.887924 -175.694594)
		(end 285.436564 -176.243234)
		(stroke
			(width 0.2)
			(type default)
		)
		(layer "In6.Cu")
	)
	(gr_line
		(start 285.436564 -143.442944)
		(end 286.836612 -143.442944)
		(stroke
			(width 0.2)
			(type default)
		)
		(layer "In6.Cu")
	)
	(gr_arc
		(start 285.436564 -142.345664)
		(mid 284.887924 -142.894304)
		(end 285.436564 -143.442944)
		(stroke
			(width 0.2)
			(type default)
		)
		(layer "In6.Cu")
	)
	(gr_line
		(start 285.436564 -139.843002)
		(end 286.836612 -139.843002)
		(stroke
			(width 0.2)
			(type default)
		)
		(layer "In6.Cu")
	)
	(gr_arc
		(start 285.436564 -138.745722)
		(mid 284.887924 -139.294362)
		(end 285.436564 -139.843002)
		(stroke
			(width 0.2)
			(type default)
		)
		(layer "In6.Cu")
	)
	(gr_line
		(start 285.436564 -136.24306)
		(end 286.836612 -136.24306)
		(stroke
			(width 0.2)
			(type default)
		)
		(layer "In6.Cu")
	)
	(gr_arc
		(start 285.436564 -135.14578)
		(mid 284.887924 -135.69442)
		(end 285.436564 -136.24306)
		(stroke
			(width 0.2)
			(type default)
		)
		(layer "In6.Cu")
	)
	(gr_line
		(start 285.436564 -132.643118)
		(end 286.836612 -132.643118)
		(stroke
			(width 0.2)
			(type default)
		)
		(layer "In6.Cu")
	)
	(gr_arc
		(start 285.436564 -131.545838)
		(mid 284.887924 -132.094478)
		(end 285.436564 -132.643118)
		(stroke
			(width 0.2)
			(type default)
		)
		(layer "In6.Cu")
	)
	(gr_line
		(start 286.436562 -239.243108)
		(end 287.83661 -239.243108)
		(stroke
			(width 0.2)
			(type default)
		)
		(layer "In6.Cu")
	)
	(gr_arc
		(start 286.436562 -238.145828)
		(mid 285.887922 -238.694468)
		(end 286.436562 -239.243108)
		(stroke
			(width 0.2)
			(type default)
		)
		(layer "In6.Cu")
	)
	(gr_line
		(start 286.436562 -235.643166)
		(end 287.83661 -235.643166)
		(stroke
			(width 0.2)
			(type default)
		)
		(layer "In6.Cu")
	)
	(gr_arc
		(start 286.436562 -234.545886)
		(mid 285.887922 -235.094526)
		(end 286.436562 -235.643166)
		(stroke
			(width 0.2)
			(type default)
		)
		(layer "In6.Cu")
	)
	(gr_line
		(start 286.436562 -232.043224)
		(end 287.83661 -232.043224)
		(stroke
			(width 0.2)
			(type default)
		)
		(layer "In6.Cu")
	)
	(gr_arc
		(start 286.436562 -230.945944)
		(mid 285.887922 -231.494584)
		(end 286.436562 -232.043224)
		(stroke
			(width 0.2)
			(type default)
		)
		(layer "In6.Cu")
	)
	(gr_line
		(start 286.436562 -228.443028)
		(end 287.83661 -228.443028)
		(stroke
			(width 0.2)
			(type default)
		)
		(layer "In6.Cu")
	)
	(gr_arc
		(start 286.436562 -227.345748)
		(mid 285.887922 -227.894388)
		(end 286.436562 -228.443028)
		(stroke
			(width 0.2)
			(type default)
		)
		(layer "In6.Cu")
	)
	(gr_line
		(start 286.436562 -224.906586)
		(end 287.83661 -224.906586)
		(stroke
			(width 0.2)
			(type default)
		)
		(layer "In6.Cu")
	)
	(gr_arc
		(start 286.436562 -223.682306)
		(mid 285.824422 -224.294446)
		(end 286.436562 -224.906586)
		(stroke
			(width 0.2)
			(type default)
		)
		(layer "In6.Cu")
	)
	(gr_line
		(start 286.436562 -221.243144)
		(end 287.83661 -221.243144)
		(stroke
			(width 0.2)
			(type default)
		)
		(layer "In6.Cu")
	)
	(gr_arc
		(start 286.436562 -220.145864)
		(mid 285.887922 -220.694504)
		(end 286.436562 -221.243144)
		(stroke
			(width 0.2)
			(type default)
		)
		(layer "In6.Cu")
	)
	(gr_line
		(start 286.436562 -217.643202)
		(end 287.83661 -217.643202)
		(stroke
			(width 0.2)
			(type default)
		)
		(layer "In6.Cu")
	)
	(gr_arc
		(start 286.436562 -216.545922)
		(mid 285.887922 -217.094562)
		(end 286.436562 -217.643202)
		(stroke
			(width 0.2)
			(type default)
		)
		(layer "In6.Cu")
	)
	(gr_line
		(start 286.436562 -214.043006)
		(end 287.83661 -214.043006)
		(stroke
			(width 0.2)
			(type default)
		)
		(layer "In6.Cu")
	)
	(gr_arc
		(start 286.436562 -212.945726)
		(mid 285.887922 -213.494366)
		(end 286.436562 -214.043006)
		(stroke
			(width 0.2)
			(type default)
		)
		(layer "In6.Cu")
	)
	(gr_line
		(start 286.436562 -210.443064)
		(end 287.83661 -210.443064)
		(stroke
			(width 0.2)
			(type default)
		)
		(layer "In6.Cu")
	)
	(gr_arc
		(start 286.436562 -209.345784)
		(mid 285.887922 -209.894424)
		(end 286.436562 -210.443064)
		(stroke
			(width 0.2)
			(type default)
		)
		(layer "In6.Cu")
	)
	(gr_line
		(start 286.436562 -206.843122)
		(end 287.83661 -206.843122)
		(stroke
			(width 0.2)
			(type default)
		)
		(layer "In6.Cu")
	)
	(gr_arc
		(start 286.436562 -205.745842)
		(mid 285.887922 -206.294482)
		(end 286.436562 -206.843122)
		(stroke
			(width 0.2)
			(type default)
		)
		(layer "In6.Cu")
	)
	(gr_line
		(start 286.436562 -203.24318)
		(end 287.83661 -203.24318)
		(stroke
			(width 0.2)
			(type default)
		)
		(layer "In6.Cu")
	)
	(gr_arc
		(start 286.436562 -202.1459)
		(mid 285.887922 -202.69454)
		(end 286.436562 -203.24318)
		(stroke
			(width 0.2)
			(type default)
		)
		(layer "In6.Cu")
	)
	(gr_line
		(start 286.436562 -199.642984)
		(end 287.83661 -199.642984)
		(stroke
			(width 0.2)
			(type default)
		)
		(layer "In6.Cu")
	)
	(gr_arc
		(start 286.436562 -198.545704)
		(mid 285.887922 -199.094344)
		(end 286.436562 -199.642984)
		(stroke
			(width 0.2)
			(type default)
		)
		(layer "In6.Cu")
	)
	(gr_line
		(start 286.436562 -196.043042)
		(end 287.83661 -196.043042)
		(stroke
			(width 0.2)
			(type default)
		)
		(layer "In6.Cu")
	)
	(gr_arc
		(start 286.436562 -194.945762)
		(mid 285.887922 -195.494402)
		(end 286.436562 -196.043042)
		(stroke
			(width 0.2)
			(type default)
		)
		(layer "In6.Cu")
	)
	(gr_line
		(start 286.436562 -192.4431)
		(end 287.83661 -192.4431)
		(stroke
			(width 0.2)
			(type default)
		)
		(layer "In6.Cu")
	)
	(gr_arc
		(start 286.436562 -191.34582)
		(mid 285.887922 -191.89446)
		(end 286.436562 -192.4431)
		(stroke
			(width 0.2)
			(type default)
		)
		(layer "In6.Cu")
	)
	(gr_line
		(start 286.436562 -188.843158)
		(end 287.83661 -188.843158)
		(stroke
			(width 0.2)
			(type default)
		)
		(layer "In6.Cu")
	)
	(gr_arc
		(start 286.436562 -187.745878)
		(mid 285.887922 -188.294518)
		(end 286.436562 -188.843158)
		(stroke
			(width 0.2)
			(type default)
		)
		(layer "In6.Cu")
	)
	(gr_line
		(start 286.436562 -185.243216)
		(end 287.83661 -185.243216)
		(stroke
			(width 0.2)
			(type default)
		)
		(layer "In6.Cu")
	)
	(gr_arc
		(start 286.436562 -184.145936)
		(mid 285.887922 -184.694576)
		(end 286.436562 -185.243216)
		(stroke
			(width 0.2)
			(type default)
		)
		(layer "In6.Cu")
	)
	(gr_line
		(start 286.436562 -181.64302)
		(end 287.83661 -181.64302)
		(stroke
			(width 0.2)
			(type default)
		)
		(layer "In6.Cu")
	)
	(gr_arc
		(start 286.436562 -180.54574)
		(mid 285.887922 -181.09438)
		(end 286.436562 -181.64302)
		(stroke
			(width 0.2)
			(type default)
		)
		(layer "In6.Cu")
	)
	(gr_line
		(start 286.436562 -178.043078)
		(end 287.83661 -178.043078)
		(stroke
			(width 0.2)
			(type default)
		)
		(layer "In6.Cu")
	)
	(gr_arc
		(start 286.436562 -176.945798)
		(mid 285.887922 -177.494438)
		(end 286.436562 -178.043078)
		(stroke
			(width 0.2)
			(type default)
		)
		(layer "In6.Cu")
	)
	(gr_line
		(start 286.436562 -145.243042)
		(end 287.83661 -145.243042)
		(stroke
			(width 0.2)
			(type default)
		)
		(layer "In6.Cu")
	)
	(gr_arc
		(start 286.436562 -144.145762)
		(mid 285.887922 -144.694402)
		(end 286.436562 -145.243042)
		(stroke
			(width 0.2)
			(type default)
		)
		(layer "In6.Cu")
	)
	(gr_line
		(start 286.436562 -141.6431)
		(end 287.83661 -141.6431)
		(stroke
			(width 0.2)
			(type default)
		)
		(layer "In6.Cu")
	)
	(gr_arc
		(start 286.436562 -140.54582)
		(mid 285.887922 -141.09446)
		(end 286.436562 -141.6431)
		(stroke
			(width 0.2)
			(type default)
		)
		(layer "In6.Cu")
	)
	(gr_line
		(start 286.436562 -138.043158)
		(end 287.83661 -138.043158)
		(stroke
			(width 0.2)
			(type default)
		)
		(layer "In6.Cu")
	)
	(gr_arc
		(start 286.436562 -136.945878)
		(mid 285.887922 -137.494518)
		(end 286.436562 -138.043158)
		(stroke
			(width 0.2)
			(type default)
		)
		(layer "In6.Cu")
	)
	(gr_line
		(start 286.436562 -134.442962)
		(end 287.83661 -134.442962)
		(stroke
			(width 0.2)
			(type default)
		)
		(layer "In6.Cu")
	)
	(gr_arc
		(start 286.436562 -133.345682)
		(mid 285.887922 -133.894322)
		(end 286.436562 -134.442962)
		(stroke
			(width 0.2)
			(type default)
		)
		(layer "In6.Cu")
	)
	(gr_line
		(start 286.436816 -223.682306)
		(end 286.436562 -223.682306)
		(stroke
			(width 0.2)
			(type default)
		)
		(layer "In6.Cu")
	)
	(gr_arc
		(start 286.836612 -237.44301)
		(mid 287.385252 -236.89437)
		(end 286.836612 -236.34573)
		(stroke
			(width 0.2)
			(type default)
		)
		(layer "In6.Cu")
	)
	(gr_line
		(start 286.836612 -236.34573)
		(end 285.436564 -236.34573)
		(stroke
			(width 0.2)
			(type default)
		)
		(layer "In6.Cu")
	)
	(gr_arc
		(start 286.836612 -233.843068)
		(mid 287.385252 -233.294428)
		(end 286.836612 -232.745788)
		(stroke
			(width 0.2)
			(type default)
		)
		(layer "In6.Cu")
	)
	(gr_line
		(start 286.836612 -232.745788)
		(end 285.436564 -232.745788)
		(stroke
			(width 0.2)
			(type default)
		)
		(layer "In6.Cu")
	)
	(gr_arc
		(start 286.836612 -230.243126)
		(mid 287.385252 -229.694486)
		(end 286.836612 -229.145846)
		(stroke
			(width 0.2)
			(type default)
		)
		(layer "In6.Cu")
	)
	(gr_line
		(start 286.836612 -229.145846)
		(end 285.436564 -229.145846)
		(stroke
			(width 0.2)
			(type default)
		)
		(layer "In6.Cu")
	)
	(gr_arc
		(start 286.836612 -226.643184)
		(mid 287.385252 -226.094544)
		(end 286.836612 -225.545904)
		(stroke
			(width 0.2)
			(type default)
		)
		(layer "In6.Cu")
	)
	(gr_line
		(start 286.836612 -225.545904)
		(end 285.436564 -225.545904)
		(stroke
			(width 0.2)
			(type default)
		)
		(layer "In6.Cu")
	)
	(gr_arc
		(start 286.836612 -223.042988)
		(mid 287.385252 -222.494348)
		(end 286.836612 -221.945708)
		(stroke
			(width 0.2)
			(type default)
		)
		(layer "In6.Cu")
	)
	(gr_line
		(start 286.836612 -221.945708)
		(end 285.436564 -221.945708)
		(stroke
			(width 0.2)
			(type default)
		)
		(layer "In6.Cu")
	)
	(gr_arc
		(start 286.836612 -219.443046)
		(mid 287.385252 -218.894406)
		(end 286.836612 -218.345766)
		(stroke
			(width 0.2)
			(type default)
		)
		(layer "In6.Cu")
	)
	(gr_line
		(start 286.836612 -218.345766)
		(end 285.436564 -218.345766)
		(stroke
			(width 0.2)
			(type default)
		)
		(layer "In6.Cu")
	)
	(gr_arc
		(start 286.836612 -215.843104)
		(mid 287.385252 -215.294464)
		(end 286.836612 -214.745824)
		(stroke
			(width 0.2)
			(type default)
		)
		(layer "In6.Cu")
	)
	(gr_line
		(start 286.836612 -214.745824)
		(end 285.436564 -214.745824)
		(stroke
			(width 0.2)
			(type default)
		)
		(layer "In6.Cu")
	)
	(gr_arc
		(start 286.836612 -212.243162)
		(mid 287.385252 -211.694522)
		(end 286.836612 -211.145882)
		(stroke
			(width 0.2)
			(type default)
		)
		(layer "In6.Cu")
	)
	(gr_line
		(start 286.836612 -211.145882)
		(end 285.436564 -211.145882)
		(stroke
			(width 0.2)
			(type default)
		)
		(layer "In6.Cu")
	)
	(gr_arc
		(start 286.836612 -208.64322)
		(mid 287.385252 -208.09458)
		(end 286.836612 -207.54594)
		(stroke
			(width 0.2)
			(type default)
		)
		(layer "In6.Cu")
	)
	(gr_line
		(start 286.836612 -207.54594)
		(end 285.436564 -207.54594)
		(stroke
			(width 0.2)
			(type default)
		)
		(layer "In6.Cu")
	)
	(gr_arc
		(start 286.836612 -205.043024)
		(mid 287.385252 -204.494384)
		(end 286.836612 -203.945744)
		(stroke
			(width 0.2)
			(type default)
		)
		(layer "In6.Cu")
	)
	(gr_line
		(start 286.836612 -203.945744)
		(end 285.436564 -203.945744)
		(stroke
			(width 0.2)
			(type default)
		)
		(layer "In6.Cu")
	)
	(gr_arc
		(start 286.836612 -201.443082)
		(mid 287.385252 -200.894442)
		(end 286.836612 -200.345802)
		(stroke
			(width 0.2)
			(type default)
		)
		(layer "In6.Cu")
	)
	(gr_line
		(start 286.836612 -200.345802)
		(end 285.436564 -200.345802)
		(stroke
			(width 0.2)
			(type default)
		)
		(layer "In6.Cu")
	)
	(gr_arc
		(start 286.836612 -197.84314)
		(mid 287.385252 -197.2945)
		(end 286.836612 -196.74586)
		(stroke
			(width 0.2)
			(type default)
		)
		(layer "In6.Cu")
	)
	(gr_line
		(start 286.836612 -196.74586)
		(end 285.436564 -196.74586)
		(stroke
			(width 0.2)
			(type default)
		)
		(layer "In6.Cu")
	)
	(gr_arc
		(start 286.836612 -194.243198)
		(mid 287.385252 -193.694558)
		(end 286.836612 -193.145918)
		(stroke
			(width 0.2)
			(type default)
		)
		(layer "In6.Cu")
	)
	(gr_line
		(start 286.836612 -193.145918)
		(end 285.436564 -193.145918)
		(stroke
			(width 0.2)
			(type default)
		)
		(layer "In6.Cu")
	)
	(gr_arc
		(start 286.836612 -190.643002)
		(mid 287.385252 -190.094362)
		(end 286.836612 -189.545722)
		(stroke
			(width 0.2)
			(type default)
		)
		(layer "In6.Cu")
	)
	(gr_line
		(start 286.836612 -189.545722)
		(end 285.436564 -189.545722)
		(stroke
			(width 0.2)
			(type default)
		)
		(layer "In6.Cu")
	)
	(gr_arc
		(start 286.836612 -187.04306)
		(mid 287.385252 -186.49442)
		(end 286.836612 -185.94578)
		(stroke
			(width 0.2)
			(type default)
		)
		(layer "In6.Cu")
	)
	(gr_line
		(start 286.836612 -185.94578)
		(end 285.436564 -185.94578)
		(stroke
			(width 0.2)
			(type default)
		)
		(layer "In6.Cu")
	)
	(gr_arc
		(start 286.836612 -183.443118)
		(mid 287.385252 -182.894478)
		(end 286.836612 -182.345838)
		(stroke
			(width 0.2)
			(type default)
		)
		(layer "In6.Cu")
	)
	(gr_line
		(start 286.836612 -182.345838)
		(end 285.436564 -182.345838)
		(stroke
			(width 0.2)
			(type default)
		)
		(layer "In6.Cu")
	)
	(gr_arc
		(start 286.836612 -179.843176)
		(mid 287.385252 -179.294536)
		(end 286.836612 -178.745896)
		(stroke
			(width 0.2)
			(type default)
		)
		(layer "In6.Cu")
	)
	(gr_line
		(start 286.836612 -178.745896)
		(end 285.436564 -178.745896)
		(stroke
			(width 0.2)
			(type default)
		)
		(layer "In6.Cu")
	)
	(gr_arc
		(start 286.836612 -176.243234)
		(mid 287.385252 -175.694594)
		(end 286.836612 -175.145954)
		(stroke
			(width 0.2)
			(type default)
		)
		(layer "In6.Cu")
	)
	(gr_line
		(start 286.836612 -175.145954)
		(end 285.436564 -175.145954)
		(stroke
			(width 0.2)
			(type default)
		)
		(layer "In6.Cu")
	)
	(gr_arc
		(start 286.836612 -143.442944)
		(mid 287.385252 -142.894304)
		(end 286.836612 -142.345664)
		(stroke
			(width 0.2)
			(type default)
		)
		(layer "In6.Cu")
	)
	(gr_line
		(start 286.836612 -142.345664)
		(end 285.436564 -142.345664)
		(stroke
			(width 0.2)
			(type default)
		)
		(layer "In6.Cu")
	)
	(gr_arc
		(start 286.836612 -139.843002)
		(mid 287.385252 -139.294362)
		(end 286.836612 -138.745722)
		(stroke
			(width 0.2)
			(type default)
		)
		(layer "In6.Cu")
	)
	(gr_line
		(start 286.836612 -138.745722)
		(end 285.436564 -138.745722)
		(stroke
			(width 0.2)
			(type default)
		)
		(layer "In6.Cu")
	)
	(gr_arc
		(start 286.836612 -136.24306)
		(mid 287.385252 -135.69442)
		(end 286.836612 -135.14578)
		(stroke
			(width 0.2)
			(type default)
		)
		(layer "In6.Cu")
	)
	(gr_line
		(start 286.836612 -135.14578)
		(end 285.436564 -135.14578)
		(stroke
			(width 0.2)
			(type default)
		)
		(layer "In6.Cu")
	)
	(gr_arc
		(start 286.836612 -132.643118)
		(mid 287.385252 -132.094478)
		(end 286.836612 -131.545838)
		(stroke
			(width 0.2)
			(type default)
		)
		(layer "In6.Cu")
	)
	(gr_line
		(start 286.836612 -131.545838)
		(end 285.436564 -131.545838)
		(stroke
			(width 0.2)
			(type default)
		)
		(layer "In6.Cu")
	)
	(gr_arc
		(start 287.83661 -239.243108)
		(mid 288.38525 -238.694468)
		(end 287.83661 -238.145828)
		(stroke
			(width 0.2)
			(type default)
		)
		(layer "In6.Cu")
	)
	(gr_line
		(start 287.83661 -238.145828)
		(end 286.436562 -238.145828)
		(stroke
			(width 0.2)
			(type default)
		)
		(layer "In6.Cu")
	)
	(gr_arc
		(start 287.83661 -235.643166)
		(mid 288.38525 -235.094526)
		(end 287.83661 -234.545886)
		(stroke
			(width 0.2)
			(type default)
		)
		(layer "In6.Cu")
	)
	(gr_line
		(start 287.83661 -234.545886)
		(end 286.436562 -234.545886)
		(stroke
			(width 0.2)
			(type default)
		)
		(layer "In6.Cu")
	)
	(gr_arc
		(start 287.83661 -232.043224)
		(mid 288.38525 -231.494584)
		(end 287.83661 -230.945944)
		(stroke
			(width 0.2)
			(type default)
		)
		(layer "In6.Cu")
	)
	(gr_line
		(start 287.83661 -230.945944)
		(end 286.436562 -230.945944)
		(stroke
			(width 0.2)
			(type default)
		)
		(layer "In6.Cu")
	)
	(gr_arc
		(start 287.83661 -228.443028)
		(mid 288.38525 -227.894388)
		(end 287.83661 -227.345748)
		(stroke
			(width 0.2)
			(type default)
		)
		(layer "In6.Cu")
	)
	(gr_line
		(start 287.83661 -227.345748)
		(end 286.436562 -227.345748)
		(stroke
			(width 0.2)
			(type default)
		)
		(layer "In6.Cu")
	)
	(gr_arc
		(start 287.83661 -224.906586)
		(mid 288.44875 -224.294446)
		(end 287.83661 -223.682306)
		(stroke
			(width 0.2)
			(type default)
		)
		(layer "In6.Cu")
	)
	(gr_line
		(start 287.83661 -223.682306)
		(end 286.436816 -223.682306)
		(stroke
			(width 0.2)
			(type default)
		)
		(layer "In6.Cu")
	)
	(gr_arc
		(start 287.83661 -221.243144)
		(mid 288.38525 -220.694504)
		(end 287.83661 -220.145864)
		(stroke
			(width 0.2)
			(type default)
		)
		(layer "In6.Cu")
	)
	(gr_line
		(start 287.83661 -220.145864)
		(end 286.436562 -220.145864)
		(stroke
			(width 0.2)
			(type default)
		)
		(layer "In6.Cu")
	)
	(gr_arc
		(start 287.83661 -217.643202)
		(mid 288.38525 -217.094562)
		(end 287.83661 -216.545922)
		(stroke
			(width 0.2)
			(type default)
		)
		(layer "In6.Cu")
	)
	(gr_line
		(start 287.83661 -216.545922)
		(end 286.436562 -216.545922)
		(stroke
			(width 0.2)
			(type default)
		)
		(layer "In6.Cu")
	)
	(gr_arc
		(start 287.83661 -214.043006)
		(mid 288.38525 -213.494366)
		(end 287.83661 -212.945726)
		(stroke
			(width 0.2)
			(type default)
		)
		(layer "In6.Cu")
	)
	(gr_line
		(start 287.83661 -212.945726)
		(end 286.436562 -212.945726)
		(stroke
			(width 0.2)
			(type default)
		)
		(layer "In6.Cu")
	)
	(gr_arc
		(start 287.83661 -210.443064)
		(mid 288.38525 -209.894424)
		(end 287.83661 -209.345784)
		(stroke
			(width 0.2)
			(type default)
		)
		(layer "In6.Cu")
	)
	(gr_line
		(start 287.83661 -209.345784)
		(end 286.436562 -209.345784)
		(stroke
			(width 0.2)
			(type default)
		)
		(layer "In6.Cu")
	)
	(gr_arc
		(start 287.83661 -206.843122)
		(mid 288.38525 -206.294482)
		(end 287.83661 -205.745842)
		(stroke
			(width 0.2)
			(type default)
		)
		(layer "In6.Cu")
	)
	(gr_line
		(start 287.83661 -205.745842)
		(end 286.436562 -205.745842)
		(stroke
			(width 0.2)
			(type default)
		)
		(layer "In6.Cu")
	)
	(gr_arc
		(start 287.83661 -203.24318)
		(mid 288.38525 -202.69454)
		(end 287.83661 -202.1459)
		(stroke
			(width 0.2)
			(type default)
		)
		(layer "In6.Cu")
	)
	(gr_line
		(start 287.83661 -202.1459)
		(end 286.436562 -202.1459)
		(stroke
			(width 0.2)
			(type default)
		)
		(layer "In6.Cu")
	)
	(gr_arc
		(start 287.83661 -199.642984)
		(mid 288.38525 -199.094344)
		(end 287.83661 -198.545704)
		(stroke
			(width 0.2)
			(type default)
		)
		(layer "In6.Cu")
	)
	(gr_line
		(start 287.83661 -198.545704)
		(end 286.436562 -198.545704)
		(stroke
			(width 0.2)
			(type default)
		)
		(layer "In6.Cu")
	)
	(gr_arc
		(start 287.83661 -196.043042)
		(mid 288.38525 -195.494402)
		(end 287.83661 -194.945762)
		(stroke
			(width 0.2)
			(type default)
		)
		(layer "In6.Cu")
	)
	(gr_line
		(start 287.83661 -194.945762)
		(end 286.436562 -194.945762)
		(stroke
			(width 0.2)
			(type default)
		)
		(layer "In6.Cu")
	)
	(gr_arc
		(start 287.83661 -192.4431)
		(mid 288.38525 -191.89446)
		(end 287.83661 -191.34582)
		(stroke
			(width 0.2)
			(type default)
		)
		(layer "In6.Cu")
	)
	(gr_line
		(start 287.83661 -191.34582)
		(end 286.436562 -191.34582)
		(stroke
			(width 0.2)
			(type default)
		)
		(layer "In6.Cu")
	)
	(gr_arc
		(start 287.83661 -188.843158)
		(mid 288.38525 -188.294518)
		(end 287.83661 -187.745878)
		(stroke
			(width 0.2)
			(type default)
		)
		(layer "In6.Cu")
	)
	(gr_line
		(start 287.83661 -187.745878)
		(end 286.436562 -187.745878)
		(stroke
			(width 0.2)
			(type default)
		)
		(layer "In6.Cu")
	)
	(gr_arc
		(start 287.83661 -185.243216)
		(mid 288.38525 -184.694576)
		(end 287.83661 -184.145936)
		(stroke
			(width 0.2)
			(type default)
		)
		(layer "In6.Cu")
	)
	(gr_line
		(start 287.83661 -184.145936)
		(end 286.436562 -184.145936)
		(stroke
			(width 0.2)
			(type default)
		)
		(layer "In6.Cu")
	)
	(gr_arc
		(start 287.83661 -181.64302)
		(mid 288.38525 -181.09438)
		(end 287.83661 -180.54574)
		(stroke
			(width 0.2)
			(type default)
		)
		(layer "In6.Cu")
	)
	(gr_line
		(start 287.83661 -180.54574)
		(end 286.436562 -180.54574)
		(stroke
			(width 0.2)
			(type default)
		)
		(layer "In6.Cu")
	)
	(gr_arc
		(start 287.83661 -178.043078)
		(mid 288.38525 -177.494438)
		(end 287.83661 -176.945798)
		(stroke
			(width 0.2)
			(type default)
		)
		(layer "In6.Cu")
	)
	(gr_line
		(start 287.83661 -176.945798)
		(end 286.436562 -176.945798)
		(stroke
			(width 0.2)
			(type default)
		)
		(layer "In6.Cu")
	)
	(gr_arc
		(start 287.83661 -145.243042)
		(mid 288.38525 -144.694402)
		(end 287.83661 -144.145762)
		(stroke
			(width 0.2)
			(type default)
		)
		(layer "In6.Cu")
	)
	(gr_line
		(start 287.83661 -144.145762)
		(end 286.436562 -144.145762)
		(stroke
			(width 0.2)
			(type default)
		)
		(layer "In6.Cu")
	)
	(gr_arc
		(start 287.83661 -141.6431)
		(mid 288.38525 -141.09446)
		(end 287.83661 -140.54582)
		(stroke
			(width 0.2)
			(type default)
		)
		(layer "In6.Cu")
	)
	(gr_line
		(start 287.83661 -140.54582)
		(end 286.436562 -140.54582)
		(stroke
			(width 0.2)
			(type default)
		)
		(layer "In6.Cu")
	)
	(gr_arc
		(start 287.83661 -138.043158)
		(mid 288.38525 -137.494518)
		(end 287.83661 -136.945878)
		(stroke
			(width 0.2)
			(type default)
		)
		(layer "In6.Cu")
	)
	(gr_line
		(start 287.83661 -136.945878)
		(end 286.436562 -136.945878)
		(stroke
			(width 0.2)
			(type default)
		)
		(layer "In6.Cu")
	)
	(gr_arc
		(start 287.83661 -134.442962)
		(mid 288.38525 -133.894322)
		(end 287.83661 -133.345682)
		(stroke
			(width 0.2)
			(type default)
		)
		(layer "In6.Cu")
	)
	(gr_line
		(start 287.83661 -133.345682)
		(end 286.436562 -133.345682)
		(stroke
			(width 0.2)
			(type default)
		)
		(layer "In6.Cu")
	)
	(gr_line
		(start 306.649882 -385.99999)
		(end 280.164286 -385.99999)
		(stroke
			(width 1.524)
			(type default)
		)
		(layer "In6.Cu")
	)
	(gr_arc
		(start 306.649882 -385.99999)
		(mid 307.356996 -385.707103)
		(end 307.64988 -384.999992)
		(stroke
			(width 1.524)
			(type default)
		)
		(layer "In6.Cu")
	)
	(gr_line
		(start 307.64988 -383.29997)
		(end 307.64988 -384.999992)
		(stroke
			(width 1.524)
			(type default)
		)
		(layer "In6.Cu")
	)
	(gr_arc
		(start 308.649878 -382.299972)
		(mid 307.942773 -382.592865)
		(end 307.64988 -383.29997)
		(stroke
			(width 1.524)
			(type default)
		)
		(layer "In6.Cu")
	)
	(gr_arc
		(start 309.999888 -48.200056)
		(mid 310.706993 -47.907163)
		(end 310.999886 -47.200058)
		(stroke
			(width 1.524)
			(type default)
		)
		(layer "In6.Cu")
	)
	(gr_line
		(start 310.999886 -47.200058)
		(end 310.999886 -0.999998)
		(stroke
			(width 1.524)
			(type default)
		)
		(layer "In6.Cu")
	)
	(gr_arc
		(start 311.999884 0)
		(mid 311.292788 -0.292898)
		(end 310.999886 -0.999998)
		(stroke
			(width 1.524)
			(type default)
		)
		(layer "In6.Cu")
	)
	(gr_line
		(start 311.999884 0)
		(end 490.450124 0)
		(stroke
			(width 1.524)
			(type default)
		)
		(layer "In6.Cu")
	)
	(gr_line
		(start 315.149992 -382.299972)
		(end 308.649878 -382.299972)
		(stroke
			(width 1.524)
			(type default)
		)
		(layer "In6.Cu")
	)
	(gr_line
		(start 316.14999 -384.999992)
		(end 316.14999 -383.29997)
		(stroke
			(width 1.524)
			(type default)
		)
		(layer "In6.Cu")
	)
	(gr_arc
		(start 316.14999 -384.999992)
		(mid 316.442879 -385.707107)
		(end 317.149988 -385.99999)
		(stroke
			(width 1.524)
			(type default)
		)
		(layer "In6.Cu")
	)
	(gr_arc
		(start 316.14999 -383.29997)
		(mid 315.857097 -382.592865)
		(end 315.149992 -382.299972)
		(stroke
			(width 1.524)
			(type default)
		)
		(layer "In6.Cu")
	)
	(gr_arc
		(start 318.91732 -245.45544)
		(mid 319.402333 -245.940834)
		(end 319.8876 -245.455694)
		(stroke
			(width 0.2)
			(type default)
		)
		(layer "In6.Cu")
	)
	(gr_line
		(start 318.91732 -244.312694)
		(end 318.91732 -245.45544)
		(stroke
			(width 0.2)
			(type default)
		)
		(layer "In6.Cu")
	)
	(gr_line
		(start 319.2145 -129.112264)
		(end 320.3575 -129.112264)
		(stroke
			(width 0.2)
			(type default)
		)
		(layer "In6.Cu")
	)
	(gr_line
		(start 319.2145 -14.11224)
		(end 320.3575 -14.11224)
		(stroke
			(width 0.2)
			(type default)
		)
		(layer "In6.Cu")
	)
	(gr_arc
		(start 319.214754 -128.141984)
		(mid 318.72936 -128.626997)
		(end 319.2145 -129.112264)
		(stroke
			(width 0.2)
			(type default)
		)
		(layer "In6.Cu")
	)
	(gr_arc
		(start 319.214754 -13.14196)
		(mid 318.72936 -13.626973)
		(end 319.2145 -14.11224)
		(stroke
			(width 0.2)
			(type default)
		)
		(layer "In6.Cu")
	)
	(gr_line
		(start 319.8876 -245.455694)
		(end 319.8876 -244.312694)
		(stroke
			(width 0.2)
			(type default)
		)
		(layer "In6.Cu")
	)
	(gr_arc
		(start 319.8876 -244.312694)
		(mid 319.40246 -243.827554)
		(end 318.91732 -244.312694)
		(stroke
			(width 0.2)
			(type default)
		)
		(layer "In6.Cu")
	)
	(gr_arc
		(start 320.3575 -129.112264)
		(mid 320.84264 -128.627124)
		(end 320.3575 -128.141984)
		(stroke
			(width 0.2)
			(type default)
		)
		(layer "In6.Cu")
	)
	(gr_line
		(start 320.3575 -128.141984)
		(end 319.214754 -128.141984)
		(stroke
			(width 0.2)
			(type default)
		)
		(layer "In6.Cu")
	)
	(gr_arc
		(start 320.3575 -14.11224)
		(mid 320.84264 -13.6271)
		(end 320.3575 -13.14196)
		(stroke
			(width 0.2)
			(type default)
		)
		(layer "In6.Cu")
	)
	(gr_line
		(start 320.3575 -13.14196)
		(end 319.214754 -13.14196)
		(stroke
			(width 0.2)
			(type default)
		)
		(layer "In6.Cu")
	)
	(gr_line
		(start 322.6816 -132.922264)
		(end 323.951346 -132.922264)
		(stroke
			(width 0.2)
			(type default)
		)
		(layer "In6.Cu")
	)
	(gr_arc
		(start 322.6816 -131.951984)
		(mid 322.19646 -132.437124)
		(end 322.6816 -132.922264)
		(stroke
			(width 0.2)
			(type default)
		)
		(layer "In6.Cu")
	)
	(gr_line
		(start 322.6816 -17.92224)
		(end 323.951346 -17.92224)
		(stroke
			(width 0.2)
			(type default)
		)
		(layer "In6.Cu")
	)
	(gr_arc
		(start 322.6816 -16.95196)
		(mid 322.19646 -17.4371)
		(end 322.6816 -17.92224)
		(stroke
			(width 0.2)
			(type default)
		)
		(layer "In6.Cu")
	)
	(gr_arc
		(start 323.10451 -249.385074)
		(mid 323.58965 -249.870214)
		(end 324.07479 -249.385074)
		(stroke
			(width 0.2)
			(type default)
		)
		(layer "In6.Cu")
	)
	(gr_line
		(start 323.10451 -248.115074)
		(end 323.10451 -249.385074)
		(stroke
			(width 0.2)
			(type default)
		)
		(layer "In6.Cu")
	)
	(gr_arc
		(start 323.951346 -132.922264)
		(mid 324.43674 -132.437251)
		(end 323.9516 -131.951984)
		(stroke
			(width 0.2)
			(type default)
		)
		(layer "In6.Cu")
	)
	(gr_arc
		(start 323.951346 -17.92224)
		(mid 324.43674 -17.437227)
		(end 323.9516 -16.95196)
		(stroke
			(width 0.2)
			(type default)
		)
		(layer "In6.Cu")
	)
	(gr_line
		(start 323.9516 -131.951984)
		(end 322.6816 -131.951984)
		(stroke
			(width 0.2)
			(type default)
		)
		(layer "In6.Cu")
	)
	(gr_line
		(start 323.9516 -16.95196)
		(end 322.6816 -16.95196)
		(stroke
			(width 0.2)
			(type default)
		)
		(layer "In6.Cu")
	)
	(gr_line
		(start 324.07479 -249.385074)
		(end 324.07479 -248.115328)
		(stroke
			(width 0.2)
			(type default)
		)
		(layer "In6.Cu")
	)
	(gr_arc
		(start 324.07479 -248.115328)
		(mid 323.589777 -247.629934)
		(end 323.10451 -248.115074)
		(stroke
			(width 0.2)
			(type default)
		)
		(layer "In6.Cu")
	)
	(gr_arc
		(start 350.457262 -245.46052)
		(mid 350.942275 -245.945914)
		(end 351.427542 -245.460774)
		(stroke
			(width 0.2)
			(type default)
		)
		(layer "In6.Cu")
	)
	(gr_line
		(start 350.457262 -244.317774)
		(end 350.457262 -245.46052)
		(stroke
			(width 0.2)
			(type default)
		)
		(layer "In6.Cu")
	)
	(gr_line
		(start 350.764602 -129.112264)
		(end 351.907602 -129.112264)
		(stroke
			(width 0.2)
			(type default)
		)
		(layer "In6.Cu")
	)
	(gr_line
		(start 350.764602 -14.11224)
		(end 351.907602 -14.11224)
		(stroke
			(width 0.2)
			(type default)
		)
		(layer "In6.Cu")
	)
	(gr_arc
		(start 350.764856 -128.141984)
		(mid 350.279462 -128.626997)
		(end 350.764602 -129.112264)
		(stroke
			(width 0.2)
			(type default)
		)
		(layer "In6.Cu")
	)
	(gr_arc
		(start 350.764856 -13.14196)
		(mid 350.279462 -13.626973)
		(end 350.764602 -14.11224)
		(stroke
			(width 0.2)
			(type default)
		)
		(layer "In6.Cu")
	)
	(gr_line
		(start 351.427542 -245.460774)
		(end 351.427542 -244.317774)
		(stroke
			(width 0.2)
			(type default)
		)
		(layer "In6.Cu")
	)
	(gr_arc
		(start 351.427542 -244.317774)
		(mid 350.942402 -243.832634)
		(end 350.457262 -244.317774)
		(stroke
			(width 0.2)
			(type default)
		)
		(layer "In6.Cu")
	)
	(gr_arc
		(start 351.907602 -129.112264)
		(mid 352.392742 -128.627124)
		(end 351.907602 -128.141984)
		(stroke
			(width 0.2)
			(type default)
		)
		(layer "In6.Cu")
	)
	(gr_line
		(start 351.907602 -128.141984)
		(end 350.764856 -128.141984)
		(stroke
			(width 0.2)
			(type default)
		)
		(layer "In6.Cu")
	)
	(gr_arc
		(start 351.907602 -14.11224)
		(mid 352.392742 -13.6271)
		(end 351.907602 -13.14196)
		(stroke
			(width 0.2)
			(type default)
		)
		(layer "In6.Cu")
	)
	(gr_line
		(start 351.907602 -13.14196)
		(end 350.764856 -13.14196)
		(stroke
			(width 0.2)
			(type default)
		)
		(layer "In6.Cu")
	)
	(gr_line
		(start 354.231702 -132.922264)
		(end 355.501702 -132.922264)
		(stroke
			(width 0.2)
			(type default)
		)
		(layer "In6.Cu")
	)
	(gr_line
		(start 354.231702 -17.92224)
		(end 355.501702 -17.92224)
		(stroke
			(width 0.2)
			(type default)
		)
		(layer "In6.Cu")
	)
	(gr_arc
		(start 354.231956 -131.951984)
		(mid 353.746562 -132.436997)
		(end 354.231702 -132.922264)
		(stroke
			(width 0.2)
			(type default)
		)
		(layer "In6.Cu")
	)
	(gr_arc
		(start 354.231956 -16.95196)
		(mid 353.746562 -17.436973)
		(end 354.231702 -17.92224)
		(stroke
			(width 0.2)
			(type default)
		)
		(layer "In6.Cu")
	)
	(gr_arc
		(start 354.654612 -249.385074)
		(mid 355.139752 -249.870214)
		(end 355.624892 -249.385074)
		(stroke
			(width 0.2)
			(type default)
		)
		(layer "In6.Cu")
	)
	(gr_line
		(start 354.654612 -248.115074)
		(end 354.654612 -249.385074)
		(stroke
			(width 0.2)
			(type default)
		)
		(layer "In6.Cu")
	)
	(gr_arc
		(start 355.501702 -132.922264)
		(mid 355.986842 -132.437124)
		(end 355.501702 -131.951984)
		(stroke
			(width 0.2)
			(type default)
		)
		(layer "In6.Cu")
	)
	(gr_line
		(start 355.501702 -131.951984)
		(end 354.231956 -131.951984)
		(stroke
			(width 0.2)
			(type default)
		)
		(layer "In6.Cu")
	)
	(gr_arc
		(start 355.501702 -17.92224)
		(mid 355.986842 -17.4371)
		(end 355.501702 -16.95196)
		(stroke
			(width 0.2)
			(type default)
		)
		(layer "In6.Cu")
	)
	(gr_line
		(start 355.501702 -16.95196)
		(end 354.231956 -16.95196)
		(stroke
			(width 0.2)
			(type default)
		)
		(layer "In6.Cu")
	)
	(gr_line
		(start 355.624892 -249.385074)
		(end 355.624892 -248.115328)
		(stroke
			(width 0.2)
			(type default)
		)
		(layer "In6.Cu")
	)
	(gr_arc
		(start 355.624892 -248.115328)
		(mid 355.139879 -247.629934)
		(end 354.654612 -248.115074)
		(stroke
			(width 0.2)
			(type default)
		)
		(layer "In6.Cu")
	)
	(gr_line
		(start 362.700062 -385.99999)
		(end 317.149988 -385.99999)
		(stroke
			(width 1.524)
			(type default)
		)
		(layer "In6.Cu")
	)
	(gr_arc
		(start 362.700062 -385.99999)
		(mid 363.407189 -385.70711)
		(end 363.70006 -384.999992)
		(stroke
			(width 1.524)
			(type default)
		)
		(layer "In6.Cu")
	)
	(gr_line
		(start 363.70006 -381)
		(end 363.70006 -384.999992)
		(stroke
			(width 1.524)
			(type default)
		)
		(layer "In6.Cu")
	)
	(gr_arc
		(start 364.700058 -380.000002)
		(mid 363.992953 -380.292895)
		(end 363.70006 -381)
		(stroke
			(width 1.524)
			(type default)
		)
		(layer "In6.Cu")
	)
	(gr_arc
		(start 382.00711 -245.44528)
		(mid 382.492123 -245.930674)
		(end 382.97739 -245.445534)
		(stroke
			(width 0.2)
			(type default)
		)
		(layer "In6.Cu")
	)
	(gr_line
		(start 382.00711 -244.302534)
		(end 382.00711 -245.44528)
		(stroke
			(width 0.2)
			(type default)
		)
		(layer "In6.Cu")
	)
	(gr_line
		(start 382.31445 -129.112264)
		(end 383.45745 -129.112264)
		(stroke
			(width 0.2)
			(type default)
		)
		(layer "In6.Cu")
	)
	(gr_line
		(start 382.31445 -14.11224)
		(end 383.45745 -14.11224)
		(stroke
			(width 0.2)
			(type default)
		)
		(layer "In6.Cu")
	)
	(gr_arc
		(start 382.314704 -128.141984)
		(mid 381.82931 -128.626997)
		(end 382.31445 -129.112264)
		(stroke
			(width 0.2)
			(type default)
		)
		(layer "In6.Cu")
	)
	(gr_arc
		(start 382.314704 -13.14196)
		(mid 381.82931 -13.626973)
		(end 382.31445 -14.11224)
		(stroke
			(width 0.2)
			(type default)
		)
		(layer "In6.Cu")
	)
	(gr_line
		(start 382.97739 -245.445534)
		(end 382.97739 -244.302534)
		(stroke
			(width 0.2)
			(type default)
		)
		(layer "In6.Cu")
	)
	(gr_arc
		(start 382.97739 -244.302534)
		(mid 382.49225 -243.817394)
		(end 382.00711 -244.302534)
		(stroke
			(width 0.2)
			(type default)
		)
		(layer "In6.Cu")
	)
	(gr_arc
		(start 383.45745 -129.112264)
		(mid 383.94259 -128.627124)
		(end 383.45745 -128.141984)
		(stroke
			(width 0.2)
			(type default)
		)
		(layer "In6.Cu")
	)
	(gr_line
		(start 383.45745 -128.141984)
		(end 382.314704 -128.141984)
		(stroke
			(width 0.2)
			(type default)
		)
		(layer "In6.Cu")
	)
	(gr_arc
		(start 383.45745 -14.11224)
		(mid 383.94259 -13.6271)
		(end 383.45745 -13.14196)
		(stroke
			(width 0.2)
			(type default)
		)
		(layer "In6.Cu")
	)
	(gr_line
		(start 383.45745 -13.14196)
		(end 382.314704 -13.14196)
		(stroke
			(width 0.2)
			(type default)
		)
		(layer "In6.Cu")
	)
	(gr_line
		(start 385.78155 -132.922264)
		(end 387.051296 -132.922264)
		(stroke
			(width 0.2)
			(type default)
		)
		(layer "In6.Cu")
	)
	(gr_arc
		(start 385.78155 -131.951984)
		(mid 385.29641 -132.437124)
		(end 385.78155 -132.922264)
		(stroke
			(width 0.2)
			(type default)
		)
		(layer "In6.Cu")
	)
	(gr_line
		(start 385.78155 -17.92224)
		(end 387.051296 -17.92224)
		(stroke
			(width 0.2)
			(type default)
		)
		(layer "In6.Cu")
	)
	(gr_arc
		(start 385.78155 -16.95196)
		(mid 385.29641 -17.4371)
		(end 385.78155 -17.92224)
		(stroke
			(width 0.2)
			(type default)
		)
		(layer "In6.Cu")
	)
	(gr_arc
		(start 386.20446 -249.385074)
		(mid 386.6896 -249.870214)
		(end 387.17474 -249.385074)
		(stroke
			(width 0.2)
			(type default)
		)
		(layer "In6.Cu")
	)
	(gr_line
		(start 386.20446 -248.115074)
		(end 386.20446 -249.385074)
		(stroke
			(width 0.2)
			(type default)
		)
		(layer "In6.Cu")
	)
	(gr_arc
		(start 387.051296 -132.922264)
		(mid 387.53669 -132.437251)
		(end 387.05155 -131.951984)
		(stroke
			(width 0.2)
			(type default)
		)
		(layer "In6.Cu")
	)
	(gr_arc
		(start 387.051296 -17.92224)
		(mid 387.53669 -17.437227)
		(end 387.05155 -16.95196)
		(stroke
			(width 0.2)
			(type default)
		)
		(layer "In6.Cu")
	)
	(gr_line
		(start 387.05155 -131.951984)
		(end 385.78155 -131.951984)
		(stroke
			(width 0.2)
			(type default)
		)
		(layer "In6.Cu")
	)
	(gr_line
		(start 387.05155 -16.95196)
		(end 385.78155 -16.95196)
		(stroke
			(width 0.2)
			(type default)
		)
		(layer "In6.Cu")
	)
	(gr_line
		(start 387.17474 -249.385074)
		(end 387.17474 -248.115328)
		(stroke
			(width 0.2)
			(type default)
		)
		(layer "In6.Cu")
	)
	(gr_arc
		(start 387.17474 -248.115328)
		(mid 386.689727 -247.629934)
		(end 386.20446 -248.115074)
		(stroke
			(width 0.2)
			(type default)
		)
		(layer "In6.Cu")
	)
	(gr_arc
		(start 413.557212 -245.58752)
		(mid 414.042225 -246.072914)
		(end 414.527492 -245.587774)
		(stroke
			(width 0.2)
			(type default)
		)
		(layer "In6.Cu")
	)
	(gr_line
		(start 413.557212 -244.444774)
		(end 413.557212 -245.58752)
		(stroke
			(width 0.2)
			(type default)
		)
		(layer "In6.Cu")
	)
	(gr_line
		(start 413.864552 -129.112264)
		(end 415.007552 -129.112264)
		(stroke
			(width 0.2)
			(type default)
		)
		(layer "In6.Cu")
	)
	(gr_line
		(start 413.864552 -14.11224)
		(end 415.007552 -14.11224)
		(stroke
			(width 0.2)
			(type default)
		)
		(layer "In6.Cu")
	)
	(gr_arc
		(start 413.864806 -128.141984)
		(mid 413.379412 -128.626997)
		(end 413.864552 -129.112264)
		(stroke
			(width 0.2)
			(type default)
		)
		(layer "In6.Cu")
	)
	(gr_arc
		(start 413.864806 -13.14196)
		(mid 413.379412 -13.626973)
		(end 413.864552 -14.11224)
		(stroke
			(width 0.2)
			(type default)
		)
		(layer "In6.Cu")
	)
	(gr_line
		(start 414.527492 -245.587774)
		(end 414.527492 -244.444774)
		(stroke
			(width 0.2)
			(type default)
		)
		(layer "In6.Cu")
	)
	(gr_arc
		(start 414.527492 -244.444774)
		(mid 414.042352 -243.959634)
		(end 413.557212 -244.444774)
		(stroke
			(width 0.2)
			(type default)
		)
		(layer "In6.Cu")
	)
	(gr_arc
		(start 415.007552 -129.112264)
		(mid 415.492692 -128.627124)
		(end 415.007552 -128.141984)
		(stroke
			(width 0.2)
			(type default)
		)
		(layer "In6.Cu")
	)
	(gr_line
		(start 415.007552 -128.141984)
		(end 413.864806 -128.141984)
		(stroke
			(width 0.2)
			(type default)
		)
		(layer "In6.Cu")
	)
	(gr_arc
		(start 415.007552 -14.11224)
		(mid 415.492692 -13.6271)
		(end 415.007552 -13.14196)
		(stroke
			(width 0.2)
			(type default)
		)
		(layer "In6.Cu")
	)
	(gr_line
		(start 415.007552 -13.14196)
		(end 413.864806 -13.14196)
		(stroke
			(width 0.2)
			(type default)
		)
		(layer "In6.Cu")
	)
	(gr_line
		(start 416.699954 -380.000002)
		(end 364.700058 -380.000002)
		(stroke
			(width 1.524)
			(type default)
		)
		(layer "In6.Cu")
	)
	(gr_line
		(start 417.331652 -132.922264)
		(end 418.601652 -132.922264)
		(stroke
			(width 0.2)
			(type default)
		)
		(layer "In6.Cu")
	)
	(gr_line
		(start 417.331652 -17.92224)
		(end 418.601652 -17.92224)
		(stroke
			(width 0.2)
			(type default)
		)
		(layer "In6.Cu")
	)
	(gr_arc
		(start 417.331906 -131.951984)
		(mid 416.846512 -132.436997)
		(end 417.331652 -132.922264)
		(stroke
			(width 0.2)
			(type default)
		)
		(layer "In6.Cu")
	)
	(gr_arc
		(start 417.331906 -16.95196)
		(mid 416.846512 -17.436973)
		(end 417.331652 -17.92224)
		(stroke
			(width 0.2)
			(type default)
		)
		(layer "In6.Cu")
	)
	(gr_line
		(start 417.699952 -384.999992)
		(end 417.699952 -381)
		(stroke
			(width 1.524)
			(type default)
		)
		(layer "In6.Cu")
	)
	(gr_arc
		(start 417.699952 -384.999992)
		(mid 417.992839 -385.70712)
		(end 418.69995 -385.99999)
		(stroke
			(width 1.524)
			(type default)
		)
		(layer "In6.Cu")
	)
	(gr_arc
		(start 417.699952 -381)
		(mid 417.407059 -380.292895)
		(end 416.699954 -380.000002)
		(stroke
			(width 1.524)
			(type default)
		)
		(layer "In6.Cu")
	)
	(gr_arc
		(start 417.754562 -249.385074)
		(mid 418.239702 -249.870214)
		(end 418.724842 -249.385074)
		(stroke
			(width 0.2)
			(type default)
		)
		(layer "In6.Cu")
	)
	(gr_line
		(start 417.754562 -248.115074)
		(end 417.754562 -249.385074)
		(stroke
			(width 0.2)
			(type default)
		)
		(layer "In6.Cu")
	)
	(gr_arc
		(start 418.601652 -132.922264)
		(mid 419.086792 -132.437124)
		(end 418.601652 -131.951984)
		(stroke
			(width 0.2)
			(type default)
		)
		(layer "In6.Cu")
	)
	(gr_line
		(start 418.601652 -131.951984)
		(end 417.331906 -131.951984)
		(stroke
			(width 0.2)
			(type default)
		)
		(layer "In6.Cu")
	)
	(gr_arc
		(start 418.601652 -17.92224)
		(mid 419.086792 -17.4371)
		(end 418.601652 -16.95196)
		(stroke
			(width 0.2)
			(type default)
		)
		(layer "In6.Cu")
	)
	(gr_line
		(start 418.601652 -16.95196)
		(end 417.331906 -16.95196)
		(stroke
			(width 0.2)
			(type default)
		)
		(layer "In6.Cu")
	)
	(gr_line
		(start 418.724842 -249.385074)
		(end 418.724842 -248.115328)
		(stroke
			(width 0.2)
			(type default)
		)
		(layer "In6.Cu")
	)
	(gr_arc
		(start 418.724842 -248.115328)
		(mid 418.239829 -247.629934)
		(end 417.754562 -248.115074)
		(stroke
			(width 0.2)
			(type default)
		)
		(layer "In6.Cu")
	)
	(gr_arc
		(start 445.11722 -245.45544)
		(mid 445.602233 -245.940834)
		(end 446.0875 -245.455694)
		(stroke
			(width 0.2)
			(type default)
		)
		(layer "In6.Cu")
	)
	(gr_line
		(start 445.11722 -244.312694)
		(end 445.11722 -245.45544)
		(stroke
			(width 0.2)
			(type default)
		)
		(layer "In6.Cu")
	)
	(gr_line
		(start 445.4144 -129.112264)
		(end 446.5574 -129.112264)
		(stroke
			(width 0.2)
			(type default)
		)
		(layer "In6.Cu")
	)
	(gr_line
		(start 445.4144 -14.11224)
		(end 446.5574 -14.11224)
		(stroke
			(width 0.2)
			(type default)
		)
		(layer "In6.Cu")
	)
	(gr_arc
		(start 445.414654 -128.141984)
		(mid 444.92926 -128.626997)
		(end 445.4144 -129.112264)
		(stroke
			(width 0.2)
			(type default)
		)
		(layer "In6.Cu")
	)
	(gr_arc
		(start 445.414654 -13.14196)
		(mid 444.92926 -13.626973)
		(end 445.4144 -14.11224)
		(stroke
			(width 0.2)
			(type default)
		)
		(layer "In6.Cu")
	)
	(gr_line
		(start 446.0875 -245.455694)
		(end 446.0875 -244.312694)
		(stroke
			(width 0.2)
			(type default)
		)
		(layer "In6.Cu")
	)
	(gr_arc
		(start 446.0875 -244.312694)
		(mid 445.60236 -243.827554)
		(end 445.11722 -244.312694)
		(stroke
			(width 0.2)
			(type default)
		)
		(layer "In6.Cu")
	)
	(gr_arc
		(start 446.5574 -129.112264)
		(mid 447.04254 -128.627124)
		(end 446.5574 -128.141984)
		(stroke
			(width 0.2)
			(type default)
		)
		(layer "In6.Cu")
	)
	(gr_line
		(start 446.5574 -128.141984)
		(end 445.414654 -128.141984)
		(stroke
			(width 0.2)
			(type default)
		)
		(layer "In6.Cu")
	)
	(gr_arc
		(start 446.5574 -14.11224)
		(mid 447.04254 -13.6271)
		(end 446.5574 -13.14196)
		(stroke
			(width 0.2)
			(type default)
		)
		(layer "In6.Cu")
	)
	(gr_line
		(start 446.5574 -13.14196)
		(end 445.414654 -13.14196)
		(stroke
			(width 0.2)
			(type default)
		)
		(layer "In6.Cu")
	)
	(gr_line
		(start 448.8815 -132.922264)
		(end 450.151246 -132.922264)
		(stroke
			(width 0.2)
			(type default)
		)
		(layer "In6.Cu")
	)
	(gr_arc
		(start 448.8815 -131.951984)
		(mid 448.39636 -132.437124)
		(end 448.8815 -132.922264)
		(stroke
			(width 0.2)
			(type default)
		)
		(layer "In6.Cu")
	)
	(gr_line
		(start 448.8815 -17.92224)
		(end 450.151246 -17.92224)
		(stroke
			(width 0.2)
			(type default)
		)
		(layer "In6.Cu")
	)
	(gr_arc
		(start 448.8815 -16.95196)
		(mid 448.39636 -17.4371)
		(end 448.8815 -17.92224)
		(stroke
			(width 0.2)
			(type default)
		)
		(layer "In6.Cu")
	)
	(gr_arc
		(start 449.30441 -249.385074)
		(mid 449.78955 -249.870214)
		(end 450.27469 -249.385074)
		(stroke
			(width 0.2)
			(type default)
		)
		(layer "In6.Cu")
	)
	(gr_line
		(start 449.30441 -248.115074)
		(end 449.30441 -249.385074)
		(stroke
			(width 0.2)
			(type default)
		)
		(layer "In6.Cu")
	)
	(gr_arc
		(start 450.151246 -132.922264)
		(mid 450.63664 -132.437251)
		(end 450.1515 -131.951984)
		(stroke
			(width 0.2)
			(type default)
		)
		(layer "In6.Cu")
	)
	(gr_arc
		(start 450.151246 -17.92224)
		(mid 450.63664 -17.437227)
		(end 450.1515 -16.95196)
		(stroke
			(width 0.2)
			(type default)
		)
		(layer "In6.Cu")
	)
	(gr_line
		(start 450.1515 -131.951984)
		(end 448.8815 -131.951984)
		(stroke
			(width 0.2)
			(type default)
		)
		(layer "In6.Cu")
	)
	(gr_line
		(start 450.1515 -16.95196)
		(end 448.8815 -16.95196)
		(stroke
			(width 0.2)
			(type default)
		)
		(layer "In6.Cu")
	)
	(gr_line
		(start 450.27469 -249.385074)
		(end 450.27469 -248.115328)
		(stroke
			(width 0.2)
			(type default)
		)
		(layer "In6.Cu")
	)
	(gr_arc
		(start 450.27469 -248.115328)
		(mid 449.789677 -247.629934)
		(end 449.30441 -248.115074)
		(stroke
			(width 0.2)
			(type default)
		)
		(layer "In6.Cu")
	)
	(gr_line
		(start 464.250024 -385.99999)
		(end 418.69995 -385.99999)
		(stroke
			(width 1.524)
			(type default)
		)
		(layer "In6.Cu")
	)
	(gr_arc
		(start 464.250024 -385.99999)
		(mid 464.957111 -385.707088)
		(end 465.250022 -384.999992)
		(stroke
			(width 1.524)
			(type default)
		)
		(layer "In6.Cu")
	)
	(gr_line
		(start 465.250022 -383.29997)
		(end 465.250022 -384.999992)
		(stroke
			(width 1.524)
			(type default)
		)
		(layer "In6.Cu")
	)
	(gr_arc
		(start 466.25002 -382.299972)
		(mid 465.542915 -382.592865)
		(end 465.250022 -383.29997)
		(stroke
			(width 1.524)
			(type default)
		)
		(layer "In6.Cu")
	)
	(gr_line
		(start 472.74988 -382.299972)
		(end 466.25002 -382.299972)
		(stroke
			(width 1.524)
			(type default)
		)
		(layer "In6.Cu")
	)
	(gr_line
		(start 473.749878 -384.999992)
		(end 473.749878 -383.29997)
		(stroke
			(width 1.524)
			(type default)
		)
		(layer "In6.Cu")
	)
	(gr_arc
		(start 473.749878 -384.999992)
		(mid 474.042766 -385.707111)
		(end 474.749876 -385.99999)
		(stroke
			(width 1.524)
			(type default)
		)
		(layer "In6.Cu")
	)
	(gr_arc
		(start 473.749878 -383.29997)
		(mid 473.456985 -382.592865)
		(end 472.74988 -382.299972)
		(stroke
			(width 1.524)
			(type default)
		)
		(layer "In6.Cu")
	)
	(gr_arc
		(start 476.667322 -245.45544)
		(mid 477.152335 -245.940834)
		(end 477.637602 -245.455694)
		(stroke
			(width 0.2)
			(type default)
		)
		(layer "In6.Cu")
	)
	(gr_line
		(start 476.667322 -244.312694)
		(end 476.667322 -245.45544)
		(stroke
			(width 0.2)
			(type default)
		)
		(layer "In6.Cu")
	)
	(gr_line
		(start 476.964502 -129.112264)
		(end 478.107502 -129.112264)
		(stroke
			(width 0.2)
			(type default)
		)
		(layer "In6.Cu")
	)
	(gr_line
		(start 476.964502 -14.11224)
		(end 478.107502 -14.11224)
		(stroke
			(width 0.2)
			(type default)
		)
		(layer "In6.Cu")
	)
	(gr_arc
		(start 476.964756 -128.141984)
		(mid 476.479362 -128.626997)
		(end 476.964502 -129.112264)
		(stroke
			(width 0.2)
			(type default)
		)
		(layer "In6.Cu")
	)
	(gr_arc
		(start 476.964756 -13.14196)
		(mid 476.479362 -13.626973)
		(end 476.964502 -14.11224)
		(stroke
			(width 0.2)
			(type default)
		)
		(layer "In6.Cu")
	)
	(gr_line
		(start 477.637602 -245.455694)
		(end 477.637602 -244.312694)
		(stroke
			(width 0.2)
			(type default)
		)
		(layer "In6.Cu")
	)
	(gr_arc
		(start 477.637602 -244.312694)
		(mid 477.152462 -243.827554)
		(end 476.667322 -244.312694)
		(stroke
			(width 0.2)
			(type default)
		)
		(layer "In6.Cu")
	)
	(gr_arc
		(start 478.107502 -129.112264)
		(mid 478.592642 -128.627124)
		(end 478.107502 -128.141984)
		(stroke
			(width 0.2)
			(type default)
		)
		(layer "In6.Cu")
	)
	(gr_line
		(start 478.107502 -128.141984)
		(end 476.964756 -128.141984)
		(stroke
			(width 0.2)
			(type default)
		)
		(layer "In6.Cu")
	)
	(gr_arc
		(start 478.107502 -14.11224)
		(mid 478.592642 -13.6271)
		(end 478.107502 -13.14196)
		(stroke
			(width 0.2)
			(type default)
		)
		(layer "In6.Cu")
	)
	(gr_line
		(start 478.107502 -13.14196)
		(end 476.964756 -13.14196)
		(stroke
			(width 0.2)
			(type default)
		)
		(layer "In6.Cu")
	)
	(gr_line
		(start 480.431602 -132.922264)
		(end 481.701602 -132.922264)
		(stroke
			(width 0.2)
			(type default)
		)
		(layer "In6.Cu")
	)
	(gr_line
		(start 480.431602 -17.92224)
		(end 481.701602 -17.92224)
		(stroke
			(width 0.2)
			(type default)
		)
		(layer "In6.Cu")
	)
	(gr_arc
		(start 480.431856 -131.951984)
		(mid 479.946462 -132.436997)
		(end 480.431602 -132.922264)
		(stroke
			(width 0.2)
			(type default)
		)
		(layer "In6.Cu")
	)
	(gr_arc
		(start 480.431856 -16.95196)
		(mid 479.946462 -17.436973)
		(end 480.431602 -17.92224)
		(stroke
			(width 0.2)
			(type default)
		)
		(layer "In6.Cu")
	)
	(gr_arc
		(start 480.854512 -249.385074)
		(mid 481.339652 -249.870214)
		(end 481.824792 -249.385074)
		(stroke
			(width 0.2)
			(type default)
		)
		(layer "In6.Cu")
	)
	(gr_line
		(start 480.854512 -248.115074)
		(end 480.854512 -249.385074)
		(stroke
			(width 0.2)
			(type default)
		)
		(layer "In6.Cu")
	)
	(gr_arc
		(start 481.701602 -132.922264)
		(mid 482.186742 -132.437124)
		(end 481.701602 -131.951984)
		(stroke
			(width 0.2)
			(type default)
		)
		(layer "In6.Cu")
	)
	(gr_line
		(start 481.701602 -131.951984)
		(end 480.431856 -131.951984)
		(stroke
			(width 0.2)
			(type default)
		)
		(layer "In6.Cu")
	)
	(gr_arc
		(start 481.701602 -17.92224)
		(mid 482.186742 -17.4371)
		(end 481.701602 -16.95196)
		(stroke
			(width 0.2)
			(type default)
		)
		(layer "In6.Cu")
	)
	(gr_line
		(start 481.701602 -16.95196)
		(end 480.431856 -16.95196)
		(stroke
			(width 0.2)
			(type default)
		)
		(layer "In6.Cu")
	)
	(gr_line
		(start 481.824792 -249.385074)
		(end 481.824792 -248.115328)
		(stroke
			(width 0.2)
			(type default)
		)
		(layer "In6.Cu")
	)
	(gr_arc
		(start 481.824792 -248.115328)
		(mid 481.339779 -247.629934)
		(end 480.854512 -248.115074)
		(stroke
			(width 0.2)
			(type default)
		)
		(layer "In6.Cu")
	)
	(gr_line
		(start 487.449876 -385.99999)
		(end 474.749876 -385.99999)
		(stroke
			(width 1.524)
			(type default)
		)
		(layer "In6.Cu")
	)
	(gr_arc
		(start 487.449876 -385.99999)
		(mid 488.156994 -385.707105)
		(end 488.449874 -384.999992)
		(stroke
			(width 1.524)
			(type default)
		)
		(layer "In6.Cu")
	)
	(gr_line
		(start 488.449874 -372.000018)
		(end 488.449874 -384.999992)
		(stroke
			(width 1.524)
			(type default)
		)
		(layer "In6.Cu")
	)
	(gr_arc
		(start 489.450126 -371.00002)
		(mid 488.742856 -371.292823)
		(end 488.449874 -372.000018)
		(stroke
			(width 1.524)
			(type default)
		)
		(layer "In6.Cu")
	)
	(gr_line
		(start 490.450124 -371.00002)
		(end 489.450126 -371.00002)
		(stroke
			(width 1.524)
			(type default)
		)
		(layer "In6.Cu")
	)
	(gr_arc
		(start 490.450124 -371.00002)
		(mid 491.157222 -370.70712)
		(end 491.450122 -370.000022)
		(stroke
			(width 1.524)
			(type default)
		)
		(layer "In6.Cu")
	)
	(gr_arc
		(start 491.450122 -0.999998)
		(mid 491.15723 -0.292885)
		(end 490.450124 0)
		(stroke
			(width 1.524)
			(type default)
		)
		(layer "In6.Cu")
	)
	(gr_line
		(start 491.450122 -0.999998)
		(end 491.450122 -370.000022)
		(stroke
			(width 1.524)
			(type default)
		)
		(layer "In6.Cu")
	)
	(gr_line
		(start 0 -370.000022)
		(end 0 -0.999998)
		(stroke
			(width 0.05)
			(type default)
		)
		(layer "Edge.Cuts")
	)
	(gr_arc
		(start 0 -370.000022)
		(mid 0.292893 -370.707127)
		(end 0.999998 -371.00002)
		(stroke
			(width 0.05)
			(type default)
		)
		(layer "Edge.Cuts")
	)
	(gr_arc
		(start 0.999998 0)
		(mid 0.292893 -0.292893)
		(end 0 -0.999998)
		(stroke
			(width 0.05)
			(type default)
		)
		(layer "Edge.Cuts")
	)
	(gr_line
		(start 0.999998 0)
		(end 198.000112 0)
		(stroke
			(width 0.05)
			(type default)
		)
		(layer "Edge.Cuts")
	)
	(gr_line
		(start 1.999996 -371.00002)
		(end 0.999998 -371.00002)
		(stroke
			(width 0.05)
			(type default)
		)
		(layer "Edge.Cuts")
	)
	(gr_line
		(start 2.999994 -384.999992)
		(end 2.999994 -372.000018)
		(stroke
			(width 0.05)
			(type default)
		)
		(layer "Edge.Cuts")
	)
	(gr_arc
		(start 2.999994 -384.999992)
		(mid 3.292883 -385.707105)
		(end 3.999992 -385.99999)
		(stroke
			(width 0.05)
			(type default)
		)
		(layer "Edge.Cuts")
	)
	(gr_arc
		(start 2.999994 -372.000018)
		(mid 2.707101 -371.292913)
		(end 1.999996 -371.00002)
		(stroke
			(width 0.05)
			(type default)
		)
		(layer "Edge.Cuts")
	)
	(gr_line
		(start 15.249906 -385.99999)
		(end 3.999992 -385.99999)
		(stroke
			(width 0.05)
			(type default)
		)
		(layer "Edge.Cuts")
	)
	(gr_arc
		(start 15.249906 -385.99999)
		(mid 15.957005 -385.707095)
		(end 16.249904 -384.999992)
		(stroke
			(width 0.05)
			(type default)
		)
		(layer "Edge.Cuts")
	)
	(gr_line
		(start 16.249904 -383.29997)
		(end 16.249904 -384.999992)
		(stroke
			(width 0.05)
			(type default)
		)
		(layer "Edge.Cuts")
	)
	(gr_arc
		(start 17.249902 -382.299972)
		(mid 16.542797 -382.592865)
		(end 16.249904 -383.29997)
		(stroke
			(width 0.05)
			(type default)
		)
		(layer "Edge.Cuts")
	)
	(gr_line
		(start 23.750016 -382.299972)
		(end 17.249902 -382.299972)
		(stroke
			(width 0.05)
			(type default)
		)
		(layer "Edge.Cuts")
	)
	(gr_line
		(start 24.750014 -384.999992)
		(end 24.750014 -383.29997)
		(stroke
			(width 0.05)
			(type default)
		)
		(layer "Edge.Cuts")
	)
	(gr_arc
		(start 24.750014 -384.999992)
		(mid 25.042905 -385.707098)
		(end 25.750012 -385.99999)
		(stroke
			(width 0.05)
			(type default)
		)
		(layer "Edge.Cuts")
	)
	(gr_arc
		(start 24.750014 -383.29997)
		(mid 24.457121 -382.592865)
		(end 23.750016 -382.299972)
		(stroke
			(width 0.05)
			(type default)
		)
		(layer "Edge.Cuts")
	)
	(gr_arc
		(start 30.78988 -300.57217)
		(mid 30.069008 -298.820889)
		(end 29.03093 -297.236896)
		(stroke
			(width 0.05)
			(type default)
		)
		(layer "Edge.Cuts")
	)
	(gr_arc
		(start 30.78988 -300.57217)
		(mid 33.325017 -302.450168)
		(end 35.859974 -300.57217)
		(stroke
			(width 0.05)
			(type default)
		)
		(layer "Edge.Cuts")
	)
	(gr_arc
		(start 30.78988 -185.572146)
		(mid 30.069005 -183.820868)
		(end 29.03093 -182.236872)
		(stroke
			(width 0.05)
			(type default)
		)
		(layer "Edge.Cuts")
	)
	(gr_arc
		(start 30.78988 -185.572146)
		(mid 33.325017 -187.450144)
		(end 35.859974 -185.572146)
		(stroke
			(width 0.05)
			(type default)
		)
		(layer "Edge.Cuts")
	)
	(gr_arc
		(start 30.78988 -70.572122)
		(mid 30.069044 -68.820823)
		(end 29.03093 -67.236848)
		(stroke
			(width 0.05)
			(type default)
		)
		(layer "Edge.Cuts")
	)
	(gr_arc
		(start 30.78988 -70.572122)
		(mid 33.325017 -72.45012)
		(end 35.859974 -70.572122)
		(stroke
			(width 0.05)
			(type default)
		)
		(layer "Edge.Cuts")
	)
	(gr_arc
		(start 37.618924 -297.236896)
		(mid 33.325133 -288.300075)
		(end 29.03093 -297.236896)
		(stroke
			(width 0.05)
			(type default)
		)
		(layer "Edge.Cuts")
	)
	(gr_arc
		(start 37.618924 -297.236896)
		(mid 36.580843 -298.820887)
		(end 35.859974 -300.57217)
		(stroke
			(width 0.05)
			(type default)
		)
		(layer "Edge.Cuts")
	)
	(gr_arc
		(start 37.618924 -182.236872)
		(mid 33.325133 -173.300051)
		(end 29.03093 -182.236872)
		(stroke
			(width 0.05)
			(type default)
		)
		(layer "Edge.Cuts")
	)
	(gr_arc
		(start 37.618924 -182.236872)
		(mid 36.580839 -183.820862)
		(end 35.859974 -185.572146)
		(stroke
			(width 0.05)
			(type default)
		)
		(layer "Edge.Cuts")
	)
	(gr_arc
		(start 37.618924 -67.236848)
		(mid 33.325133 -58.300027)
		(end 29.03093 -67.236848)
		(stroke
			(width 0.05)
			(type default)
		)
		(layer "Edge.Cuts")
	)
	(gr_arc
		(start 37.618924 -67.236848)
		(mid 36.58085 -68.820842)
		(end 35.859974 -70.572122)
		(stroke
			(width 0.05)
			(type default)
		)
		(layer "Edge.Cuts")
	)
	(gr_arc
		(start 42.22496 -13.999972)
		(mid 44.000166 -15.775178)
		(end 45.775118 -13.999972)
		(stroke
			(width 0.05)
			(type default)
		)
		(layer "Edge.Cuts")
	)
	(gr_arc
		(start 42.600118 -30.999938)
		(mid 44.000166 -32.399986)
		(end 45.39996 -30.999938)
		(stroke
			(width 0.05)
			(type default)
		)
		(layer "Edge.Cuts")
	)
	(gr_arc
		(start 45.39996 -30.999938)
		(mid 44.000166 -29.600144)
		(end 42.600118 -30.999938)
		(stroke
			(width 0.05)
			(type default)
		)
		(layer "Edge.Cuts")
	)
	(gr_arc
		(start 45.775118 -13.999972)
		(mid 44.000166 -12.22502)
		(end 42.22496 -13.999972)
		(stroke
			(width 0.05)
			(type default)
		)
		(layer "Edge.Cuts")
	)
	(gr_arc
		(start 61.030104 -335.399888)
		(mid 62.620144 -336.989928)
		(end 64.20993 -335.399888)
		(stroke
			(width 0.05)
			(type default)
		)
		(layer "Edge.Cuts")
	)
	(gr_arc
		(start 64.20993 -335.399888)
		(mid 62.620144 -333.810102)
		(end 61.030104 -335.399888)
		(stroke
			(width 0.05)
			(type default)
		)
		(layer "Edge.Cuts")
	)
	(gr_arc
		(start 66.455036 -335.399888)
		(mid 67.700144 -336.644996)
		(end 68.944998 -335.399888)
		(stroke
			(width 0.05)
			(type default)
		)
		(layer "Edge.Cuts")
	)
	(gr_arc
		(start 68.944998 -335.399888)
		(mid 67.700144 -334.155034)
		(end 66.455036 -335.399888)
		(stroke
			(width 0.05)
			(type default)
		)
		(layer "Edge.Cuts")
	)
	(gr_line
		(start 71.300086 -385.99999)
		(end 25.750012 -385.99999)
		(stroke
			(width 0.05)
			(type default)
		)
		(layer "Edge.Cuts")
	)
	(gr_arc
		(start 71.300086 -385.99999)
		(mid 72.007198 -385.707102)
		(end 72.300084 -384.999992)
		(stroke
			(width 0.05)
			(type default)
		)
		(layer "Edge.Cuts")
	)
	(gr_line
		(start 72.300084 -381)
		(end 72.300084 -384.999992)
		(stroke
			(width 0.05)
			(type default)
		)
		(layer "Edge.Cuts")
	)
	(gr_arc
		(start 73.300082 -380.000002)
		(mid 72.592977 -380.292895)
		(end 72.300084 -381)
		(stroke
			(width 0.05)
			(type default)
		)
		(layer "Edge.Cuts")
	)
	(gr_arc
		(start 93.790008 -300.57217)
		(mid 93.069181 -298.820865)
		(end 92.031058 -297.236896)
		(stroke
			(width 0.05)
			(type default)
		)
		(layer "Edge.Cuts")
	)
	(gr_arc
		(start 93.790008 -300.57217)
		(mid 96.325145 -302.450168)
		(end 98.860102 -300.57217)
		(stroke
			(width 0.05)
			(type default)
		)
		(layer "Edge.Cuts")
	)
	(gr_arc
		(start 93.790008 -185.572146)
		(mid 93.069177 -183.820843)
		(end 92.031058 -182.236872)
		(stroke
			(width 0.05)
			(type default)
		)
		(layer "Edge.Cuts")
	)
	(gr_arc
		(start 93.790008 -185.572146)
		(mid 96.325145 -187.450144)
		(end 98.860102 -185.572146)
		(stroke
			(width 0.05)
			(type default)
		)
		(layer "Edge.Cuts")
	)
	(gr_arc
		(start 93.790008 -70.572122)
		(mid 93.069174 -68.820821)
		(end 92.031058 -67.236848)
		(stroke
			(width 0.05)
			(type default)
		)
		(layer "Edge.Cuts")
	)
	(gr_arc
		(start 93.790008 -70.572122)
		(mid 96.325145 -72.45012)
		(end 98.860102 -70.572122)
		(stroke
			(width 0.05)
			(type default)
		)
		(layer "Edge.Cuts")
	)
	(gr_arc
		(start 100.619052 -297.236896)
		(mid 96.325261 -288.300075)
		(end 92.031058 -297.236896)
		(stroke
			(width 0.05)
			(type default)
		)
		(layer "Edge.Cuts")
	)
	(gr_arc
		(start 100.619052 -297.236896)
		(mid 99.58092 -298.820862)
		(end 98.860102 -300.57217)
		(stroke
			(width 0.05)
			(type default)
		)
		(layer "Edge.Cuts")
	)
	(gr_arc
		(start 100.619052 -182.236872)
		(mid 96.325261 -173.300051)
		(end 92.031058 -182.236872)
		(stroke
			(width 0.05)
			(type default)
		)
		(layer "Edge.Cuts")
	)
	(gr_arc
		(start 100.619052 -182.236872)
		(mid 99.580964 -183.820861)
		(end 98.860102 -185.572146)
		(stroke
			(width 0.05)
			(type default)
		)
		(layer "Edge.Cuts")
	)
	(gr_arc
		(start 100.619052 -67.236848)
		(mid 96.325261 -58.300027)
		(end 92.031058 -67.236848)
		(stroke
			(width 0.05)
			(type default)
		)
		(layer "Edge.Cuts")
	)
	(gr_arc
		(start 100.619052 -67.236848)
		(mid 99.580976 -68.820841)
		(end 98.860102 -70.572122)
		(stroke
			(width 0.05)
			(type default)
		)
		(layer "Edge.Cuts")
	)
	(gr_arc
		(start 105.32491 -23.999952)
		(mid 107.100116 -25.775158)
		(end 108.875068 -23.999952)
		(stroke
			(width 0.05)
			(type default)
		)
		(layer "Edge.Cuts")
	)
	(gr_arc
		(start 108.875068 -23.999952)
		(mid 107.100116 -22.225)
		(end 105.32491 -23.999952)
		(stroke
			(width 0.05)
			(type default)
		)
		(layer "Edge.Cuts")
	)
	(gr_arc
		(start 122.724926 -181.799992)
		(mid 127.824992 -186.900058)
		(end 132.925058 -181.799992)
		(stroke
			(width 0.05)
			(type default)
		)
		(layer "Edge.Cuts")
	)
	(gr_line
		(start 125.299978 -380.000002)
		(end 73.300082 -380.000002)
		(stroke
			(width 0.05)
			(type default)
		)
		(layer "Edge.Cuts")
	)
	(gr_line
		(start 126.299976 -384.999992)
		(end 126.299976 -381)
		(stroke
			(width 0.05)
			(type default)
		)
		(layer "Edge.Cuts")
	)
	(gr_arc
		(start 126.299976 -384.999992)
		(mid 126.592864 -385.707112)
		(end 127.299974 -385.99999)
		(stroke
			(width 0.05)
			(type default)
		)
		(layer "Edge.Cuts")
	)
	(gr_arc
		(start 126.299976 -381)
		(mid 126.007083 -380.292895)
		(end 125.299978 -380.000002)
		(stroke
			(width 0.05)
			(type default)
		)
		(layer "Edge.Cuts")
	)
	(gr_arc
		(start 128.674876 -335.399888)
		(mid 129.919984 -336.644996)
		(end 131.165092 -335.399888)
		(stroke
			(width 0.05)
			(type default)
		)
		(layer "Edge.Cuts")
	)
	(gr_arc
		(start 131.165092 -335.399888)
		(mid 129.919984 -334.15478)
		(end 128.674876 -335.399888)
		(stroke
			(width 0.05)
			(type default)
		)
		(layer "Edge.Cuts")
	)
	(gr_arc
		(start 132.925058 -181.799992)
		(mid 127.824992 -176.699926)
		(end 122.724926 -181.799992)
		(stroke
			(width 0.05)
			(type default)
		)
		(layer "Edge.Cuts")
	)
	(gr_arc
		(start 133.409944 -335.399888)
		(mid 134.999984 -336.989928)
		(end 136.590024 -335.399888)
		(stroke
			(width 0.05)
			(type default)
		)
		(layer "Edge.Cuts")
	)
	(gr_arc
		(start 136.590024 -335.399888)
		(mid 134.999984 -333.809848)
		(end 133.409944 -335.399888)
		(stroke
			(width 0.05)
			(type default)
		)
		(layer "Edge.Cuts")
	)
	(gr_arc
		(start 156.789882 -300.57217)
		(mid 156.069011 -298.820889)
		(end 155.030932 -297.236896)
		(stroke
			(width 0.05)
			(type default)
		)
		(layer "Edge.Cuts")
	)
	(gr_arc
		(start 156.789882 -300.57217)
		(mid 159.325019 -302.450168)
		(end 161.859976 -300.57217)
		(stroke
			(width 0.05)
			(type default)
		)
		(layer "Edge.Cuts")
	)
	(gr_arc
		(start 156.789882 -185.572146)
		(mid 156.069007 -183.820867)
		(end 155.030932 -182.236872)
		(stroke
			(width 0.05)
			(type default)
		)
		(layer "Edge.Cuts")
	)
	(gr_arc
		(start 156.789882 -185.572146)
		(mid 159.325019 -187.450144)
		(end 161.859976 -185.572146)
		(stroke
			(width 0.05)
			(type default)
		)
		(layer "Edge.Cuts")
	)
	(gr_arc
		(start 156.789882 -70.572122)
		(mid 156.069046 -68.820822)
		(end 155.030932 -67.236848)
		(stroke
			(width 0.05)
			(type default)
		)
		(layer "Edge.Cuts")
	)
	(gr_arc
		(start 156.789882 -70.572122)
		(mid 159.325019 -72.45012)
		(end 161.859976 -70.572122)
		(stroke
			(width 0.05)
			(type default)
		)
		(layer "Edge.Cuts")
	)
	(gr_arc
		(start 163.618926 -297.236896)
		(mid 159.325135 -288.300075)
		(end 155.030932 -297.236896)
		(stroke
			(width 0.05)
			(type default)
		)
		(layer "Edge.Cuts")
	)
	(gr_arc
		(start 163.618926 -297.236896)
		(mid 162.580844 -298.820887)
		(end 161.859976 -300.57217)
		(stroke
			(width 0.05)
			(type default)
		)
		(layer "Edge.Cuts")
	)
	(gr_arc
		(start 163.618926 -182.236872)
		(mid 159.325135 -173.300051)
		(end 155.030932 -182.236872)
		(stroke
			(width 0.05)
			(type default)
		)
		(layer "Edge.Cuts")
	)
	(gr_arc
		(start 163.618926 -182.236872)
		(mid 162.580841 -183.820862)
		(end 161.859976 -185.572146)
		(stroke
			(width 0.05)
			(type default)
		)
		(layer "Edge.Cuts")
	)
	(gr_arc
		(start 163.618926 -67.236848)
		(mid 159.325135 -58.300027)
		(end 155.030932 -67.236848)
		(stroke
			(width 0.05)
			(type default)
		)
		(layer "Edge.Cuts")
	)
	(gr_arc
		(start 163.618926 -67.236848)
		(mid 162.580852 -68.820842)
		(end 161.859976 -70.572122)
		(stroke
			(width 0.05)
			(type default)
		)
		(layer "Edge.Cuts")
	)
	(gr_arc
		(start 168.425114 -13.999972)
		(mid 170.200066 -15.774924)
		(end 171.975018 -13.999972)
		(stroke
			(width 0.05)
			(type default)
		)
		(layer "Edge.Cuts")
	)
	(gr_arc
		(start 168.800018 -30.999938)
		(mid 170.200066 -32.399986)
		(end 171.600114 -30.999938)
		(stroke
			(width 0.05)
			(type default)
		)
		(layer "Edge.Cuts")
	)
	(gr_arc
		(start 171.600114 -30.999938)
		(mid 170.200066 -29.59989)
		(end 168.800018 -30.999938)
		(stroke
			(width 0.05)
			(type default)
		)
		(layer "Edge.Cuts")
	)
	(gr_arc
		(start 171.975018 -13.999972)
		(mid 170.200066 -12.22502)
		(end 168.425114 -13.999972)
		(stroke
			(width 0.05)
			(type default)
		)
		(layer "Edge.Cuts")
	)
	(gr_line
		(start 172.850048 -385.99999)
		(end 127.299974 -385.99999)
		(stroke
			(width 0.05)
			(type default)
		)
		(layer "Edge.Cuts")
	)
	(gr_arc
		(start 172.850048 -385.99999)
		(mid 173.55712 -385.70708)
		(end 173.850046 -384.999992)
		(stroke
			(width 0.05)
			(type default)
		)
		(layer "Edge.Cuts")
	)
	(gr_line
		(start 173.850046 -383.29997)
		(end 173.850046 -384.999992)
		(stroke
			(width 0.05)
			(type default)
		)
		(layer "Edge.Cuts")
	)
	(gr_arc
		(start 174.850044 -382.299972)
		(mid 174.142939 -382.592865)
		(end 173.850046 -383.29997)
		(stroke
			(width 0.05)
			(type default)
		)
		(layer "Edge.Cuts")
	)
	(gr_line
		(start 181.349904 -382.299972)
		(end 174.850044 -382.299972)
		(stroke
			(width 0.05)
			(type default)
		)
		(layer "Edge.Cuts")
	)
	(gr_line
		(start 182.349902 -384.999992)
		(end 182.349902 -383.29997)
		(stroke
			(width 0.05)
			(type default)
		)
		(layer "Edge.Cuts")
	)
	(gr_arc
		(start 182.349902 -384.999992)
		(mid 182.642792 -385.707103)
		(end 183.3499 -385.99999)
		(stroke
			(width 0.05)
			(type default)
		)
		(layer "Edge.Cuts")
	)
	(gr_arc
		(start 182.349902 -383.29997)
		(mid 182.057009 -382.592865)
		(end 181.349904 -382.299972)
		(stroke
			(width 0.05)
			(type default)
		)
		(layer "Edge.Cuts")
	)
	(gr_arc
		(start 187.265056 -210.771994)
		(mid 186.544214 -209.020698)
		(end 185.506106 -207.43672)
		(stroke
			(width 0.05)
			(type default)
		)
		(layer "Edge.Cuts")
	)
	(gr_arc
		(start 187.265056 -210.771994)
		(mid 189.800193 -212.650172)
		(end 192.33515 -210.771994)
		(stroke
			(width 0.05)
			(type default)
		)
		(layer "Edge.Cuts")
	)
	(gr_arc
		(start 187.265056 -100.772214)
		(mid 186.544217 -99.020916)
		(end 185.506106 -97.43694)
		(stroke
			(width 0.05)
			(type default)
		)
		(layer "Edge.Cuts")
	)
	(gr_arc
		(start 187.265056 -100.772214)
		(mid 189.800193 -102.650212)
		(end 192.33515 -100.772214)
		(stroke
			(width 0.05)
			(type default)
		)
		(layer "Edge.Cuts")
	)
	(gr_arc
		(start 194.093846 -207.43672)
		(mid 189.799976 -198.499899)
		(end 185.506106 -207.43672)
		(stroke
			(width 0.05)
			(type default)
		)
		(layer "Edge.Cuts")
	)
	(gr_arc
		(start 194.093846 -207.43672)
		(mid 193.055896 -209.020725)
		(end 192.33515 -210.771994)
		(stroke
			(width 0.05)
			(type default)
		)
		(layer "Edge.Cuts")
	)
	(gr_arc
		(start 194.093846 -97.43694)
		(mid 189.799976 -88.500119)
		(end 185.506106 -97.43694)
		(stroke
			(width 0.05)
			(type default)
		)
		(layer "Edge.Cuts")
	)
	(gr_arc
		(start 194.093846 -97.43694)
		(mid 193.055863 -99.020929)
		(end 192.33515 -100.772214)
		(stroke
			(width 0.05)
			(type default)
		)
		(layer "Edge.Cuts")
	)
	(gr_line
		(start 197.000114 -385.99999)
		(end 183.3499 -385.99999)
		(stroke
			(width 0.05)
			(type default)
		)
		(layer "Edge.Cuts")
	)
	(gr_arc
		(start 197.000114 -385.99999)
		(mid 197.707207 -385.707092)
		(end 198.000112 -384.999992)
		(stroke
			(width 0.05)
			(type default)
		)
		(layer "Edge.Cuts")
	)
	(gr_line
		(start 198.000112 -381)
		(end 198.000112 -384.999992)
		(stroke
			(width 0.05)
			(type default)
		)
		(layer "Edge.Cuts")
	)
	(gr_arc
		(start 199.00011 -380.000002)
		(mid 198.293005 -380.292895)
		(end 198.000112 -381)
		(stroke
			(width 0.05)
			(type default)
		)
		(layer "Edge.Cuts")
	)
	(gr_arc
		(start 199.00011 -47.200058)
		(mid 199.293003 -47.907163)
		(end 200.000108 -48.200056)
		(stroke
			(width 0.05)
			(type default)
		)
		(layer "Edge.Cuts")
	)
	(gr_arc
		(start 199.00011 -0.999998)
		(mid 198.707217 -0.29289)
		(end 198.000112 0)
		(stroke
			(width 0.05)
			(type default)
		)
		(layer "Edge.Cuts")
	)
	(gr_line
		(start 199.00011 -0.999998)
		(end 199.00011 -47.200058)
		(stroke
			(width 0.05)
			(type default)
		)
		(layer "Edge.Cuts")
	)
	(gr_line
		(start 200.000108 -48.200056)
		(end 206.000096 -48.200056)
		(stroke
			(width 0.05)
			(type default)
		)
		(layer "Edge.Cuts")
	)
	(gr_arc
		(start 207.000094 -61.999876)
		(mid 207.292987 -62.706981)
		(end 208.000092 -62.999874)
		(stroke
			(width 0.05)
			(type default)
		)
		(layer "Edge.Cuts")
	)
	(gr_arc
		(start 207.000094 -49.200054)
		(mid 206.707185 -48.49298)
		(end 206.000096 -48.200056)
		(stroke
			(width 0.05)
			(type default)
		)
		(layer "Edge.Cuts")
	)
	(gr_line
		(start 207.000094 -49.200054)
		(end 207.000094 -61.999876)
		(stroke
			(width 0.05)
			(type default)
		)
		(layer "Edge.Cuts")
	)
	(gr_line
		(start 208.000092 -62.999874)
		(end 267.999972 -62.999874)
		(stroke
			(width 0.05)
			(type default)
		)
		(layer "Edge.Cuts")
	)
	(gr_arc
		(start 241.664998 -250.772168)
		(mid 240.94417 -249.020863)
		(end 239.906048 -247.436894)
		(stroke
			(width 0.05)
			(type default)
		)
		(layer "Edge.Cuts")
	)
	(gr_arc
		(start 241.664998 -250.772168)
		(mid 244.200135 -252.650166)
		(end 246.735092 -250.772168)
		(stroke
			(width 0.05)
			(type default)
		)
		(layer "Edge.Cuts")
	)
	(gr_arc
		(start 241.664998 -182.572152)
		(mid 240.944167 -180.820849)
		(end 239.906048 -179.236878)
		(stroke
			(width 0.05)
			(type default)
		)
		(layer "Edge.Cuts")
	)
	(gr_arc
		(start 241.664998 -182.572152)
		(mid 244.200135 -184.45015)
		(end 246.735092 -182.572152)
		(stroke
			(width 0.05)
			(type default)
		)
		(layer "Edge.Cuts")
	)
	(gr_arc
		(start 248.494042 -247.436894)
		(mid 244.200251 -238.500073)
		(end 239.906048 -247.436894)
		(stroke
			(width 0.05)
			(type default)
		)
		(layer "Edge.Cuts")
	)
	(gr_arc
		(start 248.494042 -247.436894)
		(mid 247.455959 -249.020884)
		(end 246.735092 -250.772168)
		(stroke
			(width 0.05)
			(type default)
		)
		(layer "Edge.Cuts")
	)
	(gr_arc
		(start 248.494042 -179.236878)
		(mid 244.200251 -170.300057)
		(end 239.906048 -179.236878)
		(stroke
			(width 0.05)
			(type default)
		)
		(layer "Edge.Cuts")
	)
	(gr_arc
		(start 248.494042 -179.236878)
		(mid 247.455956 -180.820867)
		(end 246.735092 -182.572152)
		(stroke
			(width 0.05)
			(type default)
		)
		(layer "Edge.Cuts")
	)
	(gr_line
		(start 251.000006 -380.000002)
		(end 199.00011 -380.000002)
		(stroke
			(width 0.05)
			(type default)
		)
		(layer "Edge.Cuts")
	)
	(gr_line
		(start 252.000004 -384.999992)
		(end 252.000004 -381)
		(stroke
			(width 0.05)
			(type default)
		)
		(layer "Edge.Cuts")
	)
	(gr_arc
		(start 252.000004 -384.999992)
		(mid 252.292894 -385.707102)
		(end 253.000002 -385.99999)
		(stroke
			(width 0.05)
			(type default)
		)
		(layer "Edge.Cuts")
	)
	(gr_arc
		(start 252.000004 -381)
		(mid 251.707111 -380.292895)
		(end 251.000006 -380.000002)
		(stroke
			(width 0.05)
			(type default)
		)
		(layer "Edge.Cuts")
	)
	(gr_arc
		(start 267.999972 -62.999874)
		(mid 268.707077 -62.706981)
		(end 268.99997 -61.999876)
		(stroke
			(width 0.05)
			(type default)
		)
		(layer "Edge.Cuts")
	)
	(gr_line
		(start 268.99997 -61.999876)
		(end 268.99997 -49.200054)
		(stroke
			(width 0.05)
			(type default)
		)
		(layer "Edge.Cuts")
	)
	(gr_line
		(start 269.035784 -385.99999)
		(end 253.000002 -385.99999)
		(stroke
			(width 0.05)
			(type default)
		)
		(layer "Edge.Cuts")
	)
	(gr_arc
		(start 269.035784 -385.99999)
		(mid 269.41848 -385.923895)
		(end 269.74292 -385.707128)
		(stroke
			(width 0.05)
			(type default)
		)
		(layer "Edge.Cuts")
	)
	(gr_arc
		(start 269.999968 -48.200056)
		(mid 269.292867 -48.492957)
		(end 268.99997 -49.200054)
		(stroke
			(width 0.05)
			(type default)
		)
		(layer "Edge.Cuts")
	)
	(gr_line
		(start 269.999968 -48.200056)
		(end 309.999888 -48.200056)
		(stroke
			(width 0.05)
			(type default)
		)
		(layer "Edge.Cuts")
	)
	(gr_line
		(start 272.15719 -383.292858)
		(end 269.74292 -385.707128)
		(stroke
			(width 0.05)
			(type default)
		)
		(layer "Edge.Cuts")
	)
	(gr_arc
		(start 272.15719 -383.292858)
		(mid 272.373925 -382.968408)
		(end 272.450052 -382.585722)
		(stroke
			(width 0.05)
			(type default)
		)
		(layer "Edge.Cuts")
	)
	(gr_line
		(start 272.450052 -361.00004)
		(end 272.450052 -382.585722)
		(stroke
			(width 0.05)
			(type default)
		)
		(layer "Edge.Cuts")
	)
	(gr_arc
		(start 273.45005 -360.000042)
		(mid 272.742945 -360.292935)
		(end 272.450052 -361.00004)
		(stroke
			(width 0.05)
			(type default)
		)
		(layer "Edge.Cuts")
	)
	(gr_line
		(start 275.75002 -360.000042)
		(end 273.45005 -360.000042)
		(stroke
			(width 0.05)
			(type default)
		)
		(layer "Edge.Cuts")
	)
	(gr_line
		(start 276.750018 -382.585722)
		(end 276.750018 -361.00004)
		(stroke
			(width 0.05)
			(type default)
		)
		(layer "Edge.Cuts")
	)
	(gr_arc
		(start 276.750018 -382.585722)
		(mid 276.826093 -382.96843)
		(end 277.04288 -383.292858)
		(stroke
			(width 0.05)
			(type default)
		)
		(layer "Edge.Cuts")
	)
	(gr_arc
		(start 276.750018 -361.00004)
		(mid 276.457125 -360.292935)
		(end 275.75002 -360.000042)
		(stroke
			(width 0.05)
			(type default)
		)
		(layer "Edge.Cuts")
	)
	(gr_line
		(start 279.45715 -385.707128)
		(end 277.04288 -383.292858)
		(stroke
			(width 0.05)
			(type default)
		)
		(layer "Edge.Cuts")
	)
	(gr_arc
		(start 279.45715 -385.707128)
		(mid 279.781602 -385.923853)
		(end 280.164286 -385.99999)
		(stroke
			(width 0.05)
			(type default)
		)
		(layer "Edge.Cuts")
	)
	(gr_arc
		(start 280.550112 -296.960036)
		(mid 282.300172 -295.209976)
		(end 280.550112 -293.459916)
		(stroke
			(width 0.05)
			(type default)
		)
		(layer "Edge.Cuts")
	)
	(gr_arc
		(start 280.550112 -293.459916)
		(mid 278.800052 -295.209976)
		(end 280.550112 -296.960036)
		(stroke
			(width 0.05)
			(type default)
		)
		(layer "Edge.Cuts")
	)
	(gr_arc
		(start 297.664886 -250.772168)
		(mid 296.944015 -249.020887)
		(end 295.905936 -247.436894)
		(stroke
			(width 0.05)
			(type default)
		)
		(layer "Edge.Cuts")
	)
	(gr_arc
		(start 297.664886 -250.772168)
		(mid 300.200023 -252.650166)
		(end 302.73498 -250.772168)
		(stroke
			(width 0.05)
			(type default)
		)
		(layer "Edge.Cuts")
	)
	(gr_arc
		(start 297.664886 -100.772214)
		(mid 296.944021 -99.020929)
		(end 295.905936 -97.43694)
		(stroke
			(width 0.05)
			(type default)
		)
		(layer "Edge.Cuts")
	)
	(gr_arc
		(start 297.664886 -100.772214)
		(mid 300.200023 -102.650212)
		(end 302.73498 -100.772214)
		(stroke
			(width 0.05)
			(type default)
		)
		(layer "Edge.Cuts")
	)
	(gr_arc
		(start 304.49393 -247.436894)
		(mid 300.200139 -238.500073)
		(end 295.905936 -247.436894)
		(stroke
			(width 0.05)
			(type default)
		)
		(layer "Edge.Cuts")
	)
	(gr_arc
		(start 304.49393 -247.436894)
		(mid 303.455848 -249.020885)
		(end 302.73498 -250.772168)
		(stroke
			(width 0.05)
			(type default)
		)
		(layer "Edge.Cuts")
	)
	(gr_arc
		(start 304.49393 -97.43694)
		(mid 300.200139 -88.500119)
		(end 295.905936 -97.43694)
		(stroke
			(width 0.05)
			(type default)
		)
		(layer "Edge.Cuts")
	)
	(gr_arc
		(start 304.49393 -97.43694)
		(mid 303.455854 -99.020934)
		(end 302.73498 -100.772214)
		(stroke
			(width 0.05)
			(type default)
		)
		(layer "Edge.Cuts")
	)
	(gr_line
		(start 306.649882 -385.99999)
		(end 280.164286 -385.99999)
		(stroke
			(width 0.05)
			(type default)
		)
		(layer "Edge.Cuts")
	)
	(gr_arc
		(start 306.649882 -385.99999)
		(mid 307.356996 -385.707103)
		(end 307.64988 -384.999992)
		(stroke
			(width 0.05)
			(type default)
		)
		(layer "Edge.Cuts")
	)
	(gr_line
		(start 307.64988 -383.29997)
		(end 307.64988 -384.999992)
		(stroke
			(width 0.05)
			(type default)
		)
		(layer "Edge.Cuts")
	)
	(gr_arc
		(start 308.649878 -382.299972)
		(mid 307.942773 -382.592865)
		(end 307.64988 -383.29997)
		(stroke
			(width 0.05)
			(type default)
		)
		(layer "Edge.Cuts")
	)
	(gr_arc
		(start 309.999888 -48.200056)
		(mid 310.706993 -47.907163)
		(end 310.999886 -47.200058)
		(stroke
			(width 0.05)
			(type default)
		)
		(layer "Edge.Cuts")
	)
	(gr_line
		(start 310.999886 -47.200058)
		(end 310.999886 -0.999998)
		(stroke
			(width 0.05)
			(type default)
		)
		(layer "Edge.Cuts")
	)
	(gr_arc
		(start 311.999884 0)
		(mid 311.292788 -0.292898)
		(end 310.999886 -0.999998)
		(stroke
			(width 0.05)
			(type default)
		)
		(layer "Edge.Cuts")
	)
	(gr_line
		(start 311.999884 0)
		(end 490.450124 0)
		(stroke
			(width 0.05)
			(type default)
		)
		(layer "Edge.Cuts")
	)
	(gr_line
		(start 315.149992 -382.299972)
		(end 308.649878 -382.299972)
		(stroke
			(width 0.05)
			(type default)
		)
		(layer "Edge.Cuts")
	)
	(gr_line
		(start 316.14999 -384.999992)
		(end 316.14999 -383.29997)
		(stroke
			(width 0.05)
			(type default)
		)
		(layer "Edge.Cuts")
	)
	(gr_arc
		(start 316.14999 -384.999992)
		(mid 316.442879 -385.707107)
		(end 317.149988 -385.99999)
		(stroke
			(width 0.05)
			(type default)
		)
		(layer "Edge.Cuts")
	)
	(gr_arc
		(start 316.14999 -383.29997)
		(mid 315.857097 -382.592865)
		(end 315.149992 -382.299972)
		(stroke
			(width 0.05)
			(type default)
		)
		(layer "Edge.Cuts")
	)
	(gr_arc
		(start 328.14006 -300.57217)
		(mid 327.41923 -298.820867)
		(end 326.38111 -297.236896)
		(stroke
			(width 0.05)
			(type default)
		)
		(layer "Edge.Cuts")
	)
	(gr_arc
		(start 328.14006 -300.57217)
		(mid 330.675197 -302.450168)
		(end 333.210154 -300.57217)
		(stroke
			(width 0.05)
			(type default)
		)
		(layer "Edge.Cuts")
	)
	(gr_arc
		(start 328.14006 -185.572146)
		(mid 327.419226 -183.820845)
		(end 326.38111 -182.236872)
		(stroke
			(width 0.05)
			(type default)
		)
		(layer "Edge.Cuts")
	)
	(gr_arc
		(start 328.14006 -185.572146)
		(mid 330.675197 -187.450144)
		(end 333.210154 -185.572146)
		(stroke
			(width 0.05)
			(type default)
		)
		(layer "Edge.Cuts")
	)
	(gr_arc
		(start 328.14006 -70.572122)
		(mid 327.419223 -68.820823)
		(end 326.38111 -67.236848)
		(stroke
			(width 0.05)
			(type default)
		)
		(layer "Edge.Cuts")
	)
	(gr_arc
		(start 328.14006 -70.572122)
		(mid 330.675197 -72.45012)
		(end 333.210154 -70.572122)
		(stroke
			(width 0.05)
			(type default)
		)
		(layer "Edge.Cuts")
	)
	(gr_arc
		(start 334.96885 -297.236896)
		(mid 330.67498 -288.300075)
		(end 326.38111 -297.236896)
		(stroke
			(width 0.05)
			(type default)
		)
		(layer "Edge.Cuts")
	)
	(gr_arc
		(start 334.96885 -297.236896)
		(mid 333.930896 -298.8209)
		(end 333.210154 -300.57217)
		(stroke
			(width 0.05)
			(type default)
		)
		(layer "Edge.Cuts")
	)
	(gr_arc
		(start 334.96885 -182.236872)
		(mid 330.67498 -173.300051)
		(end 326.38111 -182.236872)
		(stroke
			(width 0.05)
			(type default)
		)
		(layer "Edge.Cuts")
	)
	(gr_arc
		(start 334.96885 -182.236872)
		(mid 333.930893 -183.820874)
		(end 333.210154 -185.572146)
		(stroke
			(width 0.05)
			(type default)
		)
		(layer "Edge.Cuts")
	)
	(gr_arc
		(start 334.96885 -67.236848)
		(mid 330.67498 -58.300027)
		(end 326.38111 -67.236848)
		(stroke
			(width 0.05)
			(type default)
		)
		(layer "Edge.Cuts")
	)
	(gr_arc
		(start 334.96885 -67.236848)
		(mid 333.930889 -68.820849)
		(end 333.210154 -70.572122)
		(stroke
			(width 0.05)
			(type default)
		)
		(layer "Edge.Cuts")
	)
	(gr_arc
		(start 339.525102 -13.999972)
		(mid 341.300054 -15.774924)
		(end 343.075006 -13.999972)
		(stroke
			(width 0.05)
			(type default)
		)
		(layer "Edge.Cuts")
	)
	(gr_arc
		(start 339.900006 -30.999938)
		(mid 341.300054 -32.399986)
		(end 342.700102 -30.999938)
		(stroke
			(width 0.05)
			(type default)
		)
		(layer "Edge.Cuts")
	)
	(gr_arc
		(start 342.700102 -30.999938)
		(mid 341.300054 -29.59989)
		(end 339.900006 -30.999938)
		(stroke
			(width 0.05)
			(type default)
		)
		(layer "Edge.Cuts")
	)
	(gr_arc
		(start 343.075006 -13.999972)
		(mid 341.300054 -12.22502)
		(end 339.525102 -13.999972)
		(stroke
			(width 0.05)
			(type default)
		)
		(layer "Edge.Cuts")
	)
	(gr_line
		(start 362.700062 -385.99999)
		(end 317.149988 -385.99999)
		(stroke
			(width 0.05)
			(type default)
		)
		(layer "Edge.Cuts")
	)
	(gr_arc
		(start 362.700062 -385.99999)
		(mid 363.407189 -385.70711)
		(end 363.70006 -384.999992)
		(stroke
			(width 0.05)
			(type default)
		)
		(layer "Edge.Cuts")
	)
	(gr_line
		(start 363.70006 -381)
		(end 363.70006 -384.999992)
		(stroke
			(width 0.05)
			(type default)
		)
		(layer "Edge.Cuts")
	)
	(gr_arc
		(start 364.700058 -380.000002)
		(mid 363.992953 -380.292895)
		(end 363.70006 -381)
		(stroke
			(width 0.05)
			(type default)
		)
		(layer "Edge.Cuts")
	)
	(gr_arc
		(start 391.139934 -300.57217)
		(mid 390.419102 -298.820868)
		(end 389.380984 -297.236896)
		(stroke
			(width 0.05)
			(type default)
		)
		(layer "Edge.Cuts")
	)
	(gr_arc
		(start 391.139934 -300.57217)
		(mid 393.675071 -302.450168)
		(end 396.210028 -300.57217)
		(stroke
			(width 0.05)
			(type default)
		)
		(layer "Edge.Cuts")
	)
	(gr_arc
		(start 391.139934 -185.572146)
		(mid 390.419099 -183.820846)
		(end 389.380984 -182.236872)
		(stroke
			(width 0.05)
			(type default)
		)
		(layer "Edge.Cuts")
	)
	(gr_arc
		(start 391.139934 -185.572146)
		(mid 393.675071 -187.450144)
		(end 396.210028 -185.572146)
		(stroke
			(width 0.05)
			(type default)
		)
		(layer "Edge.Cuts")
	)
	(gr_arc
		(start 391.139934 -70.572122)
		(mid 390.419095 -68.820824)
		(end 389.380984 -67.236848)
		(stroke
			(width 0.05)
			(type default)
		)
		(layer "Edge.Cuts")
	)
	(gr_arc
		(start 391.139934 -70.572122)
		(mid 393.675071 -72.45012)
		(end 396.210028 -70.572122)
		(stroke
			(width 0.05)
			(type default)
		)
		(layer "Edge.Cuts")
	)
	(gr_arc
		(start 397.968978 -297.236896)
		(mid 393.675187 -288.300075)
		(end 389.380984 -297.236896)
		(stroke
			(width 0.05)
			(type default)
		)
		(layer "Edge.Cuts")
	)
	(gr_arc
		(start 397.968978 -297.236896)
		(mid 396.930891 -298.820885)
		(end 396.210028 -300.57217)
		(stroke
			(width 0.05)
			(type default)
		)
		(layer "Edge.Cuts")
	)
	(gr_arc
		(start 397.968978 -182.236872)
		(mid 393.675187 -173.300051)
		(end 389.380984 -182.236872)
		(stroke
			(width 0.05)
			(type default)
		)
		(layer "Edge.Cuts")
	)
	(gr_arc
		(start 397.968978 -182.236872)
		(mid 396.930888 -183.82086)
		(end 396.210028 -185.572146)
		(stroke
			(width 0.05)
			(type default)
		)
		(layer "Edge.Cuts")
	)
	(gr_arc
		(start 397.968978 -67.236848)
		(mid 393.675187 -58.300027)
		(end 389.380984 -67.236848)
		(stroke
			(width 0.05)
			(type default)
		)
		(layer "Edge.Cuts")
	)
	(gr_arc
		(start 397.968978 -67.236848)
		(mid 396.930899 -68.82084)
		(end 396.210028 -70.572122)
		(stroke
			(width 0.05)
			(type default)
		)
		(layer "Edge.Cuts")
	)
	(gr_arc
		(start 402.625052 -23.999952)
		(mid 404.400004 -25.774904)
		(end 406.174956 -23.999952)
		(stroke
			(width 0.05)
			(type default)
		)
		(layer "Edge.Cuts")
	)
	(gr_arc
		(start 406.174956 -23.999952)
		(mid 404.400004 -22.225)
		(end 402.625052 -23.999952)
		(stroke
			(width 0.05)
			(type default)
		)
		(layer "Edge.Cuts")
	)
	(gr_line
		(start 416.699954 -380.000002)
		(end 364.700058 -380.000002)
		(stroke
			(width 0.05)
			(type default)
		)
		(layer "Edge.Cuts")
	)
	(gr_line
		(start 417.699952 -384.999992)
		(end 417.699952 -381)
		(stroke
			(width 0.05)
			(type default)
		)
		(layer "Edge.Cuts")
	)
	(gr_arc
		(start 417.699952 -384.999992)
		(mid 417.992839 -385.70712)
		(end 418.69995 -385.99999)
		(stroke
			(width 0.05)
			(type default)
		)
		(layer "Edge.Cuts")
	)
	(gr_arc
		(start 417.699952 -381)
		(mid 417.407059 -380.292895)
		(end 416.699954 -380.000002)
		(stroke
			(width 0.05)
			(type default)
		)
		(layer "Edge.Cuts")
	)
	(gr_arc
		(start 420.075106 -66.799968)
		(mid 425.175172 -71.900034)
		(end 430.274984 -66.799968)
		(stroke
			(width 0.05)
			(type default)
		)
		(layer "Edge.Cuts")
	)
	(gr_arc
		(start 430.274984 -66.799968)
		(mid 425.175172 -61.700156)
		(end 420.075106 -66.799968)
		(stroke
			(width 0.05)
			(type default)
		)
		(layer "Edge.Cuts")
	)
	(gr_arc
		(start 454.140062 -300.57217)
		(mid 453.419232 -298.820867)
		(end 452.381112 -297.236896)
		(stroke
			(width 0.05)
			(type default)
		)
		(layer "Edge.Cuts")
	)
	(gr_arc
		(start 454.140062 -300.57217)
		(mid 456.675199 -302.450168)
		(end 459.210156 -300.57217)
		(stroke
			(width 0.05)
			(type default)
		)
		(layer "Edge.Cuts")
	)
	(gr_arc
		(start 454.140062 -185.572146)
		(mid 453.419228 -183.820845)
		(end 452.381112 -182.236872)
		(stroke
			(width 0.05)
			(type default)
		)
		(layer "Edge.Cuts")
	)
	(gr_arc
		(start 454.140062 -185.572146)
		(mid 456.675199 -187.450144)
		(end 459.210156 -185.572146)
		(stroke
			(width 0.05)
			(type default)
		)
		(layer "Edge.Cuts")
	)
	(gr_arc
		(start 454.140062 -70.572122)
		(mid 453.419225 -68.820823)
		(end 452.381112 -67.236848)
		(stroke
			(width 0.05)
			(type default)
		)
		(layer "Edge.Cuts")
	)
	(gr_arc
		(start 454.140062 -70.572122)
		(mid 456.675199 -72.45012)
		(end 459.210156 -70.572122)
		(stroke
			(width 0.05)
			(type default)
		)
		(layer "Edge.Cuts")
	)
	(gr_arc
		(start 460.968852 -297.236896)
		(mid 456.674982 -288.300075)
		(end 452.381112 -297.236896)
		(stroke
			(width 0.05)
			(type default)
		)
		(layer "Edge.Cuts")
	)
	(gr_arc
		(start 460.968852 -297.236896)
		(mid 459.930898 -298.820899)
		(end 459.210156 -300.57217)
		(stroke
			(width 0.05)
			(type default)
		)
		(layer "Edge.Cuts")
	)
	(gr_arc
		(start 460.968852 -182.236872)
		(mid 456.674982 -173.300051)
		(end 452.381112 -182.236872)
		(stroke
			(width 0.05)
			(type default)
		)
		(layer "Edge.Cuts")
	)
	(gr_arc
		(start 460.968852 -182.236872)
		(mid 459.930894 -183.820874)
		(end 459.210156 -185.572146)
		(stroke
			(width 0.05)
			(type default)
		)
		(layer "Edge.Cuts")
	)
	(gr_arc
		(start 460.968852 -67.236848)
		(mid 456.674982 -58.300027)
		(end 452.381112 -67.236848)
		(stroke
			(width 0.05)
			(type default)
		)
		(layer "Edge.Cuts")
	)
	(gr_arc
		(start 460.968852 -67.236848)
		(mid 459.930891 -68.820849)
		(end 459.210156 -70.572122)
		(stroke
			(width 0.05)
			(type default)
		)
		(layer "Edge.Cuts")
	)
	(gr_line
		(start 464.250024 -385.99999)
		(end 418.69995 -385.99999)
		(stroke
			(width 0.05)
			(type default)
		)
		(layer "Edge.Cuts")
	)
	(gr_arc
		(start 464.250024 -385.99999)
		(mid 464.957111 -385.707088)
		(end 465.250022 -384.999992)
		(stroke
			(width 0.05)
			(type default)
		)
		(layer "Edge.Cuts")
	)
	(gr_line
		(start 465.250022 -383.29997)
		(end 465.250022 -384.999992)
		(stroke
			(width 0.05)
			(type default)
		)
		(layer "Edge.Cuts")
	)
	(gr_arc
		(start 465.725002 -13.999972)
		(mid 467.499954 -15.774924)
		(end 469.274906 -13.999972)
		(stroke
			(width 0.05)
			(type default)
		)
		(layer "Edge.Cuts")
	)
	(gr_arc
		(start 466.099906 -30.999938)
		(mid 467.499954 -32.399986)
		(end 468.900002 -30.999938)
		(stroke
			(width 0.05)
			(type default)
		)
		(layer "Edge.Cuts")
	)
	(gr_arc
		(start 466.25002 -382.299972)
		(mid 465.542915 -382.592865)
		(end 465.250022 -383.29997)
		(stroke
			(width 0.05)
			(type default)
		)
		(layer "Edge.Cuts")
	)
	(gr_arc
		(start 468.900002 -30.999938)
		(mid 467.499954 -29.59989)
		(end 466.099906 -30.999938)
		(stroke
			(width 0.05)
			(type default)
		)
		(layer "Edge.Cuts")
	)
	(gr_arc
		(start 469.274906 -13.999972)
		(mid 467.499954 -12.22502)
		(end 465.725002 -13.999972)
		(stroke
			(width 0.05)
			(type default)
		)
		(layer "Edge.Cuts")
	)
	(gr_line
		(start 472.74988 -382.299972)
		(end 466.25002 -382.299972)
		(stroke
			(width 0.05)
			(type default)
		)
		(layer "Edge.Cuts")
	)
	(gr_line
		(start 473.749878 -384.999992)
		(end 473.749878 -383.29997)
		(stroke
			(width 0.05)
			(type default)
		)
		(layer "Edge.Cuts")
	)
	(gr_arc
		(start 473.749878 -384.999992)
		(mid 474.042766 -385.707111)
		(end 474.749876 -385.99999)
		(stroke
			(width 0.05)
			(type default)
		)
		(layer "Edge.Cuts")
	)
	(gr_arc
		(start 473.749878 -383.29997)
		(mid 473.456985 -382.592865)
		(end 472.74988 -382.299972)
		(stroke
			(width 0.05)
			(type default)
		)
		(layer "Edge.Cuts")
	)
	(gr_line
		(start 487.449876 -385.99999)
		(end 474.749876 -385.99999)
		(stroke
			(width 0.05)
			(type default)
		)
		(layer "Edge.Cuts")
	)
	(gr_arc
		(start 487.449876 -385.99999)
		(mid 488.156994 -385.707105)
		(end 488.449874 -384.999992)
		(stroke
			(width 0.05)
			(type default)
		)
		(layer "Edge.Cuts")
	)
	(gr_line
		(start 488.449874 -372.000018)
		(end 488.449874 -384.999992)
		(stroke
			(width 0.05)
			(type default)
		)
		(layer "Edge.Cuts")
	)
	(gr_arc
		(start 489.450126 -371.00002)
		(mid 488.742856 -371.292823)
		(end 488.449874 -372.000018)
		(stroke
			(width 0.05)
			(type default)
		)
		(layer "Edge.Cuts")
	)
	(gr_line
		(start 490.450124 -371.00002)
		(end 489.450126 -371.00002)
		(stroke
			(width 0.05)
			(type default)
		)
		(layer "Edge.Cuts")
	)
	(gr_arc
		(start 490.450124 -371.00002)
		(mid 491.157222 -370.70712)
		(end 491.450122 -370.000022)
		(stroke
			(width 0.05)
			(type default)
		)
		(layer "Edge.Cuts")
	)
	(gr_arc
		(start 491.450122 -0.999998)
		(mid 491.15723 -0.292885)
		(end 490.450124 0)
		(stroke
			(width 0.05)
			(type default)
		)
		(layer "Edge.Cuts")
	)
	(gr_line
		(start 491.450122 -0.999998)
		(end 491.450122 -370.000022)
		(stroke
			(width 0.05)
			(type default)
		)
		(layer "Edge.Cuts")
	)
	(segment
		(start 260.224778 -237.621318)
		(end 260.102096 -237.744)
		(width 0.17145)
		(layer "F.Cu")
		(net "SCC_B_FULL_PWR_EN_12V")
	)
	(segment
		(start 260.224778 -234.821222)
		(end 260.477 -234.569)
		(width 0.17145)
		(layer "F.Cu")
		(net "SCC_B_FULL_PWR_EN_12V")
	)
	(segment
		(start 260.102096 -237.744)
		(end 260.102096 -238.583724)
		(width 0.17145)
		(layer "F.Cu")
		(net "SCC_B_FULL_PWR_EN_12V")
	)
	(segment
		(start 260.477 -234.569)
		(end 260.477 -233.553)
		(width 0.17145)
		(layer "F.Cu")
		(net "SCC_B_FULL_PWR_EN_12V")
	)
	(segment
		(start 259.04825 -233.2355)
		(end 260.1595 -233.2355)
		(width 0.17145)
		(layer "F.Cu")
		(net "SCC_B_FULL_PWR_EN_12V")
	)
	(segment
		(start 260.1595 -233.2355)
		(end 260.477 -233.553)
		(width 0.17145)
		(layer "F.Cu")
		(net "SCC_B_FULL_PWR_EN_12V")
	)
	(segment
		(start 260.224778 -236.1565)
		(end 260.224778 -234.821222)
		(width 0.17145)
		(layer "F.Cu")
		(net "SCC_B_FULL_PWR_EN_12V")
	)
	(segment
		(start 260.224778 -236.1565)
		(end 260.224778 -237.621318)
		(width 0.17145)
		(layer "F.Cu")
		(net "SCC_B_FULL_PWR_EN_12V")
	)
	(via
		(at 260.477 -233.553)
		(size 0.6604)
		(drill 0.3302)
		(layers "F.Cu" "B.Cu")
		(net "SCC_B_FULL_PWR_EN_12V")
	)
	(segment
		(start 255.397 -232.41)
		(end 255.143 -232.664)
		(width 0.17145)
		(layer "F.Cu")
		(net "SCC_FULL_PWR_EN_5V_R")
	)
	(segment
		(start 254.127 -231.3305)
		(end 254.127 -232.41)
		(width 0.17145)
		(layer "F.Cu")
		(net "SCC_FULL_PWR_EN_5V_R")
	)
	(segment
		(start 254.127 -232.41)
		(end 254.381 -232.664)
		(width 0.17145)
		(layer "F.Cu")
		(net "SCC_FULL_PWR_EN_5V_R")
	)
	(segment
		(start 255.143 -232.664)
		(end 254.762 -232.664)
		(width 0.17145)
		(layer "F.Cu")
		(net "SCC_FULL_PWR_EN_5V_R")
	)
	(segment
		(start 255.397 -231.3305)
		(end 255.397 -232.41)
		(width 0.17145)
		(layer "F.Cu")
		(net "SCC_FULL_PWR_EN_5V_R")
	)
	(segment
		(start 255.397 -231.3305)
		(end 258.064 -231.3305)
		(width 0.17145)
		(layer "F.Cu")
		(net "SCC_FULL_PWR_EN_5V_R")
	)
	(segment
		(start 254.381 -232.664)
		(end 254.762 -232.664)
		(width 0.17145)
		(layer "F.Cu")
		(net "SCC_FULL_PWR_EN_5V_R")
	)
	(via
		(at 254.762 -232.664)
		(size 0.6604)
		(drill 0.3302)
		(layers "F.Cu" "B.Cu")
		(net "SCC_FULL_PWR_EN_5V_R")
	)
	(segment
		(start 259.60832 -244.024912)
		(end 259.60832 -244.020086)
		(width 0.17145)
		(layer "F.Cu")
		(net "SCC_FULL_PWR_EN_5V")
	)
	(segment
		(start 238.22025 -218.674188)
		(end 235.779818 -216.233756)
		(width 0.17145)
		(layer "F.Cu")
		(net "SCC_FULL_PWR_EN_5V")
	)
	(segment
		(start 256.455164 -230.4415)
		(end 255.397 -230.4415)
		(width 0.17145)
		(layer "F.Cu")
		(net "SCC_FULL_PWR_EN_5V")
	)
	(segment
		(start 237.024418 -213.063582)
		(end 239.596676 -213.063582)
		(width 0.17145)
		(layer "F.Cu")
		(net "SCC_FULL_PWR_EN_5V")
	)
	(segment
		(start 256.468626 -230.454962)
		(end 256.455164 -230.4415)
		(width 0.17145)
		(layer "F.Cu")
		(net "SCC_FULL_PWR_EN_5V")
	)
	(segment
		(start 260.747764 -230.454962)
		(end 256.468626 -230.454962)
		(width 0.17145)
		(layer "F.Cu")
		(net "SCC_FULL_PWR_EN_5V")
	)
	(segment
		(start 235.779818 -216.233756)
		(end 235.779818 -214.308182)
		(width 0.17145)
		(layer "F.Cu")
		(net "SCC_FULL_PWR_EN_5V")
	)
	(segment
		(start 229.362 -193.7258)
		(end 229.362 -192.77965)
		(width 0.17145)
		(layer "F.Cu")
		(net "SCC_FULL_PWR_EN_5V")
	)
	(segment
		(start 240.6015 -231.61625)
		(end 240.601246 -231.61625)
		(width 0.17145)
		(layer "F.Cu")
		(net "SCC_FULL_PWR_EN_5V")
	)
	(segment
		(start 229.4382 -193.8528)
		(end 229.4382 -193.802)
		(width 0.17145)
		(layer "F.Cu")
		(net "SCC_FULL_PWR_EN_5V")
	)
	(segment
		(start 247.204484 -231.61625)
		(end 240.6015 -231.61625)
		(width 0.17145)
		(layer "F.Cu")
		(net "SCC_FULL_PWR_EN_5V")
	)
	(segment
		(start 237.416086 -225.752914)
		(end 238.22025 -224.94875)
		(width 0.17145)
		(layer "F.Cu")
		(net "SCC_FULL_PWR_EN_5V")
	)
	(segment
		(start 238.886746 -229.90175)
		(end 237.416086 -228.43109)
		(width 0.17145)
		(layer "F.Cu")
		(net "SCC_FULL_PWR_EN_5V")
	)
	(segment
		(start 229.362 -192.77965)
		(end 229.39375 -192.7479)
		(width 0.17145)
		(layer "F.Cu")
		(net "SCC_FULL_PWR_EN_5V")
	)
	(segment
		(start 235.779818 -214.308182)
		(end 237.024418 -213.063582)
		(width 0.17145)
		(layer "F.Cu")
		(net "SCC_FULL_PWR_EN_5V")
	)
	(segment
		(start 261.838948 -231.546146)
		(end 260.747764 -230.454962)
		(width 0.17145)
		(layer "F.Cu")
		(net "SCC_FULL_PWR_EN_5V")
	)
	(segment
		(start 238.22025 -220.9165)
		(end 238.22025 -218.674188)
		(width 0.17145)
		(layer "F.Cu")
		(net "SCC_FULL_PWR_EN_5V")
	)
	(segment
		(start 240.601246 -231.61625)
		(end 238.886746 -229.90175)
		(width 0.17145)
		(layer "F.Cu")
		(net "SCC_FULL_PWR_EN_5V")
	)
	(segment
		(start 237.416086 -228.43109)
		(end 237.416086 -225.752914)
		(width 0.17145)
		(layer "F.Cu")
		(net "SCC_FULL_PWR_EN_5V")
	)
	(segment
		(start 261.838948 -241.794284)
		(end 261.838948 -231.546146)
		(width 0.17145)
		(layer "F.Cu")
		(net "SCC_FULL_PWR_EN_5V")
	)
	(segment
		(start 238.22025 -224.94875)
		(end 238.22025 -220.9165)
		(width 0.17145)
		(layer "F.Cu")
		(net "SCC_FULL_PWR_EN_5V")
	)
	(segment
		(start 259.60832 -244.020086)
		(end 247.204484 -231.61625)
		(width 0.17145)
		(layer "F.Cu")
		(net "SCC_FULL_PWR_EN_5V")
	)
	(segment
		(start 229.4382 -193.802)
		(end 229.362 -193.7258)
		(width 0.17145)
		(layer "F.Cu")
		(net "SCC_FULL_PWR_EN_5V")
	)
	(via
		(at 238.886746 -229.90175)
		(size 0.6604)
		(drill 0.3302)
		(layers "F.Cu" "B.Cu")
		(net "SCC_FULL_PWR_EN_5V")
	)
	(via
		(at 259.60832 -244.024912)
		(size 0.5588)
		(drill 0.3048)
		(layers "F.Cu" "B.Cu")
		(net "SCC_FULL_PWR_EN_5V")
	)
	(via
		(at 229.4382 -193.8528)
		(size 0.5588)
		(drill 0.3048)
		(layers "F.Cu" "B.Cu")
		(net "SCC_FULL_PWR_EN_5V")
	)
	(via
		(at 239.596676 -213.063582)
		(size 0.5588)
		(drill 0.3048)
		(layers "F.Cu" "B.Cu")
		(net "SCC_FULL_PWR_EN_5V")
	)
	(via
		(at 261.838948 -241.794284)
		(size 0.5588)
		(drill 0.3048)
		(layers "F.Cu" "B.Cu")
		(net "SCC_FULL_PWR_EN_5V")
	)
	(segment
		(start 239.596676 -213.063582)
		(end 239.596676 -211.279232)
		(width 0.14605)
		(layer "In5.Cu")
		(net "SCC_FULL_PWR_EN_5V")
	)
	(segment
		(start 230.505 -195.4276)
		(end 229.4382 -194.3608)
		(width 0.14605)
		(layer "In5.Cu")
		(net "SCC_FULL_PWR_EN_5V")
	)
	(segment
		(start 232.2068 -195.4276)
		(end 230.505 -195.4276)
		(width 0.14605)
		(layer "In5.Cu")
		(net "SCC_FULL_PWR_EN_5V")
	)
	(segment
		(start 240.6904 -210.185508)
		(end 240.6904 -202.2348)
		(width 0.14605)
		(layer "In5.Cu")
		(net "SCC_FULL_PWR_EN_5V")
	)
	(segment
		(start 239.596676 -211.279232)
		(end 240.6904 -210.185508)
		(width 0.14605)
		(layer "In5.Cu")
		(net "SCC_FULL_PWR_EN_5V")
	)
	(segment
		(start 229.4382 -194.3608)
		(end 229.4382 -193.8528)
		(width 0.14605)
		(layer "In5.Cu")
		(net "SCC_FULL_PWR_EN_5V")
	)
	(segment
		(start 237.3376 -198.882)
		(end 235.6612 -198.882)
		(width 0.14605)
		(layer "In5.Cu")
		(net "SCC_FULL_PWR_EN_5V")
	)
	(segment
		(start 235.6612 -198.882)
		(end 232.2068 -195.4276)
		(width 0.14605)
		(layer "In5.Cu")
		(net "SCC_FULL_PWR_EN_5V")
	)
	(segment
		(start 259.60832 -244.024912)
		(end 261.838948 -241.794284)
		(width 0.14605)
		(layer "In5.Cu")
		(net "SCC_FULL_PWR_EN_5V")
	)
	(segment
		(start 240.6904 -202.2348)
		(end 237.3376 -198.882)
		(width 0.14605)
		(layer "In5.Cu")
		(net "SCC_FULL_PWR_EN_5V")
	)
	(segment
		(start 235.458 -192.86728)
		(end 235.00588 -192.86728)
		(width 0.254)
		(layer "F.Cu")
		(net "GPIO_VCC_U9")
	)
	(segment
		(start 235.0516 -194.60718)
		(end 235.6485 -194.01028)
		(width 0.254)
		(layer "F.Cu")
		(net "GPIO_VCC_U9")
	)
	(segment
		(start 235.6485 -193.05778)
		(end 235.458 -192.86728)
		(width 0.254)
		(layer "F.Cu")
		(net "GPIO_VCC_U9")
	)
	(segment
		(start 235.00588 -192.86728)
		(end 234.4801 -192.3415)
		(width 0.254)
		(layer "F.Cu")
		(net "GPIO_VCC_U9")
	)
	(segment
		(start 234.2134 -192.3415)
		(end 232.905554 -192.3415)
		(width 0.254)
		(layer "F.Cu")
		(net "GPIO_VCC_U9")
	)
	(segment
		(start 232.905554 -192.3415)
		(end 231.76865 -192.3415)
		(width 0.254)
		(layer "F.Cu")
		(net "GPIO_VCC_U9")
	)
	(segment
		(start 231.76865 -192.3415)
		(end 231.36225 -192.7479)
		(width 0.254)
		(layer "F.Cu")
		(net "GPIO_VCC_U9")
	)
	(segment
		(start 235.0516 -195.50888)
		(end 235.0516 -194.60718)
		(width 0.254)
		(layer "F.Cu")
		(net "GPIO_VCC_U9")
	)
	(segment
		(start 235.6485 -194.01028)
		(end 235.6485 -193.05778)
		(width 0.254)
		(layer "F.Cu")
		(net "GPIO_VCC_U9")
	)
	(segment
		(start 234.4801 -192.3415)
		(end 234.2134 -192.3415)
		(width 0.254)
		(layer "F.Cu")
		(net "GPIO_VCC_U9")
	)
	(via
		(at 232.905554 -192.3415)
		(size 0.6604)
		(drill 0.3302)
		(layers "F.Cu" "B.Cu")
		(net "GPIO_VCC_U9")
	)
	(via
		(at 234.560872 -222.261176)
		(size 0.6604)
		(drill 0.3302)
		(layers "F.Cu" "B.Cu")
		(net "GPIO_VCC_U8")
	)
	(via
		(at 241.140234 -228.204268)
		(size 0.6604)
		(drill 0.3302)
		(layers "F.Cu" "B.Cu")
		(net "GPIO_VCC_U10")
	)
	(segment
		(start 457.656184 -375.15546)
		(end 457.656184 -373.89562)
		(width 0.254)
		(layer "F.Cu")
		(net "FAN_LED3_D2")
	)
	(segment
		(start 458.815694 -373.634)
		(end 457.917804 -373.634)
		(width 0.254)
		(layer "F.Cu")
		(net "FAN_LED3_D2")
	)
	(segment
		(start 457.656184 -373.89562)
		(end 457.841604 -373.7102)
		(width 0.254)
		(layer "F.Cu")
		(net "FAN_LED3_D2")
	)
	(segment
		(start 457.917804 -373.634)
		(end 457.841604 -373.7102)
		(width 0.254)
		(layer "F.Cu")
		(net "FAN_LED3_D2")
	)
	(via
		(at 457.841604 -373.7102)
		(size 0.6604)
		(drill 0.3302)
		(layers "F.Cu" "B.Cu")
		(net "FAN_LED3_D2")
	)
	(segment
		(start 322.614036 -375.65584)
		(end 322.751196 -375.793)
		(width 0.254)
		(layer "F.Cu")
		(net "FAN_LED2_D2")
	)
	(segment
		(start 322.920106 -376.7836)
		(end 322.920106 -375.96191)
		(width 0.254)
		(layer "F.Cu")
		(net "FAN_LED2_D2")
	)
	(segment
		(start 322.920106 -375.96191)
		(end 322.751196 -375.793)
		(width 0.254)
		(layer "F.Cu")
		(net "FAN_LED2_D2")
	)
	(segment
		(start 321.252596 -375.65584)
		(end 322.614036 -375.65584)
		(width 0.254)
		(layer "F.Cu")
		(net "FAN_LED2_D2")
	)
	(via
		(at 322.751196 -375.793)
		(size 0.6604)
		(drill 0.3302)
		(layers "F.Cu" "B.Cu")
		(net "FAN_LED2_D2")
	)
	(segment
		(start 190.778638 -370.400326)
		(end 190.304928 -370.874036)
		(width 0.254)
		(layer "F.Cu")
		(net "FAN_LED1_D2")
	)
	(segment
		(start 190.304928 -370.874036)
		(end 190.177928 -370.874036)
		(width 0.254)
		(layer "F.Cu")
		(net "FAN_LED1_D2")
	)
	(segment
		(start 189.542928 -370.787676)
		(end 188.806328 -370.787676)
		(width 0.254)
		(layer "F.Cu")
		(net "FAN_LED1_D2")
	)
	(segment
		(start 191.219328 -370.400326)
		(end 190.778638 -370.400326)
		(width 0.254)
		(layer "F.Cu")
		(net "FAN_LED1_D2")
	)
	(segment
		(start 190.177928 -370.874036)
		(end 189.629288 -370.874036)
		(width 0.254)
		(layer "F.Cu")
		(net "FAN_LED1_D2")
	)
	(segment
		(start 189.629288 -370.874036)
		(end 189.542928 -370.787676)
		(width 0.254)
		(layer "F.Cu")
		(net "FAN_LED1_D2")
	)
	(via
		(at 190.177928 -370.874036)
		(size 0.6604)
		(drill 0.3302)
		(layers "F.Cu" "B.Cu")
		(net "FAN_LED1_D2")
	)
	(segment
		(start 31.705296 -374.79986)
		(end 31.530036 -374.6246)
		(width 0.254)
		(layer "F.Cu")
		(net "FAN_LED0_D2")
	)
	(segment
		(start 31.705296 -375.6914)
		(end 31.705296 -374.79986)
		(width 0.254)
		(layer "F.Cu")
		(net "FAN_LED0_D2")
	)
	(segment
		(start 30.117796 -374.53824)
		(end 31.443676 -374.53824)
		(width 0.254)
		(layer "F.Cu")
		(net "FAN_LED0_D2")
	)
	(segment
		(start 31.443676 -374.53824)
		(end 31.530036 -374.6246)
		(width 0.254)
		(layer "F.Cu")
		(net "FAN_LED0_D2")
	)
	(via
		(at 31.530036 -374.6246)
		(size 0.6604)
		(drill 0.3302)
		(layers "F.Cu" "B.Cu")
		(net "FAN_LED0_D2")
	)
	(segment
		(start 457.181204 -378.4854)
		(end 457.105004 -378.4092)
		(width 0.254)
		(layer "F.Cu")
		(net "FAN_LED3_D")
	)
	(segment
		(start 456.355704 -376.3137)
		(end 456.355704 -377.03506)
		(width 0.254)
		(layer "F.Cu")
		(net "FAN_LED3_D")
	)
	(segment
		(start 457.005944 -376.32894)
		(end 456.810872 -376.133868)
		(width 0.254)
		(layer "F.Cu")
		(net "FAN_LED3_D")
	)
	(segment
		(start 456.535536 -376.133868)
		(end 456.355704 -376.3137)
		(width 0.254)
		(layer "F.Cu")
		(net "FAN_LED3_D")
	)
	(segment
		(start 457.005944 -377.03506)
		(end 457.005944 -376.32894)
		(width 0.254)
		(layer "F.Cu")
		(net "FAN_LED3_D")
	)
	(segment
		(start 457.005944 -377.03506)
		(end 457.005944 -378.31014)
		(width 0.254)
		(layer "F.Cu")
		(net "FAN_LED3_D")
	)
	(segment
		(start 458.061314 -378.4854)
		(end 457.181204 -378.4854)
		(width 0.254)
		(layer "F.Cu")
		(net "FAN_LED3_D")
	)
	(segment
		(start 457.005944 -378.31014)
		(end 457.105004 -378.4092)
		(width 0.254)
		(layer "F.Cu")
		(net "FAN_LED3_D")
	)
	(segment
		(start 456.810872 -376.133868)
		(end 456.535536 -376.133868)
		(width 0.254)
		(layer "F.Cu")
		(net "FAN_LED3_D")
	)
	(via
		(at 457.105004 -378.4092)
		(size 0.6604)
		(drill 0.3302)
		(layers "F.Cu" "B.Cu")
		(net "FAN_LED3_D")
	)
	(segment
		(start 319.372996 -375.0056)
		(end 318.229996 -375.0056)
		(width 0.254)
		(layer "F.Cu")
		(net "FAN_LED2_D")
	)
	(segment
		(start 317.975996 -375.2596)
		(end 318.077596 -375.158)
		(width 0.254)
		(layer "F.Cu")
		(net "FAN_LED2_D")
	)
	(segment
		(start 320.264028 -374.525032)
		(end 320.264028 -374.825768)
		(width 0.254)
		(layer "F.Cu")
		(net "FAN_LED2_D")
	)
	(segment
		(start 317.975996 -376.15749)
		(end 317.975996 -375.2596)
		(width 0.254)
		(layer "F.Cu")
		(net "FAN_LED2_D")
	)
	(segment
		(start 320.084196 -375.0056)
		(end 319.372996 -375.0056)
		(width 0.254)
		(layer "F.Cu")
		(net "FAN_LED2_D")
	)
	(segment
		(start 320.094356 -374.35536)
		(end 320.264028 -374.525032)
		(width 0.254)
		(layer "F.Cu")
		(net "FAN_LED2_D")
	)
	(segment
		(start 318.229996 -375.0056)
		(end 318.077596 -375.158)
		(width 0.254)
		(layer "F.Cu")
		(net "FAN_LED2_D")
	)
	(segment
		(start 320.264028 -374.825768)
		(end 320.084196 -375.0056)
		(width 0.254)
		(layer "F.Cu")
		(net "FAN_LED2_D")
	)
	(segment
		(start 319.372996 -374.35536)
		(end 320.094356 -374.35536)
		(width 0.254)
		(layer "F.Cu")
		(net "FAN_LED2_D")
	)
	(via
		(at 318.077596 -375.158)
		(size 0.6604)
		(drill 0.3302)
		(layers "F.Cu" "B.Cu")
		(net "FAN_LED2_D")
	)
	(segment
		(start 185.478928 -370.239036)
		(end 185.504328 -370.213636)
		(width 0.254)
		(layer "F.Cu")
		(net "FAN_LED1_D")
	)
	(segment
		(start 185.478928 -371.162326)
		(end 185.478928 -370.239036)
		(width 0.254)
		(layer "F.Cu")
		(net "FAN_LED1_D")
	)
	(segment
		(start 187.587128 -370.137436)
		(end 186.926728 -370.137436)
		(width 0.254)
		(layer "F.Cu")
		(net "FAN_LED1_D")
	)
	(segment
		(start 186.926728 -369.487196)
		(end 187.571888 -369.487196)
		(width 0.254)
		(layer "F.Cu")
		(net "FAN_LED1_D")
	)
	(segment
		(start 186.926728 -370.137436)
		(end 185.580528 -370.137436)
		(width 0.254)
		(layer "F.Cu")
		(net "FAN_LED1_D")
	)
	(segment
		(start 187.76696 -369.957604)
		(end 187.587128 -370.137436)
		(width 0.254)
		(layer "F.Cu")
		(net "FAN_LED1_D")
	)
	(segment
		(start 185.580528 -370.137436)
		(end 185.504328 -370.213636)
		(width 0.254)
		(layer "F.Cu")
		(net "FAN_LED1_D")
	)
	(segment
		(start 187.76696 -369.682268)
		(end 187.76696 -369.957604)
		(width 0.254)
		(layer "F.Cu")
		(net "FAN_LED1_D")
	)
	(segment
		(start 187.571888 -369.487196)
		(end 187.76696 -369.682268)
		(width 0.254)
		(layer "F.Cu")
		(net "FAN_LED1_D")
	)
	(via
		(at 185.504328 -370.213636)
		(size 0.6604)
		(drill 0.3302)
		(layers "F.Cu" "B.Cu")
		(net "FAN_LED1_D")
	)
	(segment
		(start 26.790396 -374.20169)
		(end 26.790396 -373.38)
		(width 0.254)
		(layer "F.Cu")
		(net "FAN_LED0_D")
	)
	(segment
		(start 29.230828 -373.458232)
		(end 29.230828 -373.708168)
		(width 0.254)
		(layer "F.Cu")
		(net "FAN_LED0_D")
	)
	(segment
		(start 26.790396 -373.38)
		(end 26.917396 -373.253)
		(width 0.254)
		(layer "F.Cu")
		(net "FAN_LED0_D")
	)
	(segment
		(start 29.050996 -373.888)
		(end 28.238196 -373.888)
		(width 0.254)
		(layer "F.Cu")
		(net "FAN_LED0_D")
	)
	(segment
		(start 29.230828 -373.708168)
		(end 29.050996 -373.888)
		(width 0.254)
		(layer "F.Cu")
		(net "FAN_LED0_D")
	)
	(segment
		(start 28.238196 -373.23776)
		(end 26.932636 -373.23776)
		(width 0.254)
		(layer "F.Cu")
		(net "FAN_LED0_D")
	)
	(segment
		(start 28.238196 -373.23776)
		(end 29.010356 -373.23776)
		(width 0.254)
		(layer "F.Cu")
		(net "FAN_LED0_D")
	)
	(segment
		(start 26.932636 -373.23776)
		(end 26.917396 -373.253)
		(width 0.254)
		(layer "F.Cu")
		(net "FAN_LED0_D")
	)
	(segment
		(start 29.010356 -373.23776)
		(end 29.230828 -373.458232)
		(width 0.254)
		(layer "F.Cu")
		(net "FAN_LED0_D")
	)
	(via
		(at 26.917396 -373.253)
		(size 0.6604)
		(drill 0.3302)
		(layers "F.Cu" "B.Cu")
		(net "FAN_LED0_D")
	)
	(segment
		(start 215.4936 -192.151)
		(end 215.4936 -197.5866)
		(width 0.254)
		(layer "F.Cu")
		(net "RDPB_FAN_LED3")
	)
	(segment
		(start 215.4936 -197.5866)
		(end 209.420206 -203.659994)
		(width 0.254)
		(layer "F.Cu")
		(net "RDPB_FAN_LED3")
	)
	(segment
		(start 456.353164 -369.37696)
		(end 455.784204 -368.808)
		(width 0.254)
		(layer "F.Cu")
		(net "RDPB_FAN_LED3")
	)
	(segment
		(start 275.4376 -305.8668)
		(end 274.573746 -306.730654)
		(width 0.254)
		(layer "F.Cu")
		(net "RDPB_FAN_LED3")
	)
	(segment
		(start 200.358756 -296.4688)
		(end 199.241156 -295.3512)
		(width 0.254)
		(layer "F.Cu")
		(net "RDPB_FAN_LED3")
	)
	(segment
		(start 252.454156 -302.3108)
		(end 248.720356 -302.3108)
		(width 0.254)
		(layer "F.Cu")
		(net "RDPB_FAN_LED3")
	)
	(segment
		(start 217.2716 -191.1604)
		(end 216.4842 -191.1604)
		(width 0.254)
		(layer "F.Cu")
		(net "RDPB_FAN_LED3")
	)
	(segment
		(start 248.720356 -302.3108)
		(end 242.878356 -296.4688)
		(width 0.254)
		(layer "F.Cu")
		(net "RDPB_FAN_LED3")
	)
	(segment
		(start 216.4842 -191.1604)
		(end 215.4936 -192.151)
		(width 0.254)
		(layer "F.Cu")
		(net "RDPB_FAN_LED3")
	)
	(segment
		(start 455.784204 -367.3856)
		(end 455.784204 -368.383312)
		(width 0.254)
		(layer "F.Cu")
		(net "RDPB_FAN_LED3")
	)
	(segment
		(start 242.878356 -296.4688)
		(end 200.358756 -296.4688)
		(width 0.254)
		(layer "F.Cu")
		(net "RDPB_FAN_LED3")
	)
	(segment
		(start 209.420206 -203.659994)
		(end 204.592682 -203.659994)
		(width 0.254)
		(layer "F.Cu")
		(net "RDPB_FAN_LED3")
	)
	(segment
		(start 274.573746 -306.730654)
		(end 256.87401 -306.730654)
		(width 0.254)
		(layer "F.Cu")
		(net "RDPB_FAN_LED3")
	)
	(segment
		(start 256.87401 -306.730654)
		(end 252.454156 -302.3108)
		(width 0.254)
		(layer "F.Cu")
		(net "RDPB_FAN_LED3")
	)
	(segment
		(start 455.784204 -368.808)
		(end 455.784204 -368.383312)
		(width 0.254)
		(layer "F.Cu")
		(net "RDPB_FAN_LED3")
	)
	(segment
		(start 199.241156 -295.3512)
		(end 198.12 -295.3512)
		(width 0.254)
		(layer "F.Cu")
		(net "RDPB_FAN_LED3")
	)
	(segment
		(start 456.353164 -370.0653)
		(end 456.353164 -369.37696)
		(width 0.254)
		(layer "F.Cu")
		(net "RDPB_FAN_LED3")
	)
	(segment
		(start 204.592682 -203.659994)
		(end 204.564488 -203.6318)
		(width 0.254)
		(layer "F.Cu")
		(net "RDPB_FAN_LED3")
	)
	(via
		(at 275.4376 -305.8668)
		(size 0.5588)
		(drill 0.3048)
		(layers "F.Cu" "B.Cu")
		(net "RDPB_FAN_LED3")
	)
	(via
		(at 204.564488 -203.6318)
		(size 0.5588)
		(drill 0.3048)
		(layers "F.Cu" "B.Cu")
		(net "RDPB_FAN_LED3")
	)
	(via
		(at 455.784204 -368.383312)
		(size 0.6604)
		(drill 0.3302)
		(layers "F.Cu" "B.Cu")
		(net "RDPB_FAN_LED3")
	)
	(via
		(at 198.12 -295.3512)
		(size 0.5588)
		(drill 0.3048)
		(layers "F.Cu" "B.Cu")
		(net "RDPB_FAN_LED3")
	)
	(via
		(at 455.784204 -367.3856)
		(size 0.5588)
		(drill 0.3048)
		(layers "F.Cu" "B.Cu")
		(net "RDPB_FAN_LED3")
	)
	(segment
		(start 200.476104 -247.885966)
		(end 200.476358 -247.88622)
		(width 0.254)
		(layer "In2.Cu")
		(net "RDPB_FAN_LED3")
	)
	(segment
		(start 203.555346 -215.226392)
		(end 203.555092 -215.226646)
		(width 0.254)
		(layer "In2.Cu")
		(net "RDPB_FAN_LED3")
	)
	(segment
		(start 203.555346 -218.160092)
		(end 203.555346 -220.52661)
		(width 0.254)
		(layer "In2.Cu")
		(net "RDPB_FAN_LED3")
	)
	(segment
		(start 200.476104 -250.998482)
		(end 200.476104 -290.54552)
		(width 0.254)
		(layer "In2.Cu")
		(net "RDPB_FAN_LED3")
	)
	(segment
		(start 200.476104 -223.605852)
		(end 200.476104 -247.885966)
		(width 0.254)
		(layer "In2.Cu")
		(net "RDPB_FAN_LED3")
	)
	(segment
		(start 203.555346 -204.945742)
		(end 203.555346 -215.226392)
		(width 0.254)
		(layer "In2.Cu")
		(net "RDPB_FAN_LED3")
	)
	(segment
		(start 203.555346 -220.52661)
		(end 200.476104 -223.605852)
		(width 0.254)
		(layer "In2.Cu")
		(net "RDPB_FAN_LED3")
	)
	(segment
		(start 200.476358 -250.998228)
		(end 200.476104 -250.998482)
		(width 0.254)
		(layer "In2.Cu")
		(net "RDPB_FAN_LED3")
	)
	(segment
		(start 203.555092 -218.159838)
		(end 203.555346 -218.160092)
		(width 0.254)
		(layer "In2.Cu")
		(net "RDPB_FAN_LED3")
	)
	(segment
		(start 200.476104 -290.54552)
		(end 198.12 -292.901624)
		(width 0.254)
		(layer "In2.Cu")
		(net "RDPB_FAN_LED3")
	)
	(segment
		(start 200.476358 -247.88622)
		(end 200.476358 -250.998228)
		(width 0.254)
		(layer "In2.Cu")
		(net "RDPB_FAN_LED3")
	)
	(segment
		(start 204.564488 -203.6318)
		(end 204.564488 -203.9366)
		(width 0.254)
		(layer "In2.Cu")
		(net "RDPB_FAN_LED3")
	)
	(segment
		(start 203.555092 -215.226646)
		(end 203.555092 -218.159838)
		(width 0.254)
		(layer "In2.Cu")
		(net "RDPB_FAN_LED3")
	)
	(segment
		(start 198.12 -292.901624)
		(end 198.12 -295.3512)
		(width 0.254)
		(layer "In2.Cu")
		(net "RDPB_FAN_LED3")
	)
	(segment
		(start 204.564488 -203.9366)
		(end 203.555346 -204.945742)
		(width 0.254)
		(layer "In2.Cu")
		(net "RDPB_FAN_LED3")
	)
	(segment
		(start 455.784204 -350.450404)
		(end 431.7746 -326.4408)
		(width 0.254)
		(layer "In5.Cu")
		(net "RDPB_FAN_LED3")
	)
	(segment
		(start 431.7746 -326.4408)
		(end 323.737478 -326.4408)
		(width 0.254)
		(layer "In5.Cu")
		(net "RDPB_FAN_LED3")
	)
	(segment
		(start 313.501278 -316.2046)
		(end 282.056078 -316.2046)
		(width 0.254)
		(layer "In5.Cu")
		(net "RDPB_FAN_LED3")
	)
	(segment
		(start 278.4094 -312.557922)
		(end 278.4094 -308.838854)
		(width 0.254)
		(layer "In5.Cu")
		(net "RDPB_FAN_LED3")
	)
	(segment
		(start 278.4094 -308.838854)
		(end 275.4376 -305.867054)
		(width 0.254)
		(layer "In5.Cu")
		(net "RDPB_FAN_LED3")
	)
	(segment
		(start 323.737478 -326.4408)
		(end 313.501278 -316.2046)
		(width 0.254)
		(layer "In5.Cu")
		(net "RDPB_FAN_LED3")
	)
	(segment
		(start 282.056078 -316.2046)
		(end 278.4094 -312.557922)
		(width 0.254)
		(layer "In5.Cu")
		(net "RDPB_FAN_LED3")
	)
	(segment
		(start 275.4376 -305.867054)
		(end 275.4376 -305.8668)
		(width 0.254)
		(layer "In5.Cu")
		(net "RDPB_FAN_LED3")
	)
	(segment
		(start 455.784204 -367.3856)
		(end 455.784204 -350.450404)
		(width 0.254)
		(layer "In5.Cu")
		(net "RDPB_FAN_LED3")
	)
	(segment
		(start 252.138434 -303.0728)
		(end 248.404634 -303.0728)
		(width 0.254)
		(layer "F.Cu")
		(net "RDPB_FAN_LED2")
	)
	(segment
		(start 214.5792 -197.380352)
		(end 209.061558 -202.897994)
		(width 0.254)
		(layer "F.Cu")
		(net "RDPB_FAN_LED2")
	)
	(segment
		(start 319.499996 -367.6396)
		(end 319.144396 -367.284)
		(width 0.254)
		(layer "F.Cu")
		(net "RDPB_FAN_LED2")
	)
	(segment
		(start 272.4404 -307.6956)
		(end 272.237454 -307.492654)
		(width 0.254)
		(layer "F.Cu")
		(net "RDPB_FAN_LED2")
	)
	(segment
		(start 215.96604 -190.51016)
		(end 214.5792 -191.897)
		(width 0.254)
		(layer "F.Cu")
		(net "RDPB_FAN_LED2")
	)
	(segment
		(start 242.562634 -297.2308)
		(end 200.043034 -297.2308)
		(width 0.254)
		(layer "F.Cu")
		(net "RDPB_FAN_LED2")
	)
	(segment
		(start 319.499996 -368.9604)
		(end 319.499996 -368.427)
		(width 0.254)
		(layer "F.Cu")
		(net "RDPB_FAN_LED2")
	)
	(segment
		(start 272.237454 -307.492654)
		(end 256.558288 -307.492654)
		(width 0.254)
		(layer "F.Cu")
		(net "RDPB_FAN_LED2")
	)
	(segment
		(start 214.5792 -191.897)
		(end 214.5792 -197.380352)
		(width 0.254)
		(layer "F.Cu")
		(net "RDPB_FAN_LED2")
	)
	(segment
		(start 319.499996 -368.427)
		(end 319.499996 -367.6396)
		(width 0.254)
		(layer "F.Cu")
		(net "RDPB_FAN_LED2")
	)
	(segment
		(start 217.2716 -190.51016)
		(end 215.96604 -190.51016)
		(width 0.254)
		(layer "F.Cu")
		(net "RDPB_FAN_LED2")
	)
	(segment
		(start 319.941956 -370.2177)
		(end 319.941956 -369.40236)
		(width 0.254)
		(layer "F.Cu")
		(net "RDPB_FAN_LED2")
	)
	(segment
		(start 248.404634 -303.0728)
		(end 242.562634 -297.2308)
		(width 0.254)
		(layer "F.Cu")
		(net "RDPB_FAN_LED2")
	)
	(segment
		(start 199.066912 -296.254678)
		(end 198.303388 -296.254678)
		(width 0.254)
		(layer "F.Cu")
		(net "RDPB_FAN_LED2")
	)
	(segment
		(start 209.061558 -202.897994)
		(end 205.557882 -202.897994)
		(width 0.254)
		(layer "F.Cu")
		(net "RDPB_FAN_LED2")
	)
	(segment
		(start 200.043034 -297.2308)
		(end 199.066912 -296.254678)
		(width 0.254)
		(layer "F.Cu")
		(net "RDPB_FAN_LED2")
	)
	(segment
		(start 205.557882 -202.897994)
		(end 205.326488 -202.6666)
		(width 0.254)
		(layer "F.Cu")
		(net "RDPB_FAN_LED2")
	)
	(segment
		(start 256.558288 -307.492654)
		(end 252.138434 -303.0728)
		(width 0.254)
		(layer "F.Cu")
		(net "RDPB_FAN_LED2")
	)
	(segment
		(start 319.941956 -369.40236)
		(end 319.499996 -368.9604)
		(width 0.254)
		(layer "F.Cu")
		(net "RDPB_FAN_LED2")
	)
	(via
		(at 198.303388 -296.254678)
		(size 0.5588)
		(drill 0.3048)
		(layers "F.Cu" "B.Cu")
		(net "RDPB_FAN_LED2")
	)
	(via
		(at 272.4404 -307.6956)
		(size 0.5588)
		(drill 0.3048)
		(layers "F.Cu" "B.Cu")
		(net "RDPB_FAN_LED2")
	)
	(via
		(at 319.144396 -367.284)
		(size 0.5588)
		(drill 0.3048)
		(layers "F.Cu" "B.Cu")
		(net "RDPB_FAN_LED2")
	)
	(via
		(at 319.499996 -368.427)
		(size 0.6604)
		(drill 0.3302)
		(layers "F.Cu" "B.Cu")
		(net "RDPB_FAN_LED2")
	)
	(via
		(at 205.326488 -202.6666)
		(size 0.5588)
		(drill 0.3048)
		(layers "F.Cu" "B.Cu")
		(net "RDPB_FAN_LED2")
	)
	(segment
		(start 198.9836 -293.115746)
		(end 198.9836 -295.574466)
		(width 0.254)
		(layer "In2.Cu")
		(net "RDPB_FAN_LED2")
	)
	(segment
		(start 204.317346 -220.842332)
		(end 201.238104 -223.921574)
		(width 0.254)
		(layer "In2.Cu")
		(net "RDPB_FAN_LED2")
	)
	(segment
		(start 204.317346 -215.542114)
		(end 204.317092 -215.542368)
		(width 0.254)
		(layer "In2.Cu")
		(net "RDPB_FAN_LED2")
	)
	(segment
		(start 204.317092 -217.844116)
		(end 204.317346 -217.84437)
		(width 0.254)
		(layer "In2.Cu")
		(net "RDPB_FAN_LED2")
	)
	(segment
		(start 204.317346 -217.84437)
		(end 204.317346 -220.842332)
		(width 0.254)
		(layer "In2.Cu")
		(net "RDPB_FAN_LED2")
	)
	(segment
		(start 201.238104 -251.314204)
		(end 201.238104 -290.861242)
		(width 0.254)
		(layer "In2.Cu")
		(net "RDPB_FAN_LED2")
	)
	(segment
		(start 201.238358 -251.31395)
		(end 201.238104 -251.314204)
		(width 0.254)
		(layer "In2.Cu")
		(net "RDPB_FAN_LED2")
	)
	(segment
		(start 198.9836 -295.574466)
		(end 198.303388 -296.254678)
		(width 0.254)
		(layer "In2.Cu")
		(net "RDPB_FAN_LED2")
	)
	(segment
		(start 204.317346 -205.68793)
		(end 204.317346 -215.542114)
		(width 0.254)
		(layer "In2.Cu")
		(net "RDPB_FAN_LED2")
	)
	(segment
		(start 201.238104 -247.570244)
		(end 201.238358 -247.570498)
		(width 0.254)
		(layer "In2.Cu")
		(net "RDPB_FAN_LED2")
	)
	(segment
		(start 205.326488 -202.6666)
		(end 205.326488 -204.678788)
		(width 0.254)
		(layer "In2.Cu")
		(net "RDPB_FAN_LED2")
	)
	(segment
		(start 205.326488 -204.678788)
		(end 204.317346 -205.68793)
		(width 0.254)
		(layer "In2.Cu")
		(net "RDPB_FAN_LED2")
	)
	(segment
		(start 204.317092 -215.542368)
		(end 204.317092 -217.844116)
		(width 0.254)
		(layer "In2.Cu")
		(net "RDPB_FAN_LED2")
	)
	(segment
		(start 201.238358 -247.570498)
		(end 201.238358 -251.31395)
		(width 0.254)
		(layer "In2.Cu")
		(net "RDPB_FAN_LED2")
	)
	(segment
		(start 201.238104 -290.861242)
		(end 198.9836 -293.115746)
		(width 0.254)
		(layer "In2.Cu")
		(net "RDPB_FAN_LED2")
	)
	(segment
		(start 201.238104 -223.921574)
		(end 201.238104 -247.570244)
		(width 0.254)
		(layer "In2.Cu")
		(net "RDPB_FAN_LED2")
	)
	(segment
		(start 326.865996 -333.916274)
		(end 326.865996 -359.424478)
		(width 0.254)
		(layer "In5.Cu")
		(net "RDPB_FAN_LED2")
	)
	(segment
		(start 326.865996 -359.424478)
		(end 319.144396 -367.146078)
		(width 0.254)
		(layer "In5.Cu")
		(net "RDPB_FAN_LED2")
	)
	(segment
		(start 311.770776 -318.821054)
		(end 326.865996 -333.916274)
		(width 0.254)
		(layer "In5.Cu")
		(net "RDPB_FAN_LED2")
	)
	(segment
		(start 275.792692 -310.220868)
		(end 275.792692 -313.641994)
		(width 0.254)
		(layer "In5.Cu")
		(net "RDPB_FAN_LED2")
	)
	(segment
		(start 273.267424 -307.6956)
		(end 275.792692 -310.220868)
		(width 0.254)
		(layer "In5.Cu")
		(net "RDPB_FAN_LED2")
	)
	(segment
		(start 280.971752 -318.821054)
		(end 311.770776 -318.821054)
		(width 0.254)
		(layer "In5.Cu")
		(net "RDPB_FAN_LED2")
	)
	(segment
		(start 272.4404 -307.6956)
		(end 273.267424 -307.6956)
		(width 0.254)
		(layer "In5.Cu")
		(net "RDPB_FAN_LED2")
	)
	(segment
		(start 319.144396 -367.146078)
		(end 319.144396 -367.284)
		(width 0.254)
		(layer "In5.Cu")
		(net "RDPB_FAN_LED2")
	)
	(segment
		(start 275.792692 -313.641994)
		(end 280.971752 -318.821054)
		(width 0.254)
		(layer "In5.Cu")
		(net "RDPB_FAN_LED2")
	)
	(segment
		(start 215.44788 -189.85992)
		(end 213.6648 -191.643)
		(width 0.254)
		(layer "F.Cu")
		(net "RDPB_FAN_LED1")
	)
	(segment
		(start 187.841128 -362.187236)
		(end 187.841128 -363.406436)
		(width 0.254)
		(layer "F.Cu")
		(net "RDPB_FAN_LED1")
	)
	(segment
		(start 217.2716 -189.85992)
		(end 215.44788 -189.85992)
		(width 0.254)
		(layer "F.Cu")
		(net "RDPB_FAN_LED1")
	)
	(segment
		(start 209.3976 -201.3204)
		(end 206.926688 -201.3204)
		(width 0.254)
		(layer "F.Cu")
		(net "RDPB_FAN_LED1")
	)
	(segment
		(start 206.926688 -201.3204)
		(end 206.088488 -202.1586)
		(width 0.254)
		(layer "F.Cu")
		(net "RDPB_FAN_LED1")
	)
	(segment
		(start 187.841128 -364.447836)
		(end 187.841128 -363.406436)
		(width 0.254)
		(layer "F.Cu")
		(net "RDPB_FAN_LED1")
	)
	(segment
		(start 188.359288 -365.298736)
		(end 188.359288 -364.965996)
		(width 0.254)
		(layer "F.Cu")
		(net "RDPB_FAN_LED1")
	)
	(segment
		(start 188.359288 -364.965996)
		(end 187.841128 -364.447836)
		(width 0.254)
		(layer "F.Cu")
		(net "RDPB_FAN_LED1")
	)
	(segment
		(start 213.6648 -191.643)
		(end 213.6648 -197.0532)
		(width 0.254)
		(layer "F.Cu")
		(net "RDPB_FAN_LED1")
	)
	(segment
		(start 213.6648 -197.0532)
		(end 209.3976 -201.3204)
		(width 0.254)
		(layer "F.Cu")
		(net "RDPB_FAN_LED1")
	)
	(via
		(at 187.841128 -363.406436)
		(size 0.6604)
		(drill 0.3302)
		(layers "F.Cu" "B.Cu")
		(net "RDPB_FAN_LED1")
	)
	(via
		(at 187.841128 -362.187236)
		(size 0.5588)
		(drill 0.3048)
		(layers "F.Cu" "B.Cu")
		(net "RDPB_FAN_LED1")
	)
	(via
		(at 206.088488 -202.1586)
		(size 0.5588)
		(drill 0.3048)
		(layers "F.Cu" "B.Cu")
		(net "RDPB_FAN_LED1")
	)
	(segment
		(start 199.8472 -295.844722)
		(end 199.8472 -293.329868)
		(width 0.254)
		(layer "In2.Cu")
		(net "RDPB_FAN_LED1")
	)
	(segment
		(start 205.079346 -215.857836)
		(end 205.079346 -206.003652)
		(width 0.254)
		(layer "In2.Cu")
		(net "RDPB_FAN_LED1")
	)
	(segment
		(start 205.079346 -206.003652)
		(end 206.088488 -204.99451)
		(width 0.254)
		(layer "In2.Cu")
		(net "RDPB_FAN_LED1")
	)
	(segment
		(start 202.000104 -247.254522)
		(end 202.000104 -244.838728)
		(width 0.254)
		(layer "In2.Cu")
		(net "RDPB_FAN_LED1")
	)
	(segment
		(start 206.219044 -324.851522)
		(end 193.954654 -312.587132)
		(width 0.254)
		(layer "In2.Cu")
		(net "RDPB_FAN_LED1")
	)
	(segment
		(start 202.000358 -251.629672)
		(end 202.000358 -247.254776)
		(width 0.254)
		(layer "In2.Cu")
		(net "RDPB_FAN_LED1")
	)
	(segment
		(start 205.079092 -215.85809)
		(end 205.079346 -215.857836)
		(width 0.254)
		(layer "In2.Cu")
		(net "RDPB_FAN_LED1")
	)
	(segment
		(start 202.878182 -362.187236)
		(end 206.219044 -358.846374)
		(width 0.254)
		(layer "In2.Cu")
		(net "RDPB_FAN_LED1")
	)
	(segment
		(start 193.954654 -301.737268)
		(end 199.8472 -295.844722)
		(width 0.254)
		(layer "In2.Cu")
		(net "RDPB_FAN_LED1")
	)
	(segment
		(start 205.079092 -217.528394)
		(end 205.079092 -215.85809)
		(width 0.254)
		(layer "In2.Cu")
		(net "RDPB_FAN_LED1")
	)
	(segment
		(start 202.819254 -244.019578)
		(end 202.819254 -236.335062)
		(width 0.254)
		(layer "In2.Cu")
		(net "RDPB_FAN_LED1")
	)
	(segment
		(start 202.000104 -244.838728)
		(end 202.819254 -244.019578)
		(width 0.254)
		(layer "In2.Cu")
		(net "RDPB_FAN_LED1")
	)
	(segment
		(start 193.954654 -312.587132)
		(end 193.954654 -301.737268)
		(width 0.254)
		(layer "In2.Cu")
		(net "RDPB_FAN_LED1")
	)
	(segment
		(start 202.000104 -291.176964)
		(end 202.000104 -251.629926)
		(width 0.254)
		(layer "In2.Cu")
		(net "RDPB_FAN_LED1")
	)
	(segment
		(start 202.000104 -224.237296)
		(end 205.079346 -221.158054)
		(width 0.254)
		(layer "In2.Cu")
		(net "RDPB_FAN_LED1")
	)
	(segment
		(start 206.219044 -358.846374)
		(end 206.219044 -324.851522)
		(width 0.254)
		(layer "In2.Cu")
		(net "RDPB_FAN_LED1")
	)
	(segment
		(start 202.000104 -235.515912)
		(end 202.000104 -224.237296)
		(width 0.254)
		(layer "In2.Cu")
		(net "RDPB_FAN_LED1")
	)
	(segment
		(start 202.000358 -247.254776)
		(end 202.000104 -247.254522)
		(width 0.254)
		(layer "In2.Cu")
		(net "RDPB_FAN_LED1")
	)
	(segment
		(start 202.000104 -251.629926)
		(end 202.000358 -251.629672)
		(width 0.254)
		(layer "In2.Cu")
		(net "RDPB_FAN_LED1")
	)
	(segment
		(start 206.088488 -204.99451)
		(end 206.088488 -202.1586)
		(width 0.254)
		(layer "In2.Cu")
		(net "RDPB_FAN_LED1")
	)
	(segment
		(start 187.841128 -362.187236)
		(end 202.878182 -362.187236)
		(width 0.254)
		(layer "In2.Cu")
		(net "RDPB_FAN_LED1")
	)
	(segment
		(start 199.8472 -293.329868)
		(end 202.000104 -291.176964)
		(width 0.254)
		(layer "In2.Cu")
		(net "RDPB_FAN_LED1")
	)
	(segment
		(start 202.819254 -236.335062)
		(end 202.000104 -235.515912)
		(width 0.254)
		(layer "In2.Cu")
		(net "RDPB_FAN_LED1")
	)
	(segment
		(start 205.079346 -221.158054)
		(end 205.079346 -217.528648)
		(width 0.254)
		(layer "In2.Cu")
		(net "RDPB_FAN_LED1")
	)
	(segment
		(start 205.079346 -217.528648)
		(end 205.079092 -217.528394)
		(width 0.254)
		(layer "In2.Cu")
		(net "RDPB_FAN_LED1")
	)
	(segment
		(start 209.0166 -200.4822)
		(end 205.221586 -200.4822)
		(width 0.254)
		(layer "F.Cu")
		(net "RDPB_FAN_LED0")
	)
	(segment
		(start 204.2668 -201.436986)
		(end 204.2668 -202.7428)
		(width 0.254)
		(layer "F.Cu")
		(net "RDPB_FAN_LED0")
	)
	(segment
		(start 205.221586 -200.4822)
		(end 204.2668 -201.436986)
		(width 0.254)
		(layer "F.Cu")
		(net "RDPB_FAN_LED0")
	)
	(segment
		(start 212.8266 -191.008)
		(end 212.8266 -196.6722)
		(width 0.254)
		(layer "F.Cu")
		(net "RDPB_FAN_LED0")
	)
	(segment
		(start 212.8266 -196.6722)
		(end 209.0166 -200.4822)
		(width 0.254)
		(layer "F.Cu")
		(net "RDPB_FAN_LED0")
	)
	(segment
		(start 28.781756 -367.24336)
		(end 28.781756 -366.1918)
		(width 0.254)
		(layer "F.Cu")
		(net "RDPB_FAN_LED0")
	)
	(segment
		(start 217.2716 -189.20968)
		(end 216.26068 -189.20968)
		(width 0.254)
		(layer "F.Cu")
		(net "RDPB_FAN_LED0")
	)
	(segment
		(start 216.26068 -189.20968)
		(end 216.1286 -189.0776)
		(width 0.254)
		(layer "F.Cu")
		(net "RDPB_FAN_LED0")
	)
	(segment
		(start 216.1286 -189.0776)
		(end 214.757 -189.0776)
		(width 0.254)
		(layer "F.Cu")
		(net "RDPB_FAN_LED0")
	)
	(segment
		(start 214.757 -189.0776)
		(end 212.8266 -191.008)
		(width 0.254)
		(layer "F.Cu")
		(net "RDPB_FAN_LED0")
	)
	(segment
		(start 28.781756 -368.9223)
		(end 28.781756 -367.24336)
		(width 0.254)
		(layer "F.Cu")
		(net "RDPB_FAN_LED0")
	)
	(via
		(at 28.781756 -367.24336)
		(size 0.6604)
		(drill 0.3302)
		(layers "F.Cu" "B.Cu")
		(net "RDPB_FAN_LED0")
	)
	(via
		(at 204.2668 -202.7428)
		(size 0.5588)
		(drill 0.3048)
		(layers "F.Cu" "B.Cu")
		(net "RDPB_FAN_LED0")
	)
	(via
		(at 197.3072 -297.1038)
		(size 0.5588)
		(drill 0.3048)
		(layers "F.Cu" "B.Cu")
		(net "RDPB_FAN_LED0")
	)
	(via
		(at 28.781756 -366.1918)
		(size 0.5588)
		(drill 0.3048)
		(layers "F.Cu" "B.Cu")
		(net "RDPB_FAN_LED0")
	)
	(segment
		(start 199.714358 -248.201942)
		(end 199.714358 -250.682506)
		(width 0.254)
		(layer "In2.Cu")
		(net "RDPB_FAN_LED0")
	)
	(segment
		(start 202.793092 -218.47556)
		(end 202.793346 -218.475814)
		(width 0.254)
		(layer "In2.Cu")
		(net "RDPB_FAN_LED0")
	)
	(segment
		(start 202.793092 -214.910924)
		(end 202.793092 -218.47556)
		(width 0.254)
		(layer "In2.Cu")
		(net "RDPB_FAN_LED0")
	)
	(segment
		(start 202.793346 -204.216254)
		(end 202.793346 -214.91067)
		(width 0.254)
		(layer "In2.Cu")
		(net "RDPB_FAN_LED0")
	)
	(segment
		(start 199.714358 -250.682506)
		(end 199.714104 -250.68276)
		(width 0.254)
		(layer "In2.Cu")
		(net "RDPB_FAN_LED0")
	)
	(segment
		(start 204.2668 -202.7428)
		(end 202.793346 -204.216254)
		(width 0.254)
		(layer "In2.Cu")
		(net "RDPB_FAN_LED0")
	)
	(segment
		(start 199.714104 -250.68276)
		(end 199.714104 -290.229798)
		(width 0.254)
		(layer "In2.Cu")
		(net "RDPB_FAN_LED0")
	)
	(segment
		(start 202.793346 -218.475814)
		(end 202.793346 -220.210888)
		(width 0.254)
		(layer "In2.Cu")
		(net "RDPB_FAN_LED0")
	)
	(segment
		(start 202.793346 -220.210888)
		(end 199.714104 -223.29013)
		(width 0.254)
		(layer "In2.Cu")
		(net "RDPB_FAN_LED0")
	)
	(segment
		(start 197.3072 -292.636702)
		(end 197.3072 -297.1038)
		(width 0.254)
		(layer "In2.Cu")
		(net "RDPB_FAN_LED0")
	)
	(segment
		(start 199.714104 -223.29013)
		(end 199.714104 -248.201688)
		(width 0.254)
		(layer "In2.Cu")
		(net "RDPB_FAN_LED0")
	)
	(segment
		(start 199.714104 -290.229798)
		(end 197.3072 -292.636702)
		(width 0.254)
		(layer "In2.Cu")
		(net "RDPB_FAN_LED0")
	)
	(segment
		(start 202.793346 -214.91067)
		(end 202.793092 -214.910924)
		(width 0.254)
		(layer "In2.Cu")
		(net "RDPB_FAN_LED0")
	)
	(segment
		(start 199.714104 -248.201688)
		(end 199.714358 -248.201942)
		(width 0.254)
		(layer "In2.Cu")
		(net "RDPB_FAN_LED0")
	)
	(segment
		(start 28.771596 -366.18164)
		(end 28.771596 -332.474316)
		(width 0.254)
		(layer "In5.Cu")
		(net "RDPB_FAN_LED0")
	)
	(segment
		(start 28.781756 -366.1918)
		(end 28.771596 -366.18164)
		(width 0.254)
		(layer "In5.Cu")
		(net "RDPB_FAN_LED0")
	)
	(segment
		(start 194.0814 -297.1038)
		(end 197.3072 -297.1038)
		(width 0.254)
		(layer "In5.Cu")
		(net "RDPB_FAN_LED0")
	)
	(segment
		(start 177.4952 -313.69)
		(end 194.0814 -297.1038)
		(width 0.254)
		(layer "In5.Cu")
		(net "RDPB_FAN_LED0")
	)
	(segment
		(start 28.771596 -332.474316)
		(end 47.555912 -313.69)
		(width 0.254)
		(layer "In5.Cu")
		(net "RDPB_FAN_LED0")
	)
	(segment
		(start 47.555912 -313.69)
		(end 177.4952 -313.69)
		(width 0.254)
		(layer "In5.Cu")
		(net "RDPB_FAN_LED0")
	)
	(segment
		(start 457.003404 -368.4778)
		(end 457.282804 -368.1984)
		(width 0.254)
		(layer "F.Cu")
		(net "FDPB_FAN_LED3")
	)
	(segment
		(start 257.5052 -305.2064)
		(end 253.0856 -300.7868)
		(width 0.254)
		(layer "F.Cu")
		(net "FDPB_FAN_LED3")
	)
	(segment
		(start 249.3518 -300.7868)
		(end 243.5098 -294.9448)
		(width 0.254)
		(layer "F.Cu")
		(net "FDPB_FAN_LED3")
	)
	(segment
		(start 275.481034 -304.832766)
		(end 272.229834 -304.832766)
		(width 0.254)
		(layer "F.Cu")
		(net "FDPB_FAN_LED3")
	)
	(segment
		(start 253.0856 -300.7868)
		(end 249.3518 -300.7868)
		(width 0.254)
		(layer "F.Cu")
		(net "FDPB_FAN_LED3")
	)
	(segment
		(start 243.5098 -294.9448)
		(end 200.9902 -294.9448)
		(width 0.254)
		(layer "F.Cu")
		(net "FDPB_FAN_LED3")
	)
	(segment
		(start 457.003404 -370.0653)
		(end 457.003404 -368.4778)
		(width 0.254)
		(layer "F.Cu")
		(net "FDPB_FAN_LED3")
	)
	(segment
		(start 200.9902 -294.9448)
		(end 199.7964 -293.751)
		(width 0.254)
		(layer "F.Cu")
		(net "FDPB_FAN_LED3")
	)
	(segment
		(start 271.8562 -305.2064)
		(end 257.5052 -305.2064)
		(width 0.254)
		(layer "F.Cu")
		(net "FDPB_FAN_LED3")
	)
	(segment
		(start 272.229834 -304.832766)
		(end 271.8562 -305.2064)
		(width 0.254)
		(layer "F.Cu")
		(net "FDPB_FAN_LED3")
	)
	(segment
		(start 457.282804 -367.2332)
		(end 457.282804 -368.1984)
		(width 0.254)
		(layer "F.Cu")
		(net "FDPB_FAN_LED3")
	)
	(segment
		(start 199.7964 -293.751)
		(end 195.5292 -293.751)
		(width 0.254)
		(layer "F.Cu")
		(net "FDPB_FAN_LED3")
	)
	(via
		(at 275.481034 -304.832766)
		(size 0.5588)
		(drill 0.3048)
		(layers "F.Cu" "B.Cu")
		(net "FDPB_FAN_LED3")
	)
	(via
		(at 203.9366 -161.036)
		(size 0.5588)
		(drill 0.3048)
		(layers "F.Cu" "B.Cu")
		(net "FDPB_FAN_LED3")
	)
	(via
		(at 195.5292 -293.751)
		(size 0.5588)
		(drill 0.3048)
		(layers "F.Cu" "B.Cu")
		(net "FDPB_FAN_LED3")
	)
	(via
		(at 457.282804 -368.1984)
		(size 0.6604)
		(drill 0.3302)
		(layers "F.Cu" "B.Cu")
		(net "FDPB_FAN_LED3")
	)
	(via
		(at 457.282804 -367.2332)
		(size 0.5588)
		(drill 0.3048)
		(layers "F.Cu" "B.Cu")
		(net "FDPB_FAN_LED3")
	)
	(via
		(at 223.1136 -159.0548)
		(size 0.5588)
		(drill 0.3048)
		(layers "F.Cu" "B.Cu")
		(net "FDPB_FAN_LED3")
	)
	(segment
		(start 221.615 -157.5562)
		(end 221.615 -155.6258)
		(width 0.254)
		(layer "In2.Cu")
		(net "FDPB_FAN_LED3")
	)
	(segment
		(start 231.802178 -75.300078)
		(end 231.599994 -75.300078)
		(width 0.254)
		(layer "In2.Cu")
		(net "FDPB_FAN_LED3")
	)
	(segment
		(start 221.970854 -155.269946)
		(end 221.970854 -152.539954)
		(width 0.254)
		(layer "In2.Cu")
		(net "FDPB_FAN_LED3")
	)
	(segment
		(start 221.996254 -122.730006)
		(end 221.996254 -113.693448)
		(width 0.254)
		(layer "In2.Cu")
		(net "FDPB_FAN_LED3")
	)
	(segment
		(start 233.7562 -77.2541)
		(end 231.802178 -75.300078)
		(width 0.254)
		(layer "In2.Cu")
		(net "FDPB_FAN_LED3")
	)
	(segment
		(start 223.1136 -159.0548)
		(end 221.615 -157.5562)
		(width 0.254)
		(layer "In2.Cu")
		(net "FDPB_FAN_LED3")
	)
	(segment
		(start 198.190104 -222.658686)
		(end 198.190104 -289.464496)
		(width 0.254)
		(layer "In2.Cu")
		(net "FDPB_FAN_LED3")
	)
	(segment
		(start 221.615 -155.6258)
		(end 221.970854 -155.269946)
		(width 0.254)
		(layer "In2.Cu")
		(net "FDPB_FAN_LED3")
	)
	(segment
		(start 201.187558 -219.661232)
		(end 198.190104 -222.658686)
		(width 0.254)
		(layer "In2.Cu")
		(net "FDPB_FAN_LED3")
	)
	(segment
		(start 198.190104 -289.464496)
		(end 195.5292 -292.1254)
		(width 0.254)
		(layer "In2.Cu")
		(net "FDPB_FAN_LED3")
	)
	(segment
		(start 204.327506 -161.426906)
		(end 204.327506 -169.385488)
		(width 0.254)
		(layer "In2.Cu")
		(net "FDPB_FAN_LED3")
	)
	(segment
		(start 204.8256 -169.883582)
		(end 204.8256 -193.568828)
		(width 0.254)
		(layer "In2.Cu")
		(net "FDPB_FAN_LED3")
	)
	(segment
		(start 204.327506 -169.385488)
		(end 204.8256 -169.883582)
		(width 0.254)
		(layer "In2.Cu")
		(net "FDPB_FAN_LED3")
	)
	(segment
		(start 204.347826 -197.171818)
		(end 201.187558 -200.332086)
		(width 0.254)
		(layer "In2.Cu")
		(net "FDPB_FAN_LED3")
	)
	(segment
		(start 233.7562 -86.476078)
		(end 233.7562 -77.2541)
		(width 0.254)
		(layer "In2.Cu")
		(net "FDPB_FAN_LED3")
	)
	(segment
		(start 195.5292 -292.1254)
		(end 195.5292 -293.751)
		(width 0.254)
		(layer "In2.Cu")
		(net "FDPB_FAN_LED3")
	)
	(segment
		(start 221.996254 -113.693448)
		(end 232.947972 -102.74173)
		(width 0.254)
		(layer "In2.Cu")
		(net "FDPB_FAN_LED3")
	)
	(segment
		(start 203.9366 -161.036)
		(end 204.327506 -161.426906)
		(width 0.254)
		(layer "In2.Cu")
		(net "FDPB_FAN_LED3")
	)
	(segment
		(start 232.947972 -87.284306)
		(end 233.7562 -86.476078)
		(width 0.254)
		(layer "In2.Cu")
		(net "FDPB_FAN_LED3")
	)
	(segment
		(start 221.05366 -123.6726)
		(end 221.996254 -122.730006)
		(width 0.254)
		(layer "In2.Cu")
		(net "FDPB_FAN_LED3")
	)
	(segment
		(start 201.187558 -200.332086)
		(end 201.187558 -219.661232)
		(width 0.254)
		(layer "In2.Cu")
		(net "FDPB_FAN_LED3")
	)
	(segment
		(start 232.947972 -102.74173)
		(end 232.947972 -87.284306)
		(width 0.254)
		(layer "In2.Cu")
		(net "FDPB_FAN_LED3")
	)
	(segment
		(start 204.347826 -194.046602)
		(end 204.347826 -197.171818)
		(width 0.254)
		(layer "In2.Cu")
		(net "FDPB_FAN_LED3")
	)
	(segment
		(start 221.970854 -152.539954)
		(end 221.05366 -151.62276)
		(width 0.254)
		(layer "In2.Cu")
		(net "FDPB_FAN_LED3")
	)
	(segment
		(start 204.8256 -193.568828)
		(end 204.347826 -194.046602)
		(width 0.254)
		(layer "In2.Cu")
		(net "FDPB_FAN_LED3")
	)
	(segment
		(start 221.05366 -151.62276)
		(end 221.05366 -123.6726)
		(width 0.254)
		(layer "In2.Cu")
		(net "FDPB_FAN_LED3")
	)
	(segment
		(start 220.84284 -159.159448)
		(end 220.947488 -159.0548)
		(width 0.254)
		(layer "In5.Cu")
		(net "FDPB_FAN_LED3")
	)
	(segment
		(start 457.282804 -367.2332)
		(end 457.282804 -350.806004)
		(width 0.254)
		(layer "In5.Cu")
		(net "FDPB_FAN_LED3")
	)
	(segment
		(start 279.1714 -312.2422)
		(end 279.1714 -308.523132)
		(width 0.254)
		(layer "In5.Cu")
		(net "FDPB_FAN_LED3")
	)
	(segment
		(start 279.1714 -308.523132)
		(end 275.481034 -304.832766)
		(width 0.254)
		(layer "In5.Cu")
		(net "FDPB_FAN_LED3")
	)
	(segment
		(start 313.817 -315.4426)
		(end 282.3718 -315.4426)
		(width 0.254)
		(layer "In5.Cu")
		(net "FDPB_FAN_LED3")
	)
	(segment
		(start 203.9366 -161.036)
		(end 204.160374 -160.812226)
		(width 0.254)
		(layer "In5.Cu")
		(net "FDPB_FAN_LED3")
	)
	(segment
		(start 457.282804 -350.806004)
		(end 432.1556 -325.6788)
		(width 0.254)
		(layer "In5.Cu")
		(net "FDPB_FAN_LED3")
	)
	(segment
		(start 206.176372 -160.812226)
		(end 207.82915 -159.159448)
		(width 0.254)
		(layer "In5.Cu")
		(net "FDPB_FAN_LED3")
	)
	(segment
		(start 282.3718 -315.4426)
		(end 279.1714 -312.2422)
		(width 0.254)
		(layer "In5.Cu")
		(net "FDPB_FAN_LED3")
	)
	(segment
		(start 204.160374 -160.812226)
		(end 206.176372 -160.812226)
		(width 0.254)
		(layer "In5.Cu")
		(net "FDPB_FAN_LED3")
	)
	(segment
		(start 220.947488 -159.0548)
		(end 223.1136 -159.0548)
		(width 0.254)
		(layer "In5.Cu")
		(net "FDPB_FAN_LED3")
	)
	(segment
		(start 207.82915 -159.159448)
		(end 220.84284 -159.159448)
		(width 0.254)
		(layer "In5.Cu")
		(net "FDPB_FAN_LED3")
	)
	(segment
		(start 324.0532 -325.6788)
		(end 313.817 -315.4426)
		(width 0.254)
		(layer "In5.Cu")
		(net "FDPB_FAN_LED3")
	)
	(segment
		(start 432.1556 -325.6788)
		(end 324.0532 -325.6788)
		(width 0.254)
		(layer "In5.Cu")
		(net "FDPB_FAN_LED3")
	)
	(segment
		(start 320.744596 -369.2144)
		(end 320.744596 -368.1222)
		(width 0.254)
		(layer "F.Cu")
		(net "FDPB_FAN_LED2")
	)
	(segment
		(start 320.592196 -370.2177)
		(end 320.592196 -369.3668)
		(width 0.254)
		(layer "F.Cu")
		(net "FDPB_FAN_LED2")
	)
	(segment
		(start 243.194078 -295.7068)
		(end 200.674478 -295.7068)
		(width 0.254)
		(layer "F.Cu")
		(net "FDPB_FAN_LED2")
	)
	(segment
		(start 272.197322 -305.943)
		(end 272.171668 -305.968654)
		(width 0.254)
		(layer "F.Cu")
		(net "FDPB_FAN_LED2")
	)
	(segment
		(start 249.036078 -301.5488)
		(end 243.194078 -295.7068)
		(width 0.254)
		(layer "F.Cu")
		(net "FDPB_FAN_LED2")
	)
	(segment
		(start 200.674478 -295.7068)
		(end 199.506078 -294.5384)
		(width 0.254)
		(layer "F.Cu")
		(net "FDPB_FAN_LED2")
	)
	(segment
		(start 199.506078 -294.5384)
		(end 196.4436 -294.5384)
		(width 0.254)
		(layer "F.Cu")
		(net "FDPB_FAN_LED2")
	)
	(segment
		(start 320.592196 -369.3668)
		(end 320.744596 -369.2144)
		(width 0.254)
		(layer "F.Cu")
		(net "FDPB_FAN_LED2")
	)
	(segment
		(start 196.4436 -294.5384)
		(end 196.4182 -294.5638)
		(width 0.254)
		(layer "F.Cu")
		(net "FDPB_FAN_LED2")
	)
	(segment
		(start 272.5166 -305.943)
		(end 272.197322 -305.943)
		(width 0.254)
		(layer "F.Cu")
		(net "FDPB_FAN_LED2")
	)
	(segment
		(start 272.171668 -305.968654)
		(end 257.189732 -305.968654)
		(width 0.254)
		(layer "F.Cu")
		(net "FDPB_FAN_LED2")
	)
	(segment
		(start 252.769878 -301.5488)
		(end 249.036078 -301.5488)
		(width 0.254)
		(layer "F.Cu")
		(net "FDPB_FAN_LED2")
	)
	(segment
		(start 257.189732 -305.968654)
		(end 252.769878 -301.5488)
		(width 0.254)
		(layer "F.Cu")
		(net "FDPB_FAN_LED2")
	)
	(segment
		(start 320.744596 -367.7412)
		(end 320.185796 -367.1824)
		(width 0.254)
		(layer "F.Cu")
		(net "FDPB_FAN_LED2")
	)
	(segment
		(start 320.744596 -368.1222)
		(end 320.744596 -367.7412)
		(width 0.254)
		(layer "F.Cu")
		(net "FDPB_FAN_LED2")
	)
	(via
		(at 205.08976 -159.99714)
		(size 0.5588)
		(drill 0.3048)
		(layers "F.Cu" "B.Cu")
		(net "FDPB_FAN_LED2")
	)
	(via
		(at 272.5166 -305.943)
		(size 0.5588)
		(drill 0.3048)
		(layers "F.Cu" "B.Cu")
		(net "FDPB_FAN_LED2")
	)
	(via
		(at 320.185796 -367.1824)
		(size 0.5588)
		(drill 0.3048)
		(layers "F.Cu" "B.Cu")
		(net "FDPB_FAN_LED2")
	)
	(via
		(at 223.4184 -157.8864)
		(size 0.5588)
		(drill 0.3048)
		(layers "F.Cu" "B.Cu")
		(net "FDPB_FAN_LED2")
	)
	(via
		(at 320.744596 -368.1222)
		(size 0.6604)
		(drill 0.3302)
		(layers "F.Cu" "B.Cu")
		(net "FDPB_FAN_LED2")
	)
	(via
		(at 196.4182 -294.5638)
		(size 0.5588)
		(drill 0.3048)
		(layers "F.Cu" "B.Cu")
		(net "FDPB_FAN_LED2")
	)
	(segment
		(start 205.089506 -169.069766)
		(end 205.5876 -169.56786)
		(width 0.254)
		(layer "In2.Cu")
		(net "FDPB_FAN_LED2")
	)
	(segment
		(start 222.402146 -156.046932)
		(end 222.758254 -155.690824)
		(width 0.254)
		(layer "In2.Cu")
		(net "FDPB_FAN_LED2")
	)
	(segment
		(start 196.4182 -292.3794)
		(end 196.4182 -294.5638)
		(width 0.254)
		(layer "In2.Cu")
		(net "FDPB_FAN_LED2")
	)
	(segment
		(start 222.758254 -155.690824)
		(end 222.758254 -114.00917)
		(width 0.254)
		(layer "In2.Cu")
		(net "FDPB_FAN_LED2")
	)
	(segment
		(start 231.779826 -74.200004)
		(end 231.599994 -74.200004)
		(width 0.254)
		(layer "In2.Cu")
		(net "FDPB_FAN_LED2")
	)
	(segment
		(start 205.109826 -197.48754)
		(end 201.949558 -200.647808)
		(width 0.254)
		(layer "In2.Cu")
		(net "FDPB_FAN_LED2")
	)
	(segment
		(start 198.952104 -222.974408)
		(end 198.952104 -289.845496)
		(width 0.254)
		(layer "In2.Cu")
		(net "FDPB_FAN_LED2")
	)
	(segment
		(start 233.709972 -87.600028)
		(end 234.537504 -86.772496)
		(width 0.254)
		(layer "In2.Cu")
		(net "FDPB_FAN_LED2")
	)
	(segment
		(start 205.08976 -164.409882)
		(end 205.089506 -164.410136)
		(width 0.254)
		(layer "In2.Cu")
		(net "FDPB_FAN_LED2")
	)
	(segment
		(start 223.4184 -157.8864)
		(end 222.402146 -156.870146)
		(width 0.254)
		(layer "In2.Cu")
		(net "FDPB_FAN_LED2")
	)
	(segment
		(start 234.537504 -76.957682)
		(end 231.779826 -74.200004)
		(width 0.254)
		(layer "In2.Cu")
		(net "FDPB_FAN_LED2")
	)
	(segment
		(start 234.537504 -86.772496)
		(end 234.537504 -76.957682)
		(width 0.254)
		(layer "In2.Cu")
		(net "FDPB_FAN_LED2")
	)
	(segment
		(start 205.109826 -194.362324)
		(end 205.109826 -197.48754)
		(width 0.254)
		(layer "In2.Cu")
		(net "FDPB_FAN_LED2")
	)
	(segment
		(start 222.758254 -114.00917)
		(end 233.709972 -103.057452)
		(width 0.254)
		(layer "In2.Cu")
		(net "FDPB_FAN_LED2")
	)
	(segment
		(start 201.949558 -219.976954)
		(end 198.952104 -222.974408)
		(width 0.254)
		(layer "In2.Cu")
		(net "FDPB_FAN_LED2")
	)
	(segment
		(start 222.402146 -156.870146)
		(end 222.402146 -156.046932)
		(width 0.254)
		(layer "In2.Cu")
		(net "FDPB_FAN_LED2")
	)
	(segment
		(start 233.709972 -103.057452)
		(end 233.709972 -87.600028)
		(width 0.254)
		(layer "In2.Cu")
		(net "FDPB_FAN_LED2")
	)
	(segment
		(start 198.952104 -289.845496)
		(end 196.4182 -292.3794)
		(width 0.254)
		(layer "In2.Cu")
		(net "FDPB_FAN_LED2")
	)
	(segment
		(start 205.089506 -164.410136)
		(end 205.089506 -169.069766)
		(width 0.254)
		(layer "In2.Cu")
		(net "FDPB_FAN_LED2")
	)
	(segment
		(start 205.5876 -169.56786)
		(end 205.5876 -193.88455)
		(width 0.254)
		(layer "In2.Cu")
		(net "FDPB_FAN_LED2")
	)
	(segment
		(start 205.08976 -159.99714)
		(end 205.08976 -164.409882)
		(width 0.254)
		(layer "In2.Cu")
		(net "FDPB_FAN_LED2")
	)
	(segment
		(start 205.5876 -193.88455)
		(end 205.109826 -194.362324)
		(width 0.254)
		(layer "In2.Cu")
		(net "FDPB_FAN_LED2")
	)
	(segment
		(start 201.949558 -200.647808)
		(end 201.949558 -219.976954)
		(width 0.254)
		(layer "In2.Cu")
		(net "FDPB_FAN_LED2")
	)
	(segment
		(start 219.80398 -157.84068)
		(end 219.355162 -158.289498)
		(width 0.254)
		(layer "In5.Cu")
		(net "FDPB_FAN_LED2")
	)
	(segment
		(start 320.185796 -367.1824)
		(end 327.62825 -359.739946)
		(width 0.254)
		(layer "In5.Cu")
		(net "FDPB_FAN_LED2")
	)
	(segment
		(start 276.554692 -309.803292)
		(end 272.6944 -305.943)
		(width 0.254)
		(layer "In5.Cu")
		(net "FDPB_FAN_LED2")
	)
	(segment
		(start 219.355162 -158.289498)
		(end 206.797402 -158.289498)
		(width 0.254)
		(layer "In5.Cu")
		(net "FDPB_FAN_LED2")
	)
	(segment
		(start 223.37268 -157.84068)
		(end 219.80398 -157.84068)
		(width 0.254)
		(layer "In5.Cu")
		(net "FDPB_FAN_LED2")
	)
	(segment
		(start 327.62825 -359.739946)
		(end 327.62825 -333.408528)
		(width 0.254)
		(layer "In5.Cu")
		(net "FDPB_FAN_LED2")
	)
	(segment
		(start 327.62825 -333.408528)
		(end 312.278776 -318.059054)
		(width 0.254)
		(layer "In5.Cu")
		(net "FDPB_FAN_LED2")
	)
	(segment
		(start 272.6944 -305.943)
		(end 272.5166 -305.943)
		(width 0.254)
		(layer "In5.Cu")
		(net "FDPB_FAN_LED2")
	)
	(segment
		(start 312.278776 -318.059054)
		(end 281.287474 -318.059054)
		(width 0.254)
		(layer "In5.Cu")
		(net "FDPB_FAN_LED2")
	)
	(segment
		(start 281.287474 -318.059054)
		(end 276.554692 -313.326272)
		(width 0.254)
		(layer "In5.Cu")
		(net "FDPB_FAN_LED2")
	)
	(segment
		(start 276.554692 -313.326272)
		(end 276.554692 -309.803292)
		(width 0.254)
		(layer "In5.Cu")
		(net "FDPB_FAN_LED2")
	)
	(segment
		(start 223.4184 -157.8864)
		(end 223.37268 -157.84068)
		(width 0.254)
		(layer "In5.Cu")
		(net "FDPB_FAN_LED2")
	)
	(segment
		(start 206.797402 -158.289498)
		(end 205.08976 -159.99714)
		(width 0.254)
		(layer "In5.Cu")
		(net "FDPB_FAN_LED2")
	)
	(segment
		(start 189.009528 -365.298736)
		(end 189.009528 -362.415836)
		(width 0.254)
		(layer "F.Cu")
		(net "FDPB_FAN_LED1")
	)
	(segment
		(start 189.009528 -362.415836)
		(end 189.009528 -361.666536)
		(width 0.254)
		(layer "F.Cu")
		(net "FDPB_FAN_LED1")
	)
	(segment
		(start 189.009528 -361.666536)
		(end 188.69152 -361.348528)
		(width 0.254)
		(layer "F.Cu")
		(net "FDPB_FAN_LED1")
	)
	(via
		(at 189.009528 -362.415836)
		(size 0.6604)
		(drill 0.3302)
		(layers "F.Cu" "B.Cu")
		(net "FDPB_FAN_LED1")
	)
	(via
		(at 188.69152 -361.348528)
		(size 0.5588)
		(drill 0.3048)
		(layers "F.Cu" "B.Cu")
		(net "FDPB_FAN_LED1")
	)
	(via
		(at 203.1746 -161.6202)
		(size 0.5588)
		(drill 0.3048)
		(layers "F.Cu" "B.Cu")
		(net "FDPB_FAN_LED1")
	)
	(via
		(at 223.1644 -156.3624)
		(size 0.5588)
		(drill 0.3048)
		(layers "F.Cu" "B.Cu")
		(net "FDPB_FAN_LED1")
	)
	(segment
		(start 200.425558 -200.016364)
		(end 203.565506 -196.876416)
		(width 0.254)
		(layer "In2.Cu")
		(net "FDPB_FAN_LED1")
	)
	(segment
		(start 188.691774 -361.348782)
		(end 202.573636 -361.348782)
		(width 0.254)
		(layer "In2.Cu")
		(net "FDPB_FAN_LED1")
	)
	(segment
		(start 192.6463 -312.3565)
		(end 192.6463 -293.6621)
		(width 0.254)
		(layer "In2.Cu")
		(net "FDPB_FAN_LED1")
	)
	(segment
		(start 203.565506 -169.70121)
		(end 203.565506 -162.011106)
		(width 0.254)
		(layer "In2.Cu")
		(net "FDPB_FAN_LED1")
	)
	(segment
		(start 204.0636 -193.253106)
		(end 204.0636 -170.199304)
		(width 0.254)
		(layer "In2.Cu")
		(net "FDPB_FAN_LED1")
	)
	(segment
		(start 223.520254 -114.375946)
		(end 235.299504 -102.596696)
		(width 0.254)
		(layer "In2.Cu")
		(net "FDPB_FAN_LED1")
	)
	(segment
		(start 192.6463 -293.6621)
		(end 197.428104 -288.880296)
		(width 0.254)
		(layer "In2.Cu")
		(net "FDPB_FAN_LED1")
	)
	(segment
		(start 223.1644 -156.3624)
		(end 223.520254 -156.006546)
		(width 0.254)
		(layer "In2.Cu")
		(net "FDPB_FAN_LED1")
	)
	(segment
		(start 235.299504 -76.499466)
		(end 231.599994 -72.799956)
		(width 0.254)
		(layer "In2.Cu")
		(net "FDPB_FAN_LED1")
	)
	(segment
		(start 200.425558 -219.345002)
		(end 200.425558 -200.016364)
		(width 0.254)
		(layer "In2.Cu")
		(net "FDPB_FAN_LED1")
	)
	(segment
		(start 203.565506 -193.7512)
		(end 204.0636 -193.253106)
		(width 0.254)
		(layer "In2.Cu")
		(net "FDPB_FAN_LED1")
	)
	(segment
		(start 203.565506 -162.011106)
		(end 203.1746 -161.6202)
		(width 0.254)
		(layer "In2.Cu")
		(net "FDPB_FAN_LED1")
	)
	(segment
		(start 205.457044 -325.167244)
		(end 192.6463 -312.3565)
		(width 0.254)
		(layer "In2.Cu")
		(net "FDPB_FAN_LED1")
	)
	(segment
		(start 188.69152 -361.348528)
		(end 188.691774 -361.348782)
		(width 0.254)
		(layer "In2.Cu")
		(net "FDPB_FAN_LED1")
	)
	(segment
		(start 223.520254 -156.006546)
		(end 223.520254 -114.375946)
		(width 0.254)
		(layer "In2.Cu")
		(net "FDPB_FAN_LED1")
	)
	(segment
		(start 202.573636 -361.348782)
		(end 205.457044 -358.465374)
		(width 0.254)
		(layer "In2.Cu")
		(net "FDPB_FAN_LED1")
	)
	(segment
		(start 197.428104 -288.880296)
		(end 197.428104 -222.342456)
		(width 0.254)
		(layer "In2.Cu")
		(net "FDPB_FAN_LED1")
	)
	(segment
		(start 205.457044 -358.465374)
		(end 205.457044 -325.167244)
		(width 0.254)
		(layer "In2.Cu")
		(net "FDPB_FAN_LED1")
	)
	(segment
		(start 204.0636 -170.199304)
		(end 203.565506 -169.70121)
		(width 0.254)
		(layer "In2.Cu")
		(net "FDPB_FAN_LED1")
	)
	(segment
		(start 203.565506 -196.876416)
		(end 203.565506 -193.7512)
		(width 0.254)
		(layer "In2.Cu")
		(net "FDPB_FAN_LED1")
	)
	(segment
		(start 197.428104 -222.342456)
		(end 200.425558 -219.345002)
		(width 0.254)
		(layer "In2.Cu")
		(net "FDPB_FAN_LED1")
	)
	(segment
		(start 235.299504 -102.596696)
		(end 235.299504 -76.499466)
		(width 0.254)
		(layer "In2.Cu")
		(net "FDPB_FAN_LED1")
	)
	(segment
		(start 216.942162 -157.527498)
		(end 218.3765 -156.09316)
		(width 0.254)
		(layer "In5.Cu")
		(net "FDPB_FAN_LED1")
	)
	(segment
		(start 203.1746 -161.6202)
		(end 203.1746 -160.52546)
		(width 0.254)
		(layer "In5.Cu")
		(net "FDPB_FAN_LED1")
	)
	(segment
		(start 203.1746 -160.52546)
		(end 206.172562 -157.527498)
		(width 0.254)
		(layer "In5.Cu")
		(net "FDPB_FAN_LED1")
	)
	(segment
		(start 222.89516 -156.09316)
		(end 223.1644 -156.3624)
		(width 0.254)
		(layer "In5.Cu")
		(net "FDPB_FAN_LED1")
	)
	(segment
		(start 206.172562 -157.527498)
		(end 216.942162 -157.527498)
		(width 0.254)
		(layer "In5.Cu")
		(net "FDPB_FAN_LED1")
	)
	(segment
		(start 218.3765 -156.09316)
		(end 222.89516 -156.09316)
		(width 0.254)
		(layer "In5.Cu")
		(net "FDPB_FAN_LED1")
	)
	(segment
		(start 29.431996 -368.0206)
		(end 29.611828 -367.840768)
		(width 0.254)
		(layer "F.Cu")
		(net "FDPB_FAN_LED0")
	)
	(segment
		(start 29.611828 -366.926368)
		(end 30.244796 -366.2934)
		(width 0.254)
		(layer "F.Cu")
		(net "FDPB_FAN_LED0")
	)
	(segment
		(start 29.431996 -368.9223)
		(end 29.431996 -368.0206)
		(width 0.254)
		(layer "F.Cu")
		(net "FDPB_FAN_LED0")
	)
	(segment
		(start 29.611828 -367.840768)
		(end 29.611828 -366.926368)
		(width 0.254)
		(layer "F.Cu")
		(net "FDPB_FAN_LED0")
	)
	(segment
		(start 31.489396 -365.0488)
		(end 31.514796 -365.0488)
		(width 0.254)
		(layer "F.Cu")
		(net "FDPB_FAN_LED0")
	)
	(segment
		(start 30.244796 -366.2934)
		(end 31.489396 -365.0488)
		(width 0.254)
		(layer "F.Cu")
		(net "FDPB_FAN_LED0")
	)
	(via
		(at 224.28962 -155.43276)
		(size 0.5588)
		(drill 0.3048)
		(layers "F.Cu" "B.Cu")
		(net "FDPB_FAN_LED0")
	)
	(via
		(at 201.08672 -157.2387)
		(size 0.5588)
		(drill 0.3048)
		(layers "F.Cu" "B.Cu")
		(net "FDPB_FAN_LED0")
	)
	(via
		(at 30.244796 -366.2934)
		(size 0.6604)
		(drill 0.3302)
		(layers "F.Cu" "B.Cu")
		(net "FDPB_FAN_LED0")
	)
	(via
		(at 31.514796 -365.0488)
		(size 0.5588)
		(drill 0.3048)
		(layers "F.Cu" "B.Cu")
		(net "FDPB_FAN_LED0")
	)
	(segment
		(start 31.514796 -364.925864)
		(end 31.540196 -364.900464)
		(width 0.254)
		(layer "In2.Cu")
		(net "FDPB_FAN_LED0")
	)
	(segment
		(start 224.282254 -155.425394)
		(end 224.28962 -155.43276)
		(width 0.254)
		(layer "In2.Cu")
		(net "FDPB_FAN_LED0")
	)
	(segment
		(start 199.009 -218.4654)
		(end 199.009 -192.6844)
		(width 0.254)
		(layer "In2.Cu")
		(net "FDPB_FAN_LED0")
	)
	(segment
		(start 201.5998 -167.3352)
		(end 200.445116 -166.180516)
		(width 0.254)
		(layer "In2.Cu")
		(net "FDPB_FAN_LED0")
	)
	(segment
		(start 200.445116 -166.180516)
		(end 200.445116 -157.880304)
		(width 0.254)
		(layer "In2.Cu")
		(net "FDPB_FAN_LED0")
	)
	(segment
		(start 31.540196 -362.384848)
		(end 35.299396 -358.625648)
		(width 0.254)
		(layer "In2.Cu")
		(net "FDPB_FAN_LED0")
	)
	(segment
		(start 201.5998 -172.963078)
		(end 201.5998 -167.3352)
		(width 0.254)
		(layer "In2.Cu")
		(net "FDPB_FAN_LED0")
	)
	(segment
		(start 236.061504 -76.004166)
		(end 236.061504 -102.926896)
		(width 0.254)
		(layer "In2.Cu")
		(net "FDPB_FAN_LED0")
	)
	(segment
		(start 231.599994 -71.699882)
		(end 231.75722 -71.699882)
		(width 0.254)
		(layer "In2.Cu")
		(net "FDPB_FAN_LED0")
	)
	(segment
		(start 31.514796 -365.0488)
		(end 31.514796 -364.925864)
		(width 0.254)
		(layer "In2.Cu")
		(net "FDPB_FAN_LED0")
	)
	(segment
		(start 200.914 -173.648878)
		(end 201.5998 -172.963078)
		(width 0.254)
		(layer "In2.Cu")
		(net "FDPB_FAN_LED0")
	)
	(segment
		(start 199.009 -192.6844)
		(end 200.914 -190.7794)
		(width 0.254)
		(layer "In2.Cu")
		(net "FDPB_FAN_LED0")
	)
	(segment
		(start 196.0118 -288.275522)
		(end 196.0118 -221.4626)
		(width 0.254)
		(layer "In2.Cu")
		(net "FDPB_FAN_LED0")
	)
	(segment
		(start 200.445116 -157.880304)
		(end 201.08672 -157.2387)
		(width 0.254)
		(layer "In2.Cu")
		(net "FDPB_FAN_LED0")
	)
	(segment
		(start 31.540196 -364.900464)
		(end 31.540196 -362.384848)
		(width 0.254)
		(layer "In2.Cu")
		(net "FDPB_FAN_LED0")
	)
	(segment
		(start 196.0118 -221.4626)
		(end 199.009 -218.4654)
		(width 0.254)
		(layer "In2.Cu")
		(net "FDPB_FAN_LED0")
	)
	(segment
		(start 200.914 -190.7794)
		(end 200.914 -173.648878)
		(width 0.254)
		(layer "In2.Cu")
		(net "FDPB_FAN_LED0")
	)
	(segment
		(start 231.75722 -71.699882)
		(end 236.061504 -76.004166)
		(width 0.254)
		(layer "In2.Cu")
		(net "FDPB_FAN_LED0")
	)
	(segment
		(start 35.299396 -323.334126)
		(end 46.90237 -311.731152)
		(width 0.254)
		(layer "In2.Cu")
		(net "FDPB_FAN_LED0")
	)
	(segment
		(start 35.299396 -358.625648)
		(end 35.299396 -323.334126)
		(width 0.254)
		(layer "In2.Cu")
		(net "FDPB_FAN_LED0")
	)
	(segment
		(start 224.282254 -114.706146)
		(end 224.282254 -155.425394)
		(width 0.254)
		(layer "In2.Cu")
		(net "FDPB_FAN_LED0")
	)
	(segment
		(start 46.90237 -311.731152)
		(end 172.55617 -311.731152)
		(width 0.254)
		(layer "In2.Cu")
		(net "FDPB_FAN_LED0")
	)
	(segment
		(start 236.061504 -102.926896)
		(end 224.282254 -114.706146)
		(width 0.254)
		(layer "In2.Cu")
		(net "FDPB_FAN_LED0")
	)
	(segment
		(start 172.55617 -311.731152)
		(end 196.0118 -288.275522)
		(width 0.254)
		(layer "In2.Cu")
		(net "FDPB_FAN_LED0")
	)
	(segment
		(start 201.08672 -157.2387)
		(end 201.2188 -157.2387)
		(width 0.254)
		(layer "In5.Cu")
		(net "FDPB_FAN_LED0")
	)
	(segment
		(start 212.86724 -156.10078)
		(end 216.98458 -156.10078)
		(width 0.254)
		(layer "In5.Cu")
		(net "FDPB_FAN_LED0")
	)
	(segment
		(start 212.202522 -156.765498)
		(end 212.86724 -156.10078)
		(width 0.254)
		(layer "In5.Cu")
		(net "FDPB_FAN_LED0")
	)
	(segment
		(start 217.7542 -155.33116)
		(end 224.18802 -155.33116)
		(width 0.254)
		(layer "In5.Cu")
		(net "FDPB_FAN_LED0")
	)
	(segment
		(start 216.98458 -156.10078)
		(end 217.7542 -155.33116)
		(width 0.254)
		(layer "In5.Cu")
		(net "FDPB_FAN_LED0")
	)
	(segment
		(start 201.2188 -157.2387)
		(end 201.692002 -156.765498)
		(width 0.254)
		(layer "In5.Cu")
		(net "FDPB_FAN_LED0")
	)
	(segment
		(start 224.18802 -155.33116)
		(end 224.28962 -155.43276)
		(width 0.254)
		(layer "In5.Cu")
		(net "FDPB_FAN_LED0")
	)
	(segment
		(start 201.692002 -156.765498)
		(end 212.202522 -156.765498)
		(width 0.254)
		(layer "In5.Cu")
		(net "FDPB_FAN_LED0")
	)
	(segment
		(start 460.737204 -373.6086)
		(end 461.715104 -373.6086)
		(width 0.254)
		(layer "F.Cu")
		(net "FAN_YELLOW_LED3")
	)
	(segment
		(start 461.715104 -374.2309)
		(end 461.715104 -373.6086)
		(width 0.254)
		(layer "F.Cu")
		(net "FAN_YELLOW_LED3")
	)
	(segment
		(start 459.704694 -373.634)
		(end 460.711804 -373.634)
		(width 0.254)
		(layer "F.Cu")
		(net "FAN_YELLOW_LED3")
	)
	(segment
		(start 461.296004 -375.07291)
		(end 461.296004 -374.65)
		(width 0.254)
		(layer "F.Cu")
		(net "FAN_YELLOW_LED3")
	)
	(segment
		(start 460.711804 -373.634)
		(end 460.737204 -373.6086)
		(width 0.254)
		(layer "F.Cu")
		(net "FAN_YELLOW_LED3")
	)
	(segment
		(start 461.296004 -374.65)
		(end 461.715104 -374.2309)
		(width 0.254)
		(layer "F.Cu")
		(net "FAN_YELLOW_LED3")
	)
	(via
		(at 460.711804 -373.634)
		(size 0.6604)
		(drill 0.3302)
		(layers "F.Cu" "B.Cu")
		(net "FAN_YELLOW_LED3")
	)
	(segment
		(start 322.573396 -379.4506)
		(end 322.725796 -379.2982)
		(width 0.254)
		(layer "F.Cu")
		(net "FAN_YELLOW_LED2")
	)
	(segment
		(start 321.836796 -379.4506)
		(end 322.573396 -379.4506)
		(width 0.254)
		(layer "F.Cu")
		(net "FAN_YELLOW_LED2")
	)
	(segment
		(start 321.709796 -379.3236)
		(end 321.836796 -379.4506)
		(width 0.254)
		(layer "F.Cu")
		(net "FAN_YELLOW_LED2")
	)
	(segment
		(start 321.312286 -379.3236)
		(end 321.709796 -379.3236)
		(width 0.254)
		(layer "F.Cu")
		(net "FAN_YELLOW_LED2")
	)
	(segment
		(start 322.916296 -377.8123)
		(end 323.809106 -376.91949)
		(width 0.254)
		(layer "F.Cu")
		(net "FAN_YELLOW_LED2")
	)
	(segment
		(start 323.809106 -376.91949)
		(end 323.809106 -376.7836)
		(width 0.254)
		(layer "F.Cu")
		(net "FAN_YELLOW_LED2")
	)
	(segment
		(start 322.916296 -378.1044)
		(end 322.916296 -377.8123)
		(width 0.254)
		(layer "F.Cu")
		(net "FAN_YELLOW_LED2")
	)
	(segment
		(start 322.916296 -378.1044)
		(end 322.916296 -379.1077)
		(width 0.254)
		(layer "F.Cu")
		(net "FAN_YELLOW_LED2")
	)
	(segment
		(start 322.916296 -379.1077)
		(end 322.725796 -379.2982)
		(width 0.254)
		(layer "F.Cu")
		(net "FAN_YELLOW_LED2")
	)
	(via
		(at 322.725796 -379.2982)
		(size 0.6604)
		(drill 0.3302)
		(layers "F.Cu" "B.Cu")
		(net "FAN_YELLOW_LED2")
	)
	(segment
		(start 190.368428 -372.140226)
		(end 191.219328 -371.289326)
		(width 0.254)
		(layer "F.Cu")
		(net "FAN_YELLOW_LED1")
	)
	(segment
		(start 190.368428 -372.347236)
		(end 190.368428 -372.664736)
		(width 0.254)
		(layer "F.Cu")
		(net "FAN_YELLOW_LED1")
	)
	(segment
		(start 190.558928 -372.855236)
		(end 190.558928 -374.023636)
		(width 0.254)
		(layer "F.Cu")
		(net "FAN_YELLOW_LED1")
	)
	(segment
		(start 190.368428 -372.664736)
		(end 190.558928 -372.855236)
		(width 0.254)
		(layer "F.Cu")
		(net "FAN_YELLOW_LED1")
	)
	(segment
		(start 189.145418 -374.531636)
		(end 190.050928 -374.531636)
		(width 0.254)
		(layer "F.Cu")
		(net "FAN_YELLOW_LED1")
	)
	(segment
		(start 190.368428 -372.347236)
		(end 190.368428 -372.140226)
		(width 0.254)
		(layer "F.Cu")
		(net "FAN_YELLOW_LED1")
	)
	(segment
		(start 190.050928 -374.531636)
		(end 190.558928 -374.023636)
		(width 0.254)
		(layer "F.Cu")
		(net "FAN_YELLOW_LED1")
	)
	(via
		(at 190.558928 -374.023636)
		(size 0.6604)
		(drill 0.3302)
		(layers "F.Cu" "B.Cu")
		(net "FAN_YELLOW_LED1")
	)
	(segment
		(start 31.540196 -378.1044)
		(end 31.641796 -378.0028)
		(width 0.254)
		(layer "F.Cu")
		(net "FAN_YELLOW_LED0")
	)
	(segment
		(start 30.152086 -378.1044)
		(end 31.540196 -378.1044)
		(width 0.254)
		(layer "F.Cu")
		(net "FAN_YELLOW_LED0")
	)
	(segment
		(start 31.908496 -376.9868)
		(end 31.908496 -376.5423)
		(width 0.254)
		(layer "F.Cu")
		(net "FAN_YELLOW_LED0")
	)
	(segment
		(start 31.908496 -376.9868)
		(end 31.908496 -377.7361)
		(width 0.254)
		(layer "F.Cu")
		(net "FAN_YELLOW_LED0")
	)
	(segment
		(start 32.594296 -375.8565)
		(end 32.594296 -375.6914)
		(width 0.254)
		(layer "F.Cu")
		(net "FAN_YELLOW_LED0")
	)
	(segment
		(start 31.908496 -377.7361)
		(end 31.641796 -378.0028)
		(width 0.254)
		(layer "F.Cu")
		(net "FAN_YELLOW_LED0")
	)
	(segment
		(start 31.908496 -376.5423)
		(end 32.594296 -375.8565)
		(width 0.254)
		(layer "F.Cu")
		(net "FAN_YELLOW_LED0")
	)
	(via
		(at 31.641796 -378.0028)
		(size 0.6604)
		(drill 0.3302)
		(layers "F.Cu" "B.Cu")
		(net "FAN_YELLOW_LED0")
	)
	(via
		(at 433.415186 -112.066578)
		(size 0.6604)
		(drill 0.3302)
		(layers "F.Cu" "B.Cu")
		(net "P12V_B_4_VIN_U34")
	)
	(via
		(at 433.542186 -113.082578)
		(size 0.5588)
		(drill 0.3048)
		(layers "F.Cu" "B.Cu")
		(net "P12V_B_4_VIN_U34")
	)
	(via
		(at 433.923186 -114.098578)
		(size 0.5588)
		(drill 0.3048)
		(layers "F.Cu" "B.Cu")
		(net "P12V_B_4_VIN_U34")
	)
	(via
		(at 429.097186 -118.479316)
		(size 0.6096)
		(drill 0.3048)
		(layers "F.Cu" "B.Cu")
		(net "P12V_B_4_VDD_U34")
	)
	(segment
		(start 433.110386 -117.197378)
		(end 431.828448 -118.479316)
		(width 0.508)
		(layer "B.Cu")
		(net "P12V_B_4_VDD_U34")
	)
	(segment
		(start 428.143924 -118.479316)
		(end 429.097186 -118.479316)
		(width 0.508)
		(layer "B.Cu")
		(net "P12V_B_4_VDD_U34")
	)
	(segment
		(start 434.989986 -115.600226)
		(end 434.745384 -115.844828)
		(width 0.3048)
		(layer "B.Cu")
		(net "P12V_B_4_VDD_U34")
	)
	(segment
		(start 435.852062 -115.600226)
		(end 434.989986 -115.600226)
		(width 0.3048)
		(layer "B.Cu")
		(net "P12V_B_4_VDD_U34")
	)
	(segment
		(start 431.828448 -118.479316)
		(end 429.097186 -118.479316)
		(width 0.508)
		(layer "B.Cu")
		(net "P12V_B_4_VDD_U34")
	)
	(segment
		(start 424.906186 -112.955578)
		(end 424.906186 -115.241578)
		(width 0.508)
		(layer "B.Cu")
		(net "P12V_B_4_VDD_U34")
	)
	(segment
		(start 424.906186 -115.241578)
		(end 428.143924 -118.479316)
		(width 0.508)
		(layer "B.Cu")
		(net "P12V_B_4_VDD_U34")
	)
	(segment
		(start 433.110386 -116.765578)
		(end 433.110386 -117.197378)
		(width 0.508)
		(layer "B.Cu")
		(net "P12V_B_4_VDD_U34")
	)
	(segment
		(start 434.745384 -115.844828)
		(end 434.031136 -115.844828)
		(width 0.3048)
		(layer "B.Cu")
		(net "P12V_B_4_VDD_U34")
	)
	(segment
		(start 434.031136 -115.844828)
		(end 433.110386 -116.765578)
		(width 0.3048)
		(layer "B.Cu")
		(net "P12V_B_4_VDD_U34")
	)
	(via
		(at 452.313802 -222.38335)
		(size 0.6604)
		(drill 0.3302)
		(layers "F.Cu" "B.Cu")
		(net "P12V_B_3_VIN_U33")
	)
	(via
		(at 452.440802 -223.39935)
		(size 0.5588)
		(drill 0.3048)
		(layers "F.Cu" "B.Cu")
		(net "P12V_B_3_VIN_U33")
	)
	(via
		(at 452.821802 -224.41535)
		(size 0.5588)
		(drill 0.3048)
		(layers "F.Cu" "B.Cu")
		(net "P12V_B_3_VIN_U33")
	)
	(via
		(at 447.995802 -228.796088)
		(size 0.6096)
		(drill 0.3048)
		(layers "F.Cu" "B.Cu")
		(net "P12V_B_3_VDD_U33")
	)
	(segment
		(start 453.732392 -226.06635)
		(end 453.456802 -226.06635)
		(width 0.3048)
		(layer "B.Cu")
		(net "P12V_B_3_VDD_U33")
	)
	(segment
		(start 454.750678 -225.916998)
		(end 453.881744 -225.916998)
		(width 0.3048)
		(layer "B.Cu")
		(net "P12V_B_3_VDD_U33")
	)
	(segment
		(start 450.727064 -228.796088)
		(end 452.009002 -227.51415)
		(width 0.508)
		(layer "B.Cu")
		(net "P12V_B_3_VDD_U33")
	)
	(segment
		(start 453.075802 -226.44735)
		(end 452.644002 -226.44735)
		(width 0.3048)
		(layer "B.Cu")
		(net "P12V_B_3_VDD_U33")
	)
	(segment
		(start 443.804802 -225.55835)
		(end 447.04254 -228.796088)
		(width 0.508)
		(layer "B.Cu")
		(net "P12V_B_3_VDD_U33")
	)
	(segment
		(start 447.995802 -228.796088)
		(end 450.727064 -228.796088)
		(width 0.508)
		(layer "B.Cu")
		(net "P12V_B_3_VDD_U33")
	)
	(segment
		(start 452.009002 -227.51415)
		(end 452.009002 -227.08235)
		(width 0.508)
		(layer "B.Cu")
		(net "P12V_B_3_VDD_U33")
	)
	(segment
		(start 447.04254 -228.796088)
		(end 447.995802 -228.796088)
		(width 0.508)
		(layer "B.Cu")
		(net "P12V_B_3_VDD_U33")
	)
	(segment
		(start 453.881744 -225.916998)
		(end 453.732392 -226.06635)
		(width 0.3048)
		(layer "B.Cu")
		(net "P12V_B_3_VDD_U33")
	)
	(segment
		(start 453.456802 -226.06635)
		(end 453.075802 -226.44735)
		(width 0.3048)
		(layer "B.Cu")
		(net "P12V_B_3_VDD_U33")
	)
	(segment
		(start 452.644002 -226.44735)
		(end 452.009002 -227.08235)
		(width 0.3048)
		(layer "B.Cu")
		(net "P12V_B_3_VDD_U33")
	)
	(segment
		(start 443.804802 -223.27235)
		(end 443.804802 -225.55835)
		(width 0.508)
		(layer "B.Cu")
		(net "P12V_B_3_VDD_U33")
	)
	(via
		(at 42.05986 -113.230406)
		(size 0.5588)
		(drill 0.3048)
		(layers "F.Cu" "B.Cu")
		(net "P12V_B_2_VIN_U32")
	)
	(via
		(at 41.688258 -112.335056)
		(size 0.5588)
		(drill 0.3048)
		(layers "F.Cu" "B.Cu")
		(net "P12V_B_2_VIN_U32")
	)
	(via
		(at 41.762172 -111.293148)
		(size 0.6604)
		(drill 0.3302)
		(layers "F.Cu" "B.Cu")
		(net "P12V_B_2_VIN_U32")
	)
	(via
		(at 37.23386 -117.611144)
		(size 0.6096)
		(drill 0.3048)
		(layers "F.Cu" "B.Cu")
		(net "P12V_B_2_VDD_U32")
	)
	(segment
		(start 33.57626 -113.001806)
		(end 33.57626 -114.906806)
		(width 0.508)
		(layer "B.Cu")
		(net "P12V_B_2_VDD_U32")
	)
	(segment
		(start 42.42308 -115.262406)
		(end 41.88206 -115.262406)
		(width 0.3048)
		(layer "B.Cu")
		(net "P12V_B_2_VDD_U32")
	)
	(segment
		(start 37.23386 -117.611144)
		(end 39.965122 -117.611144)
		(width 0.508)
		(layer "B.Cu")
		(net "P12V_B_2_VDD_U32")
	)
	(segment
		(start 33.57626 -114.906806)
		(end 36.280598 -117.611144)
		(width 0.508)
		(layer "B.Cu")
		(net "P12V_B_2_VDD_U32")
	)
	(segment
		(start 43.119802 -114.732054)
		(end 43.0276 -114.824256)
		(width 0.3048)
		(layer "B.Cu")
		(net "P12V_B_2_VDD_U32")
	)
	(segment
		(start 39.965122 -117.611144)
		(end 41.24706 -116.329206)
		(width 0.508)
		(layer "B.Cu")
		(net "P12V_B_2_VDD_U32")
	)
	(segment
		(start 43.0276 -114.824256)
		(end 42.86123 -114.824256)
		(width 0.3048)
		(layer "B.Cu")
		(net "P12V_B_2_VDD_U32")
	)
	(segment
		(start 41.88206 -115.262406)
		(end 41.24706 -115.897406)
		(width 0.3048)
		(layer "B.Cu")
		(net "P12V_B_2_VDD_U32")
	)
	(segment
		(start 43.988736 -114.732054)
		(end 43.119802 -114.732054)
		(width 0.3048)
		(layer "B.Cu")
		(net "P12V_B_2_VDD_U32")
	)
	(segment
		(start 42.86123 -114.824256)
		(end 42.42308 -115.262406)
		(width 0.3048)
		(layer "B.Cu")
		(net "P12V_B_2_VDD_U32")
	)
	(segment
		(start 36.280598 -117.611144)
		(end 37.23386 -117.611144)
		(width 0.508)
		(layer "B.Cu")
		(net "P12V_B_2_VDD_U32")
	)
	(segment
		(start 41.24706 -116.329206)
		(end 41.24706 -115.897406)
		(width 0.508)
		(layer "B.Cu")
		(net "P12V_B_2_VDD_U32")
	)
	(via
		(at 17.211802 -224.41535)
		(size 0.5588)
		(drill 0.3048)
		(layers "F.Cu" "B.Cu")
		(net "P12V_B_1_VIN_U31")
	)
	(via
		(at 16.703802 -222.38335)
		(size 0.6604)
		(drill 0.3302)
		(layers "F.Cu" "B.Cu")
		(net "P12V_B_1_VIN_U31")
	)
	(via
		(at 16.830802 -223.39935)
		(size 0.5588)
		(drill 0.3048)
		(layers "F.Cu" "B.Cu")
		(net "P12V_B_1_VIN_U31")
	)
	(via
		(at 12.385802 -228.796088)
		(size 0.6096)
		(drill 0.3048)
		(layers "F.Cu" "B.Cu")
		(net "P12V_B_1_VDD_U31")
	)
	(segment
		(start 11.43254 -228.796088)
		(end 12.385802 -228.796088)
		(width 0.508)
		(layer "B.Cu")
		(net "P12V_B_1_VDD_U31")
	)
	(segment
		(start 8.194802 -225.55835)
		(end 11.43254 -228.796088)
		(width 0.508)
		(layer "B.Cu")
		(net "P12V_B_1_VDD_U31")
	)
	(segment
		(start 12.385802 -228.796088)
		(end 15.117064 -228.796088)
		(width 0.508)
		(layer "B.Cu")
		(net "P12V_B_1_VDD_U31")
	)
	(segment
		(start 17.465802 -226.44735)
		(end 17.034002 -226.44735)
		(width 0.3048)
		(layer "B.Cu")
		(net "P12V_B_1_VDD_U31")
	)
	(segment
		(start 18.122392 -226.06635)
		(end 17.846802 -226.06635)
		(width 0.3048)
		(layer "B.Cu")
		(net "P12V_B_1_VDD_U31")
	)
	(segment
		(start 17.846802 -226.06635)
		(end 17.465802 -226.44735)
		(width 0.3048)
		(layer "B.Cu")
		(net "P12V_B_1_VDD_U31")
	)
	(segment
		(start 18.271744 -225.916998)
		(end 18.122392 -226.06635)
		(width 0.3048)
		(layer "B.Cu")
		(net "P12V_B_1_VDD_U31")
	)
	(segment
		(start 15.117064 -228.796088)
		(end 16.399002 -227.51415)
		(width 0.508)
		(layer "B.Cu")
		(net "P12V_B_1_VDD_U31")
	)
	(segment
		(start 17.034002 -226.44735)
		(end 16.399002 -227.08235)
		(width 0.3048)
		(layer "B.Cu")
		(net "P12V_B_1_VDD_U31")
	)
	(segment
		(start 8.194802 -223.27235)
		(end 8.194802 -225.55835)
		(width 0.508)
		(layer "B.Cu")
		(net "P12V_B_1_VDD_U31")
	)
	(segment
		(start 16.399002 -227.51415)
		(end 16.399002 -227.08235)
		(width 0.508)
		(layer "B.Cu")
		(net "P12V_B_1_VDD_U31")
	)
	(segment
		(start 19.140678 -225.916998)
		(end 18.271744 -225.916998)
		(width 0.3048)
		(layer "B.Cu")
		(net "P12V_B_1_VDD_U31")
	)
	(segment
		(start 290.137088 -350.396302)
		(end 289.690048 -350.843342)
		(width 0.254)
		(layer "F.Cu")
		(net "FANTACH_B_R3")
	)
	(segment
		(start 288.826448 -351.706942)
		(end 289.690048 -350.843342)
		(width 0.254)
		(layer "F.Cu")
		(net "FANTACH_B_R3")
	)
	(segment
		(start 287.683448 -351.948242)
		(end 288.585148 -351.948242)
		(width 0.2032)
		(layer "F.Cu")
		(net "FANTACH_B_R3")
	)
	(segment
		(start 299.392848 -350.396302)
		(end 290.137088 -350.396302)
		(width 0.254)
		(layer "F.Cu")
		(net "FANTACH_B_R3")
	)
	(segment
		(start 288.585148 -351.948242)
		(end 288.826448 -351.706942)
		(width 0.2032)
		(layer "F.Cu")
		(net "FANTACH_B_R3")
	)
	(via
		(at 289.690048 -350.843342)
		(size 0.6604)
		(drill 0.3302)
		(layers "F.Cu" "B.Cu")
		(net "FANTACH_B_R3")
	)
	(segment
		(start 290.894008 -351.696782)
		(end 289.60445 -352.98634)
		(width 0.254)
		(layer "F.Cu")
		(net "FANTACH_B_R2")
	)
	(segment
		(start 289.207448 -353.383342)
		(end 289.60445 -352.98634)
		(width 0.254)
		(layer "F.Cu")
		(net "FANTACH_B_R2")
	)
	(segment
		(start 287.683448 -353.548442)
		(end 289.042348 -353.548442)
		(width 0.2032)
		(layer "F.Cu")
		(net "FANTACH_B_R2")
	)
	(segment
		(start 289.042348 -353.548442)
		(end 289.207448 -353.383342)
		(width 0.2032)
		(layer "F.Cu")
		(net "FANTACH_B_R2")
	)
	(segment
		(start 299.392848 -351.696782)
		(end 290.894008 -351.696782)
		(width 0.254)
		(layer "F.Cu")
		(net "FANTACH_B_R2")
	)
	(via
		(at 289.60445 -352.98634)
		(size 0.6604)
		(drill 0.3302)
		(layers "F.Cu" "B.Cu")
		(net "FANTACH_B_R2")
	)
	(segment
		(start 286.051498 -354.780342)
		(end 286.051498 -355.275134)
		(width 0.2032)
		(layer "F.Cu")
		(net "FANTACH_B_R1")
	)
	(segment
		(start 288.699448 -355.796342)
		(end 290.719256 -353.776534)
		(width 0.254)
		(layer "F.Cu")
		(net "FANTACH_B_R1")
	)
	(segment
		(start 286.572706 -355.796342)
		(end 286.794448 -355.796342)
		(width 0.2032)
		(layer "F.Cu")
		(net "FANTACH_B_R1")
	)
	(segment
		(start 291.498528 -352.997262)
		(end 290.719256 -353.776534)
		(width 0.254)
		(layer "F.Cu")
		(net "FANTACH_B_R1")
	)
	(segment
		(start 299.392848 -352.997262)
		(end 291.498528 -352.997262)
		(width 0.254)
		(layer "F.Cu")
		(net "FANTACH_B_R1")
	)
	(segment
		(start 286.794448 -355.796342)
		(end 288.699448 -355.796342)
		(width 0.254)
		(layer "F.Cu")
		(net "FANTACH_B_R1")
	)
	(segment
		(start 286.051498 -355.275134)
		(end 286.572706 -355.796342)
		(width 0.2032)
		(layer "F.Cu")
		(net "FANTACH_B_R1")
	)
	(via
		(at 290.719256 -353.776534)
		(size 0.6604)
		(drill 0.3302)
		(layers "F.Cu" "B.Cu")
		(net "FANTACH_B_R1")
	)
	(segment
		(start 285.651448 -355.669342)
		(end 286.032448 -356.050342)
		(width 0.2032)
		(layer "F.Cu")
		(net "FANTACH_B_R0")
	)
	(segment
		(start 297.538648 -354.297742)
		(end 299.392848 -354.297742)
		(width 0.254)
		(layer "F.Cu")
		(net "FANTACH_B_R0")
	)
	(segment
		(start 285.651448 -354.780342)
		(end 285.651448 -355.669342)
		(width 0.2032)
		(layer "F.Cu")
		(net "FANTACH_B_R0")
	)
	(segment
		(start 297.030648 -354.805742)
		(end 297.538648 -354.297742)
		(width 0.254)
		(layer "F.Cu")
		(net "FANTACH_B_R0")
	)
	(via
		(at 294.795448 -356.050342)
		(size 0.6096)
		(drill 0.3048)
		(layers "F.Cu" "B.Cu")
		(net "FANTACH_B_R0")
	)
	(via
		(at 297.030648 -354.805742)
		(size 0.5588)
		(drill 0.3048)
		(layers "F.Cu" "B.Cu")
		(net "FANTACH_B_R0")
	)
	(via
		(at 286.032448 -356.050342)
		(size 0.5588)
		(drill 0.3048)
		(layers "F.Cu" "B.Cu")
		(net "FANTACH_B_R0")
	)
	(segment
		(start 294.795448 -356.050342)
		(end 286.032448 -356.050342)
		(width 0.254)
		(layer "B.Cu")
		(net "FANTACH_B_R0")
	)
	(segment
		(start 295.786048 -356.050342)
		(end 294.795448 -356.050342)
		(width 0.254)
		(layer "B.Cu")
		(net "FANTACH_B_R0")
	)
	(segment
		(start 297.030648 -354.805742)
		(end 295.786048 -356.050342)
		(width 0.254)
		(layer "B.Cu")
		(net "FANTACH_B_R0")
	)
	(segment
		(start 307.533548 -356.060756)
		(end 307.533548 -355.26853)
		(width 0.254)
		(layer "F.Cu")
		(net "FANTACH_B_OE_N")
	)
	(segment
		(start 307.213 -354.947982)
		(end 305.031648 -354.947982)
		(width 0.254)
		(layer "F.Cu")
		(net "FANTACH_B_OE_N")
	)
	(segment
		(start 307.300884 -357.518462)
		(end 307.533548 -357.285798)
		(width 0.254)
		(layer "F.Cu")
		(net "FANTACH_B_OE_N")
	)
	(segment
		(start 307.533548 -355.26853)
		(end 307.213 -354.947982)
		(width 0.254)
		(layer "F.Cu")
		(net "FANTACH_B_OE_N")
	)
	(segment
		(start 307.533548 -357.285798)
		(end 307.533548 -356.060756)
		(width 0.254)
		(layer "F.Cu")
		(net "FANTACH_B_OE_N")
	)
	(via
		(at 307.213 -354.947982)
		(size 0.6604)
		(drill 0.3302)
		(layers "F.Cu" "B.Cu")
		(net "FANTACH_B_OE_N")
	)
	(segment
		(start 307.512974 -361.849416)
		(end 306.68976 -361.849416)
		(width 0.254)
		(layer "F.Cu")
		(net "FANTACH_B_OE")
	)
	(segment
		(start 307.96484 -361.39755)
		(end 307.512974 -361.849416)
		(width 0.254)
		(layer "F.Cu")
		(net "FANTACH_B_OE")
	)
	(segment
		(start 308.285134 -359.423462)
		(end 308.285134 -361.077256)
		(width 0.254)
		(layer "F.Cu")
		(net "FANTACH_B_OE")
	)
	(segment
		(start 305.707796 -361.849416)
		(end 306.68976 -361.849416)
		(width 0.254)
		(layer "F.Cu")
		(net "FANTACH_B_OE")
	)
	(segment
		(start 308.285134 -361.077256)
		(end 307.96484 -361.39755)
		(width 0.254)
		(layer "F.Cu")
		(net "FANTACH_B_OE")
	)
	(segment
		(start 305.685698 -361.871514)
		(end 305.707796 -361.849416)
		(width 0.254)
		(layer "F.Cu")
		(net "FANTACH_B_OE")
	)
	(via
		(at 307.96484 -361.39755)
		(size 0.6604)
		(drill 0.3302)
		(layers "F.Cu" "B.Cu")
		(net "FANTACH_B_OE")
	)
	(segment
		(start 291.468048 -351.046542)
		(end 299.392848 -351.046542)
		(width 0.254)
		(layer "F.Cu")
		(net "FANTACH_B_F3")
	)
	(segment
		(start 289.207448 -352.494342)
		(end 290.655248 -351.046542)
		(width 0.254)
		(layer "F.Cu")
		(net "FANTACH_B_F3")
	)
	(segment
		(start 288.953448 -352.748342)
		(end 289.207448 -352.494342)
		(width 0.2032)
		(layer "F.Cu")
		(net "FANTACH_B_F3")
	)
	(segment
		(start 287.683448 -352.748342)
		(end 288.953448 -352.748342)
		(width 0.2032)
		(layer "F.Cu")
		(net "FANTACH_B_F3")
	)
	(segment
		(start 290.655248 -351.046542)
		(end 291.468048 -351.046542)
		(width 0.254)
		(layer "F.Cu")
		(net "FANTACH_B_F3")
	)
	(via
		(at 291.468048 -351.046542)
		(size 0.6604)
		(drill 0.3302)
		(layers "F.Cu" "B.Cu")
		(net "FANTACH_B_F3")
	)
	(segment
		(start 286.851344 -354.780342)
		(end 287.810448 -354.780342)
		(width 0.2032)
		(layer "F.Cu")
		(net "FANTACH_B_F2")
	)
	(segment
		(start 287.810448 -354.780342)
		(end 288.724848 -354.780342)
		(width 0.254)
		(layer "F.Cu")
		(net "FANTACH_B_F2")
	)
	(segment
		(start 288.724848 -354.780342)
		(end 291.158168 -352.347022)
		(width 0.254)
		(layer "F.Cu")
		(net "FANTACH_B_F2")
	)
	(segment
		(start 291.158168 -352.347022)
		(end 291.417248 -352.347022)
		(width 0.254)
		(layer "F.Cu")
		(net "FANTACH_B_F2")
	)
	(segment
		(start 291.417248 -352.347022)
		(end 299.392848 -352.347022)
		(width 0.254)
		(layer "F.Cu")
		(net "FANTACH_B_F2")
	)
	(via
		(at 291.417248 -352.347022)
		(size 0.6604)
		(drill 0.3302)
		(layers "F.Cu" "B.Cu")
		(net "FANTACH_B_F2")
	)
	(segment
		(start 285.251398 -355.549454)
		(end 285.308548 -355.606604)
		(width 0.2032)
		(layer "F.Cu")
		(net "FANTACH_B_F1")
	)
	(segment
		(start 299.392848 -353.647502)
		(end 291.81044 -353.647502)
		(width 0.254)
		(layer "F.Cu")
		(net "FANTACH_B_F1")
	)
	(segment
		(start 285.308548 -355.606604)
		(end 285.308548 -356.080822)
		(width 0.2032)
		(layer "F.Cu")
		(net "FANTACH_B_F1")
	)
	(segment
		(start 285.251398 -354.780342)
		(end 285.251398 -355.549454)
		(width 0.2032)
		(layer "F.Cu")
		(net "FANTACH_B_F1")
	)
	(segment
		(start 285.308548 -356.080822)
		(end 285.811468 -356.583742)
		(width 0.2032)
		(layer "F.Cu")
		(net "FANTACH_B_F1")
	)
	(segment
		(start 290.883848 -354.574094)
		(end 290.883848 -354.584508)
		(width 0.254)
		(layer "F.Cu")
		(net "FANTACH_B_F1")
	)
	(segment
		(start 290.883848 -354.584508)
		(end 289.954716 -355.51364)
		(width 0.254)
		(layer "F.Cu")
		(net "FANTACH_B_F1")
	)
	(segment
		(start 285.811468 -356.583742)
		(end 286.667448 -356.583742)
		(width 0.2032)
		(layer "F.Cu")
		(net "FANTACH_B_F1")
	)
	(segment
		(start 286.667448 -356.583742)
		(end 288.884614 -356.583742)
		(width 0.254)
		(layer "F.Cu")
		(net "FANTACH_B_F1")
	)
	(segment
		(start 288.884614 -356.583742)
		(end 289.954716 -355.51364)
		(width 0.254)
		(layer "F.Cu")
		(net "FANTACH_B_F1")
	)
	(segment
		(start 291.81044 -353.647502)
		(end 290.883848 -354.574094)
		(width 0.254)
		(layer "F.Cu")
		(net "FANTACH_B_F1")
	)
	(via
		(at 289.954716 -355.51364)
		(size 0.6604)
		(drill 0.3302)
		(layers "F.Cu" "B.Cu")
		(net "FANTACH_B_F1")
	)
	(segment
		(start 295.204896 -357.421942)
		(end 297.678856 -354.947982)
		(width 0.254)
		(layer "F.Cu")
		(net "FANTACH_B_F0")
	)
	(segment
		(start 284.851348 -356.545642)
		(end 285.727648 -357.421942)
		(width 0.254)
		(layer "F.Cu")
		(net "FANTACH_B_F0")
	)
	(segment
		(start 284.851348 -354.780342)
		(end 284.851348 -356.545642)
		(width 0.2032)
		(layer "F.Cu")
		(net "FANTACH_B_F0")
	)
	(segment
		(start 285.727648 -357.421942)
		(end 287.886648 -357.421942)
		(width 0.254)
		(layer "F.Cu")
		(net "FANTACH_B_F0")
	)
	(segment
		(start 287.886648 -357.421942)
		(end 295.204896 -357.421942)
		(width 0.254)
		(layer "F.Cu")
		(net "FANTACH_B_F0")
	)
	(segment
		(start 297.678856 -354.947982)
		(end 299.392848 -354.947982)
		(width 0.254)
		(layer "F.Cu")
		(net "FANTACH_B_F0")
	)
	(via
		(at 287.886648 -357.421942)
		(size 0.6604)
		(drill 0.3302)
		(layers "F.Cu" "B.Cu")
		(net "FANTACH_B_F0")
	)
	(segment
		(start 238.51616 -308.98084)
		(end 237.0328 -308.98084)
		(width 0.254)
		(layer "F.Cu")
		(net "FANTACH_A_R3")
	)
	(segment
		(start 239.9919 -307.5051)
		(end 239.903 -307.594)
		(width 0.2032)
		(layer "F.Cu")
		(net "FANTACH_A_R3")
	)
	(segment
		(start 233.8324 -308.98084)
		(end 237.0328 -308.98084)
		(width 0.254)
		(layer "F.Cu")
		(net "FANTACH_A_R3")
	)
	(segment
		(start 239.903 -307.594)
		(end 238.51616 -308.98084)
		(width 0.254)
		(layer "F.Cu")
		(net "FANTACH_A_R3")
	)
	(segment
		(start 241.046 -307.5051)
		(end 239.9919 -307.5051)
		(width 0.2032)
		(layer "F.Cu")
		(net "FANTACH_A_R3")
	)
	(via
		(at 237.0328 -308.98084)
		(size 0.6604)
		(drill 0.3302)
		(layers "F.Cu" "B.Cu")
		(net "FANTACH_A_R3")
	)
	(segment
		(start 239.522 -306.07)
		(end 237.91164 -307.68036)
		(width 0.254)
		(layer "F.Cu")
		(net "FANTACH_A_R2")
	)
	(segment
		(start 235.585 -307.68036)
		(end 233.8324 -307.68036)
		(width 0.254)
		(layer "F.Cu")
		(net "FANTACH_A_R2")
	)
	(segment
		(start 241.046 -305.9049)
		(end 239.6871 -305.9049)
		(width 0.2032)
		(layer "F.Cu")
		(net "FANTACH_A_R2")
	)
	(segment
		(start 239.6871 -305.9049)
		(end 239.522 -306.07)
		(width 0.2032)
		(layer "F.Cu")
		(net "FANTACH_A_R2")
	)
	(segment
		(start 237.91164 -307.68036)
		(end 235.585 -307.68036)
		(width 0.254)
		(layer "F.Cu")
		(net "FANTACH_A_R2")
	)
	(via
		(at 235.585 -307.68036)
		(size 0.6604)
		(drill 0.3302)
		(layers "F.Cu" "B.Cu")
		(net "FANTACH_A_R2")
	)
	(segment
		(start 242.156742 -303.657)
		(end 241.935 -303.657)
		(width 0.2032)
		(layer "F.Cu")
		(net "FANTACH_A_R1")
	)
	(segment
		(start 241.935 -303.657)
		(end 239.5728 -303.657)
		(width 0.254)
		(layer "F.Cu")
		(net "FANTACH_A_R1")
	)
	(segment
		(start 242.67795 -304.673)
		(end 242.67795 -304.178208)
		(width 0.2032)
		(layer "F.Cu")
		(net "FANTACH_A_R1")
	)
	(segment
		(start 239.5728 -303.657)
		(end 236.84992 -306.37988)
		(width 0.254)
		(layer "F.Cu")
		(net "FANTACH_A_R1")
	)
	(segment
		(start 233.8324 -306.37988)
		(end 236.7026 -306.37988)
		(width 0.254)
		(layer "F.Cu")
		(net "FANTACH_A_R1")
	)
	(segment
		(start 242.67795 -304.178208)
		(end 242.156742 -303.657)
		(width 0.2032)
		(layer "F.Cu")
		(net "FANTACH_A_R1")
	)
	(segment
		(start 236.84992 -306.37988)
		(end 236.7026 -306.37988)
		(width 0.254)
		(layer "F.Cu")
		(net "FANTACH_A_R1")
	)
	(via
		(at 236.7026 -306.37988)
		(size 0.6604)
		(drill 0.3302)
		(layers "F.Cu" "B.Cu")
		(net "FANTACH_A_R1")
	)
	(segment
		(start 243.078 -303.931574)
		(end 242.346226 -303.1998)
		(width 0.2032)
		(layer "F.Cu")
		(net "FANTACH_A_R0")
	)
	(segment
		(start 242.242848 -303.0982)
		(end 241.935 -303.0982)
		(width 0.2032)
		(layer "F.Cu")
		(net "FANTACH_A_R0")
	)
	(segment
		(start 242.344448 -303.1998)
		(end 242.242848 -303.0982)
		(width 0.2032)
		(layer "F.Cu")
		(net "FANTACH_A_R0")
	)
	(segment
		(start 243.078 -304.673)
		(end 243.078 -303.931574)
		(width 0.2032)
		(layer "F.Cu")
		(net "FANTACH_A_R0")
	)
	(segment
		(start 242.346226 -303.1998)
		(end 242.344448 -303.1998)
		(width 0.2032)
		(layer "F.Cu")
		(net "FANTACH_A_R0")
	)
	(segment
		(start 233.8324 -305.0794)
		(end 234.8484 -305.0794)
		(width 0.254)
		(layer "F.Cu")
		(net "FANTACH_A_R0")
	)
	(segment
		(start 234.8484 -305.0794)
		(end 235.3818 -304.546)
		(width 0.254)
		(layer "F.Cu")
		(net "FANTACH_A_R0")
	)
	(via
		(at 239.2934 -303.0982)
		(size 0.6096)
		(drill 0.3048)
		(layers "F.Cu" "B.Cu")
		(net "FANTACH_A_R0")
	)
	(via
		(at 241.935 -303.0982)
		(size 0.5588)
		(drill 0.3048)
		(layers "F.Cu" "B.Cu")
		(net "FANTACH_A_R0")
	)
	(via
		(at 235.3818 -304.546)
		(size 0.5588)
		(drill 0.3048)
		(layers "F.Cu" "B.Cu")
		(net "FANTACH_A_R0")
	)
	(segment
		(start 236.8296 -303.0982)
		(end 235.3818 -304.546)
		(width 0.254)
		(layer "B.Cu")
		(net "FANTACH_A_R0")
	)
	(segment
		(start 241.935 -303.0982)
		(end 239.2934 -303.0982)
		(width 0.254)
		(layer "B.Cu")
		(net "FANTACH_A_R0")
	)
	(segment
		(start 239.2934 -303.0982)
		(end 236.8296 -303.0982)
		(width 0.254)
		(layer "B.Cu")
		(net "FANTACH_A_R0")
	)
	(segment
		(start 221.996 -306.2351)
		(end 223.9391 -306.2351)
		(width 0.254)
		(layer "F.Cu")
		(net "FANTACH_A_OE_N")
	)
	(segment
		(start 226.41433 -304.3936)
		(end 226.14763 -304.1269)
		(width 0.254)
		(layer "F.Cu")
		(net "FANTACH_A_OE_N")
	)
	(segment
		(start 225.552 -304.6222)
		(end 224.819972 -305.354228)
		(width 0.254)
		(layer "F.Cu")
		(net "FANTACH_A_OE_N")
	)
	(segment
		(start 228.1936 -304.42916)
		(end 226.47656 -304.42916)
		(width 0.254)
		(layer "F.Cu")
		(net "FANTACH_A_OE_N")
	)
	(segment
		(start 226.14763 -304.1269)
		(end 225.552 -304.1269)
		(width 0.254)
		(layer "F.Cu")
		(net "FANTACH_A_OE_N")
	)
	(segment
		(start 226.441 -304.3936)
		(end 226.41433 -304.3936)
		(width 0.254)
		(layer "F.Cu")
		(net "FANTACH_A_OE_N")
	)
	(segment
		(start 226.47656 -304.42916)
		(end 226.441 -304.3936)
		(width 0.254)
		(layer "F.Cu")
		(net "FANTACH_A_OE_N")
	)
	(segment
		(start 223.9391 -306.2351)
		(end 224.819972 -305.354228)
		(width 0.254)
		(layer "F.Cu")
		(net "FANTACH_A_OE_N")
	)
	(segment
		(start 225.552 -304.1269)
		(end 225.552 -304.6222)
		(width 0.254)
		(layer "F.Cu")
		(net "FANTACH_A_OE_N")
	)
	(via
		(at 224.819972 -305.354228)
		(size 0.6604)
		(drill 0.3302)
		(layers "F.Cu" "B.Cu")
		(net "FANTACH_A_OE_N")
	)
	(segment
		(start 220.7006 -302.9204)
		(end 220.7006 -301.8155)
		(width 0.254)
		(layer "F.Cu")
		(net "FANTACH_A_OE")
	)
	(segment
		(start 220.7006 -304.01895)
		(end 220.7006 -302.9204)
		(width 0.254)
		(layer "F.Cu")
		(net "FANTACH_A_OE")
	)
	(segment
		(start 221.01175 -304.3301)
		(end 220.7006 -304.01895)
		(width 0.254)
		(layer "F.Cu")
		(net "FANTACH_A_OE")
	)
	(segment
		(start 220.7006 -301.8155)
		(end 221.8182 -301.8155)
		(width 0.254)
		(layer "F.Cu")
		(net "FANTACH_A_OE")
	)
	(segment
		(start 221.8182 -301.8155)
		(end 221.8563 -301.8536)
		(width 0.254)
		(layer "F.Cu")
		(net "FANTACH_A_OE")
	)
	(via
		(at 220.7006 -302.9204)
		(size 0.6604)
		(drill 0.3302)
		(layers "F.Cu" "B.Cu")
		(net "FANTACH_A_OE")
	)
	(segment
		(start 239.522 -306.959)
		(end 238.802672 -307.678328)
		(width 0.254)
		(layer "F.Cu")
		(net "FANTACH_A_F3")
	)
	(segment
		(start 239.776 -306.705)
		(end 239.522 -306.959)
		(width 0.2032)
		(layer "F.Cu")
		(net "FANTACH_A_F3")
	)
	(segment
		(start 233.8324 -308.3306)
		(end 238.1504 -308.3306)
		(width 0.254)
		(layer "F.Cu")
		(net "FANTACH_A_F3")
	)
	(segment
		(start 238.1504 -308.3306)
		(end 238.802672 -307.678328)
		(width 0.254)
		(layer "F.Cu")
		(net "FANTACH_A_F3")
	)
	(segment
		(start 241.046 -306.705)
		(end 239.776 -306.705)
		(width 0.2032)
		(layer "F.Cu")
		(net "FANTACH_A_F3")
	)
	(via
		(at 238.802672 -307.678328)
		(size 0.6604)
		(drill 0.3302)
		(layers "F.Cu" "B.Cu")
		(net "FANTACH_A_F3")
	)
	(segment
		(start 239.8776 -304.673)
		(end 239.51057 -305.04003)
		(width 0.254)
		(layer "F.Cu")
		(net "FANTACH_A_F2")
	)
	(segment
		(start 240.919 -304.673)
		(end 239.8776 -304.673)
		(width 0.254)
		(layer "F.Cu")
		(net "FANTACH_A_F2")
	)
	(segment
		(start 233.8324 -307.03012)
		(end 237.52048 -307.03012)
		(width 0.254)
		(layer "F.Cu")
		(net "FANTACH_A_F2")
	)
	(segment
		(start 241.878104 -304.673)
		(end 240.919 -304.673)
		(width 0.2032)
		(layer "F.Cu")
		(net "FANTACH_A_F2")
	)
	(segment
		(start 237.52048 -307.03012)
		(end 239.51057 -305.04003)
		(width 0.254)
		(layer "F.Cu")
		(net "FANTACH_A_F2")
	)
	(via
		(at 239.51057 -305.04003)
		(size 0.6604)
		(drill 0.3302)
		(layers "F.Cu" "B.Cu")
		(net "FANTACH_A_F2")
	)
	(segment
		(start 243.47805 -304.673)
		(end 243.47805 -303.59985)
		(width 0.2032)
		(layer "F.Cu")
		(net "FANTACH_A_F1")
	)
	(segment
		(start 242.4176 -302.5394)
		(end 239.0648 -302.5394)
		(width 0.254)
		(layer "F.Cu")
		(net "FANTACH_A_F1")
	)
	(segment
		(start 243.47805 -303.59985)
		(end 242.57 -302.6918)
		(width 0.2032)
		(layer "F.Cu")
		(net "FANTACH_A_F1")
	)
	(segment
		(start 239.0648 -302.5394)
		(end 237.304834 -304.299366)
		(width 0.254)
		(layer "F.Cu")
		(net "FANTACH_A_F1")
	)
	(segment
		(start 235.87456 -305.72964)
		(end 237.304834 -304.299366)
		(width 0.254)
		(layer "F.Cu")
		(net "FANTACH_A_F1")
	)
	(segment
		(start 242.57 -302.6918)
		(end 242.4176 -302.5394)
		(width 0.254)
		(layer "F.Cu")
		(net "FANTACH_A_F1")
	)
	(segment
		(start 233.8324 -305.72964)
		(end 235.87456 -305.72964)
		(width 0.254)
		(layer "F.Cu")
		(net "FANTACH_A_F1")
	)
	(via
		(at 237.304834 -304.299366)
		(size 0.6604)
		(drill 0.3302)
		(layers "F.Cu" "B.Cu")
		(net "FANTACH_A_F1")
	)
	(segment
		(start 235.4072 -303.6316)
		(end 236.093 -303.6316)
		(width 0.254)
		(layer "F.Cu")
		(net "FANTACH_A_F0")
	)
	(segment
		(start 243.96065 -302.99025)
		(end 242.9764 -302.006)
		(width 0.254)
		(layer "F.Cu")
		(net "FANTACH_A_F0")
	)
	(segment
		(start 242.9764 -302.006)
		(end 237.7186 -302.006)
		(width 0.254)
		(layer "F.Cu")
		(net "FANTACH_A_F0")
	)
	(segment
		(start 243.8781 -304.673)
		(end 243.8781 -303.990502)
		(width 0.2032)
		(layer "F.Cu")
		(net "FANTACH_A_F0")
	)
	(segment
		(start 234.60964 -304.42916)
		(end 235.4072 -303.6316)
		(width 0.254)
		(layer "F.Cu")
		(net "FANTACH_A_F0")
	)
	(segment
		(start 237.7186 -302.006)
		(end 237.2868 -302.4378)
		(width 0.254)
		(layer "F.Cu")
		(net "FANTACH_A_F0")
	)
	(segment
		(start 243.96065 -303.907952)
		(end 243.96065 -302.99025)
		(width 0.2032)
		(layer "F.Cu")
		(net "FANTACH_A_F0")
	)
	(segment
		(start 236.093 -303.6316)
		(end 237.2868 -302.4378)
		(width 0.254)
		(layer "F.Cu")
		(net "FANTACH_A_F0")
	)
	(segment
		(start 233.8324 -304.42916)
		(end 234.60964 -304.42916)
		(width 0.254)
		(layer "F.Cu")
		(net "FANTACH_A_F0")
	)
	(segment
		(start 243.8781 -303.990502)
		(end 243.96065 -303.907952)
		(width 0.2032)
		(layer "F.Cu")
		(net "FANTACH_A_F0")
	)
	(via
		(at 237.2868 -302.4378)
		(size 0.6604)
		(drill 0.3302)
		(layers "F.Cu" "B.Cu")
		(net "FANTACH_A_F0")
	)
	(segment
		(start 244.9957 -303.149)
		(end 244.9957 -302.3108)
		(width 0.508)
		(layer "F.Cu")
		(net "P3V3_STBY_A")
	)
	(segment
		(start 244.6274 -304.673)
		(end 244.983 -304.3174)
		(width 0.2032)
		(layer "F.Cu")
		(net "P3V3_STBY_A")
	)
	(segment
		(start 244.277896 -304.673)
		(end 244.6274 -304.673)
		(width 0.2032)
		(layer "F.Cu")
		(net "P3V3_STBY_A")
	)
	(segment
		(start 248.7295 -310.134)
		(end 249.555 -310.134)
		(width 0.508)
		(layer "F.Cu")
		(net "P3V3_STBY_A")
	)
	(segment
		(start 240.665 -312.3565)
		(end 240.665 -313.182)
		(width 0.508)
		(layer "F.Cu")
		(net "P3V3_STBY_A")
	)
	(segment
		(start 242.697 -312.3565)
		(end 242.697 -313.182)
		(width 0.508)
		(layer "F.Cu")
		(net "P3V3_STBY_A")
	)
	(segment
		(start 244.983 -304.3174)
		(end 244.983 -303.1617)
		(width 0.2032)
		(layer "F.Cu")
		(net "P3V3_STBY_A")
	)
	(segment
		(start 211.4042 -298.1198)
		(end 214.2109 -300.9265)
		(width 0.508)
		(layer "F.Cu")
		(net "P3V3_STBY_A")
	)
	(segment
		(start 248.7295 -311.15)
		(end 249.555 -311.15)
		(width 0.508)
		(layer "F.Cu")
		(net "P3V3_STBY_A")
	)
	(segment
		(start 44.4627 -7.4168)
		(end 44.6151 -7.2644)
		(width 0.508)
		(layer "F.Cu")
		(net "P3V3_STBY_A")
	)
	(segment
		(start 224.411286 -298.750482)
		(end 228.579426 -298.750482)
		(width 0.508)
		(layer "F.Cu")
		(net "P3V3_STBY_A")
	)
	(segment
		(start 208.7626 -298.1198)
		(end 211.4042 -298.1198)
		(width 0.508)
		(layer "F.Cu")
		(net "P3V3_STBY_A")
	)
	(segment
		(start 44.6151 -6.3754)
		(end 44.6151 -7.2644)
		(width 0.508)
		(layer "F.Cu")
		(net "P3V3_STBY_A")
	)
	(segment
		(start 44.6151 -5.3086)
		(end 44.6151 -6.3754)
		(width 0.508)
		(layer "F.Cu")
		(net "P3V3_STBY_A")
	)
	(segment
		(start 244.983 -303.1617)
		(end 244.9957 -303.149)
		(width 0.2032)
		(layer "F.Cu")
		(net "P3V3_STBY_A")
	)
	(segment
		(start 222.235268 -300.9265)
		(end 224.411286 -298.750482)
		(width 0.508)
		(layer "F.Cu")
		(net "P3V3_STBY_A")
	)
	(segment
		(start 241.435382 -298.750482)
		(end 228.579426 -298.750482)
		(width 0.508)
		(layer "F.Cu")
		(net "P3V3_STBY_A")
	)
	(segment
		(start 244.9957 -302.3108)
		(end 241.435382 -298.750482)
		(width 0.508)
		(layer "F.Cu")
		(net "P3V3_STBY_A")
	)
	(segment
		(start 248.7295 -308.102)
		(end 249.555 -308.102)
		(width 0.508)
		(layer "F.Cu")
		(net "P3V3_STBY_A")
	)
	(segment
		(start 220.7006 -300.9265)
		(end 222.235268 -300.9265)
		(width 0.508)
		(layer "F.Cu")
		(net "P3V3_STBY_A")
	)
	(segment
		(start 248.7295 -306.07)
		(end 249.555 -306.07)
		(width 0.508)
		(layer "F.Cu")
		(net "P3V3_STBY_A")
	)
	(segment
		(start 43.6499 -7.4168)
		(end 44.4627 -7.4168)
		(width 0.508)
		(layer "F.Cu")
		(net "P3V3_STBY_A")
	)
	(segment
		(start 214.2109 -300.9265)
		(end 220.7006 -300.9265)
		(width 0.508)
		(layer "F.Cu")
		(net "P3V3_STBY_A")
	)
	(via
		(at 244.9957 -302.3108)
		(size 0.5588)
		(drill 0.3048)
		(layers "F.Cu" "B.Cu")
		(net "P3V3_STBY_A")
	)
	(via
		(at 242.697 -313.182)
		(size 0.5588)
		(drill 0.3048)
		(layers "F.Cu" "B.Cu")
		(net "P3V3_STBY_A")
	)
	(via
		(at 205.33233 -115.39601)
		(size 0.5588)
		(drill 0.3048)
		(layers "F.Cu" "B.Cu")
		(net "P3V3_STBY_A")
	)
	(via
		(at 221.0816 -115.39601)
		(size 0.5588)
		(drill 0.3048)
		(layers "F.Cu" "B.Cu")
		(net "P3V3_STBY_A")
	)
	(via
		(at 44.6151 -7.2644)
		(size 0.5588)
		(drill 0.3048)
		(layers "F.Cu" "B.Cu")
		(net "P3V3_STBY_A")
	)
	(via
		(at 249.555 -311.15)
		(size 0.5588)
		(drill 0.3048)
		(layers "F.Cu" "B.Cu")
		(net "P3V3_STBY_A")
	)
	(via
		(at 249.555 -306.07)
		(size 0.5588)
		(drill 0.3048)
		(layers "F.Cu" "B.Cu")
		(net "P3V3_STBY_A")
	)
	(via
		(at 249.555 -310.134)
		(size 0.5588)
		(drill 0.3048)
		(layers "F.Cu" "B.Cu")
		(net "P3V3_STBY_A")
	)
	(via
		(at 228.579426 -298.750482)
		(size 0.6604)
		(drill 0.3302)
		(layers "F.Cu" "B.Cu")
		(net "P3V3_STBY_A")
	)
	(via
		(at 179.113434 -4.128516)
		(size 0.5588)
		(drill 0.3048)
		(layers "F.Cu" "B.Cu")
		(net "P3V3_STBY_A")
	)
	(via
		(at 249.555 -308.102)
		(size 0.5588)
		(drill 0.3048)
		(layers "F.Cu" "B.Cu")
		(net "P3V3_STBY_A")
	)
	(via
		(at 37.049456 -8.436864)
		(size 0.5588)
		(drill 0.3048)
		(layers "F.Cu" "B.Cu")
		(net "P3V3_STBY_A")
	)
	(via
		(at 208.7626 -298.1198)
		(size 0.5588)
		(drill 0.3048)
		(layers "F.Cu" "B.Cu")
		(net "P3V3_STBY_A")
	)
	(via
		(at 240.665 -313.182)
		(size 0.5588)
		(drill 0.3048)
		(layers "F.Cu" "B.Cu")
		(net "P3V3_STBY_A")
	)
	(segment
		(start 205.33233 -113.915444)
		(end 201.566272 -110.149386)
		(width 0.508)
		(layer "In2.Cu")
		(net "P3V3_STBY_A")
	)
	(segment
		(start 192.076832 -65.121282)
		(end 192.076832 -30.007052)
		(width 0.508)
		(layer "In2.Cu")
		(net "P3V3_STBY_A")
	)
	(segment
		(start 216.328752 -230.939848)
		(end 219.8116 -227.457)
		(width 0.508)
		(layer "In2.Cu")
		(net "P3V3_STBY_A")
	)
	(segment
		(start 192.077848 -65.308988)
		(end 192.077848 -65.122298)
		(width 0.508)
		(layer "In2.Cu")
		(net "P3V3_STBY_A")
	)
	(segment
		(start 219.8116 -227.457)
		(end 219.8116 -224.638616)
		(width 0.508)
		(layer "In2.Cu")
		(net "P3V3_STBY_A")
	)
	(segment
		(start 219.5068 -151.3332)
		(end 219.5068 -125.11532)
		(width 0.508)
		(layer "In2.Cu")
		(net "P3V3_STBY_A")
	)
	(segment
		(start 216.328752 -290.553648)
		(end 216.328752 -230.939848)
		(width 0.508)
		(layer "In2.Cu")
		(net "P3V3_STBY_A")
	)
	(segment
		(start 221.865952 -222.584264)
		(end 221.865952 -217.681048)
		(width 0.508)
		(layer "In2.Cu")
		(net "P3V3_STBY_A")
	)
	(segment
		(start 232.058972 -102.373176)
		(end 221.107254 -113.324894)
		(width 0.508)
		(layer "In2.Cu")
		(net "P3V3_STBY_A")
	)
	(segment
		(start 192.076832 -30.007052)
		(end 183.94426 -21.87448)
		(width 0.508)
		(layer "In2.Cu")
		(net "P3V3_STBY_A")
	)
	(segment
		(start 231.644698 -76.399898)
		(end 232.664 -77.4192)
		(width 0.508)
		(layer "In2.Cu")
		(net "P3V3_STBY_A")
	)
	(segment
		(start 232.664 -77.4192)
		(end 232.664 -86.31047)
		(width 0.508)
		(layer "In2.Cu")
		(net "P3V3_STBY_A")
	)
	(segment
		(start 219.8116 -224.638616)
		(end 221.865952 -222.584264)
		(width 0.508)
		(layer "In2.Cu")
		(net "P3V3_STBY_A")
	)
	(segment
		(start 221.0816 -152.908)
		(end 219.5068 -151.3332)
		(width 0.508)
		(layer "In2.Cu")
		(net "P3V3_STBY_A")
	)
	(segment
		(start 223.266508 -213.354412)
		(end 223.266508 -207.518508)
		(width 0.508)
		(layer "In2.Cu")
		(net "P3V3_STBY_A")
	)
	(segment
		(start 219.5068 -125.11532)
		(end 220.1164 -124.50572)
		(width 0.508)
		(layer "In2.Cu")
		(net "P3V3_STBY_A")
	)
	(segment
		(start 201.566272 -74.797412)
		(end 192.077848 -65.308988)
		(width 0.508)
		(layer "In2.Cu")
		(net "P3V3_STBY_A")
	)
	(segment
		(start 179.113434 -8.73125)
		(end 179.113434 -4.128516)
		(width 0.508)
		(layer "In2.Cu")
		(net "P3V3_STBY_A")
	)
	(segment
		(start 220.1164 -120.3198)
		(end 221.0816 -119.3546)
		(width 0.508)
		(layer "In2.Cu")
		(net "P3V3_STBY_A")
	)
	(segment
		(start 220.726 -155.257246)
		(end 221.0816 -154.901646)
		(width 0.508)
		(layer "In2.Cu")
		(net "P3V3_STBY_A")
	)
	(segment
		(start 222.922846 -207.174846)
		(end 222.922846 -203.543154)
		(width 0.508)
		(layer "In2.Cu")
		(net "P3V3_STBY_A")
	)
	(segment
		(start 223.266508 -207.518508)
		(end 222.922846 -207.174846)
		(width 0.508)
		(layer "In2.Cu")
		(net "P3V3_STBY_A")
	)
	(segment
		(start 205.33233 -115.39601)
		(end 205.33233 -113.915444)
		(width 0.508)
		(layer "In2.Cu")
		(net "P3V3_STBY_A")
	)
	(segment
		(start 208.7626 -298.1198)
		(end 216.328752 -290.553648)
		(width 0.508)
		(layer "In2.Cu")
		(net "P3V3_STBY_A")
	)
	(segment
		(start 221.107254 -113.324894)
		(end 221.107254 -115.370356)
		(width 0.508)
		(layer "In2.Cu")
		(net "P3V3_STBY_A")
	)
	(segment
		(start 220.1164 -124.50572)
		(end 220.1164 -120.3198)
		(width 0.508)
		(layer "In2.Cu")
		(net "P3V3_STBY_A")
	)
	(segment
		(start 221.0816 -119.3546)
		(end 221.0816 -115.39601)
		(width 0.508)
		(layer "In2.Cu")
		(net "P3V3_STBY_A")
	)
	(segment
		(start 221.107254 -115.370356)
		(end 221.0816 -115.39601)
		(width 0.508)
		(layer "In2.Cu")
		(net "P3V3_STBY_A")
	)
	(segment
		(start 232.664 -86.31047)
		(end 232.058972 -86.915498)
		(width 0.508)
		(layer "In2.Cu")
		(net "P3V3_STBY_A")
	)
	(segment
		(start 221.0816 -154.901646)
		(end 221.0816 -152.908)
		(width 0.508)
		(layer "In2.Cu")
		(net "P3V3_STBY_A")
	)
	(segment
		(start 183.94426 -13.562076)
		(end 179.113434 -8.73125)
		(width 0.508)
		(layer "In2.Cu")
		(net "P3V3_STBY_A")
	)
	(segment
		(start 223.52 -213.607904)
		(end 223.266508 -213.354412)
		(width 0.508)
		(layer "In2.Cu")
		(net "P3V3_STBY_A")
	)
	(segment
		(start 232.058972 -86.915498)
		(end 232.058972 -102.373176)
		(width 0.508)
		(layer "In2.Cu")
		(net "P3V3_STBY_A")
	)
	(segment
		(start 220.726 -158.0388)
		(end 220.726 -155.257246)
		(width 0.508)
		(layer "In2.Cu")
		(net "P3V3_STBY_A")
	)
	(segment
		(start 231.599994 -76.399898)
		(end 231.644698 -76.399898)
		(width 0.508)
		(layer "In2.Cu")
		(net "P3V3_STBY_A")
	)
	(segment
		(start 183.94426 -21.87448)
		(end 183.94426 -13.562076)
		(width 0.508)
		(layer "In2.Cu")
		(net "P3V3_STBY_A")
	)
	(segment
		(start 201.566272 -110.149386)
		(end 201.566272 -74.797412)
		(width 0.508)
		(layer "In2.Cu")
		(net "P3V3_STBY_A")
	)
	(segment
		(start 223.266 -203.2)
		(end 223.266 -190.881)
		(width 0.508)
		(layer "In2.Cu")
		(net "P3V3_STBY_A")
	)
	(segment
		(start 222.508572 -159.821372)
		(end 220.726 -158.0388)
		(width 0.508)
		(layer "In2.Cu")
		(net "P3V3_STBY_A")
	)
	(segment
		(start 223.266 -190.881)
		(end 222.508572 -190.123572)
		(width 0.508)
		(layer "In2.Cu")
		(net "P3V3_STBY_A")
	)
	(segment
		(start 221.865952 -217.681048)
		(end 223.52 -216.027)
		(width 0.508)
		(layer "In2.Cu")
		(net "P3V3_STBY_A")
	)
	(segment
		(start 222.922846 -203.543154)
		(end 223.266 -203.2)
		(width 0.508)
		(layer "In2.Cu")
		(net "P3V3_STBY_A")
	)
	(segment
		(start 223.52 -216.027)
		(end 223.52 -213.607904)
		(width 0.508)
		(layer "In2.Cu")
		(net "P3V3_STBY_A")
	)
	(segment
		(start 192.077848 -65.122298)
		(end 192.076832 -65.121282)
		(width 0.508)
		(layer "In2.Cu")
		(net "P3V3_STBY_A")
	)
	(segment
		(start 222.508572 -190.123572)
		(end 222.508572 -159.821372)
		(width 0.508)
		(layer "In2.Cu")
		(net "P3V3_STBY_A")
	)
	(segment
		(start 37.049456 -8.436864)
		(end 38.22192 -7.2644)
		(width 0.508)
		(layer "In5.Cu")
		(net "P3V3_STBY_A")
	)
	(segment
		(start 51.147472 -4.14274)
		(end 48.025812 -7.2644)
		(width 0.508)
		(layer "In5.Cu")
		(net "P3V3_STBY_A")
	)
	(segment
		(start 48.025812 -7.2644)
		(end 44.6151 -7.2644)
		(width 0.508)
		(layer "In5.Cu")
		(net "P3V3_STBY_A")
	)
	(segment
		(start 179.113434 -4.128516)
		(end 179.09921 -4.14274)
		(width 0.508)
		(layer "In5.Cu")
		(net "P3V3_STBY_A")
	)
	(segment
		(start 179.09921 -4.14274)
		(end 51.147472 -4.14274)
		(width 0.508)
		(layer "In5.Cu")
		(net "P3V3_STBY_A")
	)
	(segment
		(start 214.782908 -114.36985)
		(end 213.756748 -115.39601)
		(width 0.508)
		(layer "In5.Cu")
		(net "P3V3_STBY_A")
	)
	(segment
		(start 213.756748 -115.39601)
		(end 205.33233 -115.39601)
		(width 0.508)
		(layer "In5.Cu")
		(net "P3V3_STBY_A")
	)
	(segment
		(start 221.0816 -115.39601)
		(end 220.05544 -114.36985)
		(width 0.508)
		(layer "In5.Cu")
		(net "P3V3_STBY_A")
	)
	(segment
		(start 38.22192 -7.2644)
		(end 44.6151 -7.2644)
		(width 0.508)
		(layer "In5.Cu")
		(net "P3V3_STBY_A")
	)
	(segment
		(start 220.05544 -114.36985)
		(end 214.782908 -114.36985)
		(width 0.508)
		(layer "In5.Cu")
		(net "P3V3_STBY_A")
	)
	(segment
		(start 280.60904 -341.32901)
		(end 280.60904 -342.07196)
		(width 0.254)
		(layer "F.Cu")
		(net "P3V3_IN_EN")
	)
	(segment
		(start 281.6225 -345.821)
		(end 280.048462 -345.821)
		(width 0.254)
		(layer "F.Cu")
		(net "P3V3_IN_EN")
	)
	(segment
		(start 282.3845 -345.059)
		(end 281.6225 -345.821)
		(width 0.254)
		(layer "F.Cu")
		(net "P3V3_IN_EN")
	)
	(segment
		(start 280.048462 -345.821)
		(end 279.4762 -345.248738)
		(width 0.254)
		(layer "F.Cu")
		(net "P3V3_IN_EN")
	)
	(segment
		(start 279.4762 -343.2048)
		(end 279.4762 -345.248738)
		(width 0.254)
		(layer "F.Cu")
		(net "P3V3_IN_EN")
	)
	(segment
		(start 280.60904 -342.07196)
		(end 279.4762 -343.2048)
		(width 0.254)
		(layer "F.Cu")
		(net "P3V3_IN_EN")
	)
	(via
		(at 279.4762 -345.248738)
		(size 0.6604)
		(drill 0.3302)
		(layers "F.Cu" "B.Cu")
		(net "P3V3_IN_EN")
	)
	(segment
		(start 226.575112 -301.099728)
		(end 227.173282 -300.501558)
		(width 1.016)
		(layer "F.Cu")
		(net "P3V3_IN")
	)
	(segment
		(start 38.59403 -362.14304)
		(end 39.392098 -362.14304)
		(width 0.254)
		(layer "F.Cu")
		(net "P3V3_IN")
	)
	(segment
		(start 266.192 -227.0125)
		(end 265.3792 -227.0125)
		(width 0.508)
		(layer "F.Cu")
		(net "P3V3_IN")
	)
	(segment
		(start 419.7985 -373.665496)
		(end 422.053004 -375.92)
		(width 0.508)
		(layer "F.Cu")
		(net "P3V3_IN")
	)
	(segment
		(start 129.252218 -379.696218)
		(end 126.639066 -377.083066)
		(width 1.016)
		(layer "F.Cu")
		(net "P3V3_IN")
	)
	(segment
		(start 240.102898 -300.501558)
		(end 240.7158 -301.11446)
		(width 1.016)
		(layer "F.Cu")
		(net "P3V3_IN")
	)
	(segment
		(start 287.0835 -329.3618)
		(end 287.90392 -329.3618)
		(width 0.508)
		(layer "F.Cu")
		(net "P3V3_IN")
	)
	(segment
		(start 268.097 -227.0125)
		(end 268.9352 -227.0125)
		(width 0.508)
		(layer "F.Cu")
		(net "P3V3_IN")
	)
	(segment
		(start 42.068496 -361.4039)
		(end 42.106596 -361.3658)
		(width 0.508)
		(layer "F.Cu")
		(net "P3V3_IN")
	)
	(segment
		(start 273.1389 -330.04125)
		(end 272.31848 -330.04125)
		(width 0.508)
		(layer "F.Cu")
		(net "P3V3_IN")
	)
	(segment
		(start 419.7985 -372.11)
		(end 419.7985 -373.665496)
		(width 0.508)
		(layer "F.Cu")
		(net "P3V3_IN")
	)
	(segment
		(start 38.184074 -377.083066)
		(end 37.465508 -376.3645)
		(width 1.016)
		(layer "F.Cu")
		(net "P3V3_IN")
	)
	(segment
		(start 273.1389 -332.61173)
		(end 272.31848 -332.61173)
		(width 0.508)
		(layer "F.Cu")
		(net "P3V3_IN")
	)
	(segment
		(start 263.5377 -375.999756)
		(end 263.5377 -374.856756)
		(width 0.508)
		(layer "F.Cu")
		(net "P3V3_IN")
	)
	(segment
		(start 28.781756 -370.5733)
		(end 28.705556 -370.4971)
		(width 0.4064)
		(layer "F.Cu")
		(net "P3V3_IN")
	)
	(segment
		(start 159.639 -371.1575)
		(end 158.6865 -371.1575)
		(width 0.508)
		(layer "F.Cu")
		(net "P3V3_IN")
	)
	(segment
		(start 455.492104 -372.3259)
		(end 454.717404 -372.3259)
		(width 0.4064)
		(layer "F.Cu")
		(net "P3V3_IN")
	)
	(segment
		(start 264.328402 -372.844314)
		(end 264.328402 -374.066054)
		(width 0.508)
		(layer "F.Cu")
		(net "P3V3_IN")
	)
	(segment
		(start 227.173282 -300.501558)
		(end 240.102898 -300.501558)
		(width 1.016)
		(layer "F.Cu")
		(net "P3V3_IN")
	)
	(segment
		(start 36.168584 -376.3645)
		(end 35.400996 -376.3645)
		(width 0.508)
		(layer "F.Cu")
		(net "P3V3_IN")
	)
	(segment
		(start 319.941956 -372.20144)
		(end 319.614296 -372.5291)
		(width 0.4064)
		(layer "F.Cu")
		(net "P3V3_IN")
	)
	(segment
		(start 269.42034 -237.094014)
		(end 269.42034 -227.49764)
		(width 1.016)
		(layer "F.Cu")
		(net "P3V3_IN")
	)
	(segment
		(start 26.828496 -370.4971)
		(end 27.298396 -370.4971)
		(width 0.508)
		(layer "F.Cu")
		(net "P3V3_IN")
	)
	(segment
		(start 276.342348 -243.650008)
		(end 275.976334 -243.650008)
		(width 1.016)
		(layer "F.Cu")
		(net "P3V3_IN")
	)
	(segment
		(start 318.356996 -372.5291)
		(end 318.356996 -373.38)
		(width 0.508)
		(layer "F.Cu")
		(net "P3V3_IN")
	)
	(segment
		(start 269.42034 -227.49764)
		(end 268.9352 -227.0125)
		(width 0.508)
		(layer "F.Cu")
		(net "P3V3_IN")
	)
	(segment
		(start 28.705556 -370.4971)
		(end 27.298396 -370.4971)
		(width 0.4064)
		(layer "F.Cu")
		(net "P3V3_IN")
	)
	(segment
		(start 326.294496 -375.92)
		(end 326.294496 -375.0056)
		(width 0.508)
		(layer "F.Cu")
		(net "P3V3_IN")
	)
	(segment
		(start 186.748928 -368.60734)
		(end 186.748928 -367.559336)
		(width 0.508)
		(layer "F.Cu")
		(net "P3V3_IN")
	)
	(segment
		(start 129.259584 -380.4412)
		(end 129.252218 -380.433834)
		(width 0.508)
		(layer "F.Cu")
		(net "P3V3_IN")
	)
	(segment
		(start 264.328402 -374.066054)
		(end 263.5377 -374.856756)
		(width 0.508)
		(layer "F.Cu")
		(net "P3V3_IN")
	)
	(segment
		(start 26.462736 -370.13134)
		(end 26.828496 -370.4971)
		(width 0.508)
		(layer "F.Cu")
		(net "P3V3_IN")
	)
	(segment
		(start 454.717404 -372.3259)
		(end 454.717404 -373.2022)
		(width 0.508)
		(layer "F.Cu")
		(net "P3V3_IN")
	)
	(segment
		(start 273.1389 -331.34173)
		(end 272.31848 -331.34173)
		(width 0.508)
		(layer "F.Cu")
		(net "P3V3_IN")
	)
	(segment
		(start 40.252396 -361.4039)
		(end 41.217596 -361.4039)
		(width 0.508)
		(layer "F.Cu")
		(net "P3V3_IN")
	)
	(segment
		(start 275.976334 -243.650008)
		(end 269.42034 -237.094014)
		(width 1.016)
		(layer "F.Cu")
		(net "P3V3_IN")
	)
	(segment
		(start 35.400996 -376.3645)
		(end 35.400996 -377.4694)
		(width 0.508)
		(layer "F.Cu")
		(net "P3V3_IN")
	)
	(segment
		(start 240.7158 -301.11446)
		(end 240.7158 -301.117)
		(width 1.016)
		(layer "F.Cu")
		(net "P3V3_IN")
	)
	(segment
		(start 319.614296 -372.5291)
		(end 318.356996 -372.5291)
		(width 0.4064)
		(layer "F.Cu")
		(net "P3V3_IN")
	)
	(segment
		(start 126.639066 -377.083066)
		(end 38.184074 -377.083066)
		(width 1.016)
		(layer "F.Cu")
		(net "P3V3_IN")
	)
	(segment
		(start 311.6834 -341.257382)
		(end 311.6834 -342.077802)
		(width 0.508)
		(layer "F.Cu")
		(net "P3V3_IN")
	)
	(segment
		(start 273.1389 -328.28484)
		(end 272.31848 -328.28484)
		(width 0.508)
		(layer "F.Cu")
		(net "P3V3_IN")
	)
	(segment
		(start 259.207 -380.190756)
		(end 259.207 -381.003556)
		(width 0.508)
		(layer "F.Cu")
		(net "P3V3_IN")
	)
	(segment
		(start 226.575112 -302.11776)
		(end 226.575112 -301.099728)
		(width 1.016)
		(layer "F.Cu")
		(net "P3V3_IN")
	)
	(segment
		(start 37.465508 -376.3645)
		(end 36.168584 -376.3645)
		(width 1.016)
		(layer "F.Cu")
		(net "P3V3_IN")
	)
	(segment
		(start 40.131238 -361.4039)
		(end 40.252396 -361.4039)
		(width 0.508)
		(layer "F.Cu")
		(net "P3V3_IN")
	)
	(segment
		(start 41.217596 -361.4039)
		(end 42.068496 -361.4039)
		(width 0.508)
		(layer "F.Cu")
		(net "P3V3_IN")
	)
	(segment
		(start 188.359288 -367.231676)
		(end 188.031628 -367.559336)
		(width 0.4064)
		(layer "F.Cu")
		(net "P3V3_IN")
	)
	(segment
		(start 306.932076 -341.257382)
		(end 306.932076 -342.077802)
		(width 0.508)
		(layer "F.Cu")
		(net "P3V3_IN")
	)
	(segment
		(start 303.249076 -341.257382)
		(end 303.249076 -342.077802)
		(width 0.508)
		(layer "F.Cu")
		(net "P3V3_IN")
	)
	(segment
		(start 129.252218 -380.433834)
		(end 129.252218 -379.696218)
		(width 1.016)
		(layer "F.Cu")
		(net "P3V3_IN")
	)
	(segment
		(start 39.392098 -362.14304)
		(end 39.740586 -361.794552)
		(width 0.254)
		(layer "F.Cu")
		(net "P3V3_IN")
	)
	(segment
		(start 456.101704 -371.7163)
		(end 455.492104 -372.3259)
		(width 0.4064)
		(layer "F.Cu")
		(net "P3V3_IN")
	)
	(segment
		(start 315.3664 -341.257382)
		(end 315.3664 -342.077802)
		(width 0.508)
		(layer "F.Cu")
		(net "P3V3_IN")
	)
	(segment
		(start 456.353164 -371.7163)
		(end 456.101704 -371.7163)
		(width 0.4064)
		(layer "F.Cu")
		(net "P3V3_IN")
	)
	(segment
		(start 39.740586 -361.794552)
		(end 40.131238 -361.4039)
		(width 0.508)
		(layer "F.Cu")
		(net "P3V3_IN")
	)
	(segment
		(start 319.941956 -371.8687)
		(end 319.941956 -372.20144)
		(width 0.4064)
		(layer "F.Cu")
		(net "P3V3_IN")
	)
	(segment
		(start 287.0835 -328.0918)
		(end 287.90392 -328.0918)
		(width 0.508)
		(layer "F.Cu")
		(net "P3V3_IN")
	)
	(segment
		(start 188.031628 -367.559336)
		(end 186.748928 -367.559336)
		(width 0.4064)
		(layer "F.Cu")
		(net "P3V3_IN")
	)
	(segment
		(start 26.462736 -370.1288)
		(end 26.462736 -370.13134)
		(width 0.508)
		(layer "F.Cu")
		(net "P3V3_IN")
	)
	(segment
		(start 188.359288 -366.949736)
		(end 188.359288 -367.231676)
		(width 0.4064)
		(layer "F.Cu")
		(net "P3V3_IN")
	)
	(via
		(at 287.90392 -328.0918)
		(size 0.5588)
		(drill 0.3048)
		(layers "F.Cu" "B.Cu")
		(net "P3V3_IN")
	)
	(via
		(at 268.9352 -227.0125)
		(size 0.5588)
		(drill 0.3048)
		(layers "F.Cu" "B.Cu")
		(net "P3V3_IN")
	)
	(via
		(at 283.718 -337.439)
		(size 0.5588)
		(drill 0.3048)
		(layers "F.Cu" "B.Cu")
		(net "P3V3_IN")
	)
	(via
		(at 316.911228 -361.088432)
		(size 0.6096)
		(drill 0.3048)
		(layers "F.Cu" "B.Cu")
		(net "P3V3_IN")
	)
	(via
		(at 26.462736 -370.1288)
		(size 0.5588)
		(drill 0.3048)
		(layers "F.Cu" "B.Cu")
		(net "P3V3_IN")
	)
	(via
		(at 284.821884 -332.07579)
		(size 0.5588)
		(drill 0.3048)
		(layers "F.Cu" "B.Cu")
		(net "P3V3_IN")
	)
	(via
		(at 300.709076 -332.430882)
		(size 0.5588)
		(drill 0.3048)
		(layers "F.Cu" "B.Cu")
		(net "P3V3_IN")
	)
	(via
		(at 158.6865 -371.1575)
		(size 0.5588)
		(drill 0.3048)
		(layers "F.Cu" "B.Cu")
		(net "P3V3_IN")
	)
	(via
		(at 422.053004 -375.92)
		(size 0.5588)
		(drill 0.3048)
		(layers "F.Cu" "B.Cu")
		(net "P3V3_IN")
	)
	(via
		(at 284.821884 -333.09179)
		(size 0.5588)
		(drill 0.3048)
		(layers "F.Cu" "B.Cu")
		(net "P3V3_IN")
	)
	(via
		(at 287.90392 -329.3618)
		(size 0.5588)
		(drill 0.3048)
		(layers "F.Cu" "B.Cu")
		(net "P3V3_IN")
	)
	(via
		(at 283.718 -338.455)
		(size 0.5588)
		(drill 0.3048)
		(layers "F.Cu" "B.Cu")
		(net "P3V3_IN")
	)
	(via
		(at 240.7158 -301.117)
		(size 0.5588)
		(drill 0.3048)
		(layers "F.Cu" "B.Cu")
		(net "P3V3_IN")
	)
	(via
		(at 283.21 -377.19)
		(size 0.7112)
		(drill 0.4064)
		(layers "F.Cu" "B.Cu")
		(net "P3V3_IN")
	)
	(via
		(at 306.932076 -342.077802)
		(size 0.5588)
		(drill 0.3048)
		(layers "F.Cu" "B.Cu")
		(net "P3V3_IN")
	)
	(via
		(at 283.972 -376.047)
		(size 0.7112)
		(drill 0.4064)
		(layers "F.Cu" "B.Cu")
		(net "P3V3_IN")
	)
	(via
		(at 326.294496 -375.0056)
		(size 0.5588)
		(drill 0.3048)
		(layers "F.Cu" "B.Cu")
		(net "P3V3_IN")
	)
	(via
		(at 259.207 -381.003556)
		(size 0.5588)
		(drill 0.3048)
		(layers "F.Cu" "B.Cu")
		(net "P3V3_IN")
	)
	(via
		(at 311.6834 -342.077802)
		(size 0.5588)
		(drill 0.3048)
		(layers "F.Cu" "B.Cu")
		(net "P3V3_IN")
	)
	(via
		(at 272.31848 -331.34173)
		(size 0.5588)
		(drill 0.3048)
		(layers "F.Cu" "B.Cu")
		(net "P3V3_IN")
	)
	(via
		(at 309.091076 -332.303882)
		(size 0.5588)
		(drill 0.3048)
		(layers "F.Cu" "B.Cu")
		(net "P3V3_IN")
	)
	(via
		(at 309.091076 -331.287882)
		(size 0.5588)
		(drill 0.3048)
		(layers "F.Cu" "B.Cu")
		(net "P3V3_IN")
	)
	(via
		(at 276.342348 -243.650008)
		(size 0.5588)
		(drill 0.3048)
		(layers "F.Cu" "B.Cu")
		(net "P3V3_IN")
	)
	(via
		(at 454.717404 -373.2022)
		(size 0.5588)
		(drill 0.3048)
		(layers "F.Cu" "B.Cu")
		(net "P3V3_IN")
	)
	(via
		(at 263.5377 -374.856756)
		(size 0.5588)
		(drill 0.3048)
		(layers "F.Cu" "B.Cu")
		(net "P3V3_IN")
	)
	(via
		(at 305.641248 -356.309422)
		(size 0.5588)
		(drill 0.3048)
		(layers "F.Cu" "B.Cu")
		(net "P3V3_IN")
	)
	(via
		(at 186.748928 -368.60734)
		(size 0.5588)
		(drill 0.3048)
		(layers "F.Cu" "B.Cu")
		(net "P3V3_IN")
	)
	(via
		(at 42.106596 -361.3658)
		(size 0.5588)
		(drill 0.3048)
		(layers "F.Cu" "B.Cu")
		(net "P3V3_IN")
	)
	(via
		(at 35.400996 -377.4694)
		(size 0.5588)
		(drill 0.3048)
		(layers "F.Cu" "B.Cu")
		(net "P3V3_IN")
	)
	(via
		(at 272.31848 -328.28484)
		(size 0.5588)
		(drill 0.3048)
		(layers "F.Cu" "B.Cu")
		(net "P3V3_IN")
	)
	(via
		(at 272.31848 -332.61173)
		(size 0.5588)
		(drill 0.3048)
		(layers "F.Cu" "B.Cu")
		(net "P3V3_IN")
	)
	(via
		(at 265.3792 -227.0125)
		(size 0.5588)
		(drill 0.3048)
		(layers "F.Cu" "B.Cu")
		(net "P3V3_IN")
	)
	(via
		(at 300.709076 -331.414882)
		(size 0.5588)
		(drill 0.3048)
		(layers "F.Cu" "B.Cu")
		(net "P3V3_IN")
	)
	(via
		(at 129.252218 -380.433834)
		(size 0.5588)
		(drill 0.3048)
		(layers "F.Cu" "B.Cu")
		(net "P3V3_IN")
	)
	(via
		(at 315.3664 -342.077802)
		(size 0.5588)
		(drill 0.3048)
		(layers "F.Cu" "B.Cu")
		(net "P3V3_IN")
	)
	(via
		(at 318.356996 -373.38)
		(size 0.5588)
		(drill 0.3048)
		(layers "F.Cu" "B.Cu")
		(net "P3V3_IN")
	)
	(via
		(at 282.134818 -332.514448)
		(size 0.6096)
		(drill 0.3048)
		(layers "F.Cu" "B.Cu")
		(net "P3V3_IN")
	)
	(via
		(at 272.31848 -330.04125)
		(size 0.5588)
		(drill 0.3048)
		(layers "F.Cu" "B.Cu")
		(net "P3V3_IN")
	)
	(via
		(at 282.448 -376.047)
		(size 0.7112)
		(drill 0.4064)
		(layers "F.Cu" "B.Cu")
		(net "P3V3_IN")
	)
	(via
		(at 303.249076 -342.077802)
		(size 0.5588)
		(drill 0.3048)
		(layers "F.Cu" "B.Cu")
		(net "P3V3_IN")
	)
	(segment
		(start 422.637204 -375.92)
		(end 423.526204 -375.031)
		(width 1.016)
		(layer "B.Cu")
		(net "P3V3_IN")
	)
	(segment
		(start 186.748928 -368.60734)
		(end 187.752482 -367.603786)
		(width 1.016)
		(layer "B.Cu")
		(net "P3V3_IN")
	)
	(segment
		(start 281.001216 -358.309418)
		(end 296.964608 -358.309418)
		(width 1.016)
		(layer "B.Cu")
		(net "P3V3_IN")
	)
	(segment
		(start 305.641248 -356.309422)
		(end 310.132222 -356.309422)
		(width 1.016)
		(layer "B.Cu")
		(net "P3V3_IN")
	)
	(segment
		(start 192.321688 -367.603786)
		(end 198.428102 -373.7102)
		(width 1.016)
		(layer "B.Cu")
		(net "P3V3_IN")
	)
	(segment
		(start 158.6865 -371.1575)
		(end 158.6865 -373.916702)
		(width 0.508)
		(layer "B.Cu")
		(net "P3V3_IN")
	)
	(segment
		(start 269.569438 -365.600996)
		(end 269.569438 -358.516682)
		(width 1.016)
		(layer "B.Cu")
		(net "P3V3_IN")
	)
	(segment
		(start 267.686028 -367.484406)
		(end 269.569438 -365.600996)
		(width 1.016)
		(layer "B.Cu")
		(net "P3V3_IN")
	)
	(segment
		(start 131.50215 -382.683766)
		(end 129.252218 -380.433834)
		(width 1.016)
		(layer "B.Cu")
		(net "P3V3_IN")
	)
	(segment
		(start 454.336404 -373.5832)
		(end 454.717404 -373.2022)
		(width 1.016)
		(layer "B.Cu")
		(net "P3V3_IN")
	)
	(segment
		(start 186.748928 -368.60734)
		(end 186.748928 -372.600474)
		(width 1.016)
		(layer "B.Cu")
		(net "P3V3_IN")
	)
	(segment
		(start 298.964604 -356.309422)
		(end 305.641248 -356.309422)
		(width 1.016)
		(layer "B.Cu")
		(net "P3V3_IN")
	)
	(segment
		(start 314.911232 -361.088432)
		(end 316.911228 -361.088432)
		(width 1.016)
		(layer "B.Cu")
		(net "P3V3_IN")
	)
	(segment
		(start 310.132222 -356.309422)
		(end 314.911232 -361.088432)
		(width 1.016)
		(layer "B.Cu")
		(net "P3V3_IN")
	)
	(segment
		(start 186.748928 -372.600474)
		(end 184.669938 -374.679464)
		(width 1.016)
		(layer "B.Cu")
		(net "P3V3_IN")
	)
	(segment
		(start 326.294496 -375.0056)
		(end 323.754496 -372.4656)
		(width 1.016)
		(layer "B.Cu")
		(net "P3V3_IN")
	)
	(segment
		(start 158.6865 -373.916702)
		(end 164.296598 -379.5268)
		(width 0.508)
		(layer "B.Cu")
		(net "P3V3_IN")
	)
	(segment
		(start 269.569438 -358.516682)
		(end 271.306036 -356.780084)
		(width 1.016)
		(layer "B.Cu")
		(net "P3V3_IN")
	)
	(segment
		(start 271.306036 -356.780084)
		(end 279.471882 -356.780084)
		(width 1.016)
		(layer "B.Cu")
		(net "P3V3_IN")
	)
	(segment
		(start 184.669938 -377.444762)
		(end 182.5879 -379.5268)
		(width 1.016)
		(layer "B.Cu")
		(net "P3V3_IN")
	)
	(segment
		(start 319.271396 -372.4656)
		(end 318.356996 -373.38)
		(width 1.016)
		(layer "B.Cu")
		(net "P3V3_IN")
	)
	(segment
		(start 263.5377 -374.856756)
		(end 263.5377 -373.26697)
		(width 1.016)
		(layer "B.Cu")
		(net "P3V3_IN")
	)
	(segment
		(start 184.669938 -374.679464)
		(end 184.669938 -377.444762)
		(width 1.016)
		(layer "B.Cu")
		(net "P3V3_IN")
	)
	(segment
		(start 422.053004 -375.92)
		(end 422.637204 -375.92)
		(width 1.016)
		(layer "B.Cu")
		(net "P3V3_IN")
	)
	(segment
		(start 182.5879 -379.5268)
		(end 164.296598 -379.5268)
		(width 1.016)
		(layer "B.Cu")
		(net "P3V3_IN")
	)
	(segment
		(start 251.131578 -376.447812)
		(end 254.651256 -376.447812)
		(width 1.016)
		(layer "B.Cu")
		(net "P3V3_IN")
	)
	(segment
		(start 317.188596 -372.2116)
		(end 318.356996 -373.38)
		(width 1.016)
		(layer "B.Cu")
		(net "P3V3_IN")
	)
	(segment
		(start 279.471882 -356.780084)
		(end 281.001216 -358.309418)
		(width 1.016)
		(layer "B.Cu")
		(net "P3V3_IN")
	)
	(segment
		(start 450.729604 -375.031)
		(end 452.177404 -373.5832)
		(width 1.016)
		(layer "B.Cu")
		(net "P3V3_IN")
	)
	(segment
		(start 267.686028 -369.118642)
		(end 267.686028 -367.484406)
		(width 1.016)
		(layer "B.Cu")
		(net "P3V3_IN")
	)
	(segment
		(start 198.428102 -373.7102)
		(end 248.393966 -373.7102)
		(width 1.016)
		(layer "B.Cu")
		(net "P3V3_IN")
	)
	(segment
		(start 248.393966 -373.7102)
		(end 251.131578 -376.447812)
		(width 1.016)
		(layer "B.Cu")
		(net "P3V3_IN")
	)
	(segment
		(start 164.296598 -379.5268)
		(end 161.139632 -382.683766)
		(width 1.016)
		(layer "B.Cu")
		(net "P3V3_IN")
	)
	(segment
		(start 296.964608 -358.309418)
		(end 298.964604 -356.309422)
		(width 1.016)
		(layer "B.Cu")
		(net "P3V3_IN")
	)
	(segment
		(start 254.651256 -376.447812)
		(end 259.207 -381.003556)
		(width 1.016)
		(layer "B.Cu")
		(net "P3V3_IN")
	)
	(segment
		(start 187.752482 -367.603786)
		(end 192.321688 -367.603786)
		(width 1.016)
		(layer "B.Cu")
		(net "P3V3_IN")
	)
	(segment
		(start 452.177404 -373.5832)
		(end 454.336404 -373.5832)
		(width 1.016)
		(layer "B.Cu")
		(net "P3V3_IN")
	)
	(segment
		(start 317.188596 -361.3658)
		(end 317.188596 -372.2116)
		(width 1.016)
		(layer "B.Cu")
		(net "P3V3_IN")
	)
	(segment
		(start 263.5377 -373.26697)
		(end 267.686028 -369.118642)
		(width 1.016)
		(layer "B.Cu")
		(net "P3V3_IN")
	)
	(segment
		(start 323.754496 -372.4656)
		(end 319.271396 -372.4656)
		(width 1.016)
		(layer "B.Cu")
		(net "P3V3_IN")
	)
	(segment
		(start 161.139632 -382.683766)
		(end 131.50215 -382.683766)
		(width 1.016)
		(layer "B.Cu")
		(net "P3V3_IN")
	)
	(segment
		(start 316.911228 -361.088432)
		(end 317.188596 -361.3658)
		(width 1.016)
		(layer "B.Cu")
		(net "P3V3_IN")
	)
	(segment
		(start 423.526204 -375.031)
		(end 450.729604 -375.031)
		(width 1.016)
		(layer "B.Cu")
		(net "P3V3_IN")
	)
	(segment
		(start 263.5377 -374.856756)
		(end 263.5377 -376.672856)
		(width 1.016)
		(layer "In2.Cu")
		(net "P3V3_IN")
	)
	(segment
		(start 263.5377 -376.672856)
		(end 259.207 -381.003556)
		(width 1.016)
		(layer "In2.Cu")
		(net "P3V3_IN")
	)
	(segment
		(start 272.31848 -328.28484)
		(end 272.31848 -323.60108)
		(width 1.016)
		(layer "In5.Cu")
		(net "P3V3_IN")
	)
	(segment
		(start 34.994596 -377.4694)
		(end 34.181796 -378.2822)
		(width 1.016)
		(layer "In5.Cu")
		(net "P3V3_IN")
	)
	(segment
		(start 276.342348 -243.650008)
		(end 276.342348 -247.956578)
		(width 1.016)
		(layer "In5.Cu")
		(net "P3V3_IN")
	)
	(segment
		(start 34.181796 -378.2822)
		(end 29.558996 -378.2822)
		(width 1.016)
		(layer "In5.Cu")
		(net "P3V3_IN")
	)
	(segment
		(start 36.467796 -370.332)
		(end 35.652456 -369.51666)
		(width 1.016)
		(layer "In5.Cu")
		(net "P3V3_IN")
	)
	(segment
		(start 272.31848 -323.60108)
		(end 262.700516 -313.983116)
		(width 1.016)
		(layer "In5.Cu")
		(net "P3V3_IN")
	)
	(segment
		(start 36.467796 -376.4026)
		(end 36.467796 -370.332)
		(width 1.016)
		(layer "In5.Cu")
		(net "P3V3_IN")
	)
	(segment
		(start 27.730196 -371.39626)
		(end 26.462736 -370.1288)
		(width 1.016)
		(layer "In5.Cu")
		(net "P3V3_IN")
	)
	(segment
		(start 35.652456 -364.014766)
		(end 38.301422 -361.3658)
		(width 1.016)
		(layer "In5.Cu")
		(net "P3V3_IN")
	)
	(segment
		(start 261.960614 -299.636434)
		(end 242.196366 -299.636434)
		(width 1.016)
		(layer "In5.Cu")
		(net "P3V3_IN")
	)
	(segment
		(start 262.700516 -313.983116)
		(end 262.700516 -300.376336)
		(width 1.016)
		(layer "In5.Cu")
		(net "P3V3_IN")
	)
	(segment
		(start 268.9352 -227.0125)
		(end 265.3792 -227.0125)
		(width 1.016)
		(layer "In5.Cu")
		(net "P3V3_IN")
	)
	(segment
		(start 38.301422 -361.3658)
		(end 42.106596 -361.3658)
		(width 1.016)
		(layer "In5.Cu")
		(net "P3V3_IN")
	)
	(segment
		(start 332.648306 -375.92)
		(end 330.184506 -378.3838)
		(width 1.016)
		(layer "In5.Cu")
		(net "P3V3_IN")
	)
	(segment
		(start 264.37336 -298.703492)
		(end 262.700516 -300.376336)
		(width 1.016)
		(layer "In5.Cu")
		(net "P3V3_IN")
	)
	(segment
		(start 262.700516 -300.376336)
		(end 261.960614 -299.636434)
		(width 1.016)
		(layer "In5.Cu")
		(net "P3V3_IN")
	)
	(segment
		(start 330.184506 -378.3838)
		(end 327.170796 -378.3838)
		(width 1.016)
		(layer "In5.Cu")
		(net "P3V3_IN")
	)
	(segment
		(start 27.730196 -376.4534)
		(end 27.730196 -371.39626)
		(width 1.016)
		(layer "In5.Cu")
		(net "P3V3_IN")
	)
	(segment
		(start 264.373106 -259.92582)
		(end 264.373106 -260.661912)
		(width 1.016)
		(layer "In5.Cu")
		(net "P3V3_IN")
	)
	(segment
		(start 29.558996 -378.2822)
		(end 27.730196 -376.4534)
		(width 1.016)
		(layer "In5.Cu")
		(net "P3V3_IN")
	)
	(segment
		(start 326.294496 -377.5075)
		(end 326.294496 -375.0056)
		(width 1.016)
		(layer "In5.Cu")
		(net "P3V3_IN")
	)
	(segment
		(start 35.400996 -377.4694)
		(end 36.467796 -376.4026)
		(width 1.016)
		(layer "In5.Cu")
		(net "P3V3_IN")
	)
	(segment
		(start 264.37336 -260.662166)
		(end 264.37336 -298.703492)
		(width 1.016)
		(layer "In5.Cu")
		(net "P3V3_IN")
	)
	(segment
		(start 327.170796 -378.3838)
		(end 326.294496 -377.5075)
		(width 1.016)
		(layer "In5.Cu")
		(net "P3V3_IN")
	)
	(segment
		(start 242.196366 -299.636434)
		(end 240.7158 -301.117)
		(width 1.016)
		(layer "In5.Cu")
		(net "P3V3_IN")
	)
	(segment
		(start 35.400996 -377.4694)
		(end 34.994596 -377.4694)
		(width 1.016)
		(layer "In5.Cu")
		(net "P3V3_IN")
	)
	(segment
		(start 35.652456 -369.51666)
		(end 35.652456 -364.014766)
		(width 1.016)
		(layer "In5.Cu")
		(net "P3V3_IN")
	)
	(segment
		(start 276.342348 -247.956578)
		(end 264.373106 -259.92582)
		(width 1.016)
		(layer "In5.Cu")
		(net "P3V3_IN")
	)
	(segment
		(start 264.373106 -260.661912)
		(end 264.37336 -260.662166)
		(width 1.016)
		(layer "In5.Cu")
		(net "P3V3_IN")
	)
	(segment
		(start 422.053004 -375.92)
		(end 332.648306 -375.92)
		(width 1.016)
		(layer "In5.Cu")
		(net "P3V3_IN")
	)
	(segment
		(start 284.723586 -157.986222)
		(end 285.75635 -157.986222)
		(width 0.17145)
		(layer "F.Cu")
		(net "SCC_B_HS_EN")
	)
	(segment
		(start 283.41955 -157.986222)
		(end 284.723586 -157.986222)
		(width 0.17145)
		(layer "F.Cu")
		(net "SCC_B_HS_EN")
	)
	(via
		(at 285.75635 -157.986222)
		(size 0.5588)
		(drill 0.3048)
		(layers "F.Cu" "B.Cu")
		(net "SCC_B_HS_EN")
	)
	(via
		(at 284.723586 -157.986222)
		(size 0.6604)
		(drill 0.3302)
		(layers "F.Cu" "B.Cu")
		(net "SCC_B_HS_EN")
	)
	(segment
		(start 288.374074 -160.61563)
		(end 285.75635 -157.997906)
		(width 0.14605)
		(layer "In2.Cu")
		(net "SCC_B_HS_EN")
	)
	(segment
		(start 285.75635 -157.997906)
		(end 285.75635 -157.986222)
		(width 0.14605)
		(layer "In2.Cu")
		(net "SCC_B_HS_EN")
	)
	(segment
		(start 288.374074 -174.832772)
		(end 288.374074 -160.61563)
		(width 0.14605)
		(layer "In2.Cu")
		(net "SCC_B_HS_EN")
	)
	(segment
		(start 283.23667 -175.694594)
		(end 283.953458 -174.977806)
		(width 0.14605)
		(layer "In2.Cu")
		(net "SCC_B_HS_EN")
	)
	(segment
		(start 288.22904 -174.977806)
		(end 288.374074 -174.832772)
		(width 0.14605)
		(layer "In2.Cu")
		(net "SCC_B_HS_EN")
	)
	(segment
		(start 283.953458 -174.977806)
		(end 288.22904 -174.977806)
		(width 0.14605)
		(layer "In2.Cu")
		(net "SCC_B_HS_EN")
	)
	(segment
		(start 464.674204 -376.3772)
		(end 464.674204 -376.936)
		(width 0.254)
		(layer "F.Cu")
		(net "FAN_YELLOW_3")
	)
	(segment
		(start 465.944204 -375.1072)
		(end 464.674204 -376.3772)
		(width 0.254)
		(layer "F.Cu")
		(net "FAN_YELLOW_3")
	)
	(segment
		(start 465.944204 -374.2309)
		(end 465.944204 -375.1072)
		(width 0.254)
		(layer "F.Cu")
		(net "FAN_YELLOW_3")
	)
	(segment
		(start 461.065372 -378.229368)
		(end 463.164936 -378.229368)
		(width 0.254)
		(layer "F.Cu")
		(net "FAN_YELLOW_3")
	)
	(segment
		(start 464.674204 -376.936)
		(end 463.975704 -377.6345)
		(width 0.254)
		(layer "F.Cu")
		(net "FAN_YELLOW_3")
	)
	(segment
		(start 463.975704 -377.6345)
		(end 463.759804 -377.6345)
		(width 0.254)
		(layer "F.Cu")
		(net "FAN_YELLOW_3")
	)
	(segment
		(start 460.645764 -377.12269)
		(end 460.645764 -377.80976)
		(width 0.254)
		(layer "F.Cu")
		(net "FAN_YELLOW_3")
	)
	(segment
		(start 463.164936 -378.229368)
		(end 463.759804 -377.6345)
		(width 0.254)
		(layer "F.Cu")
		(net "FAN_YELLOW_3")
	)
	(segment
		(start 460.645764 -377.80976)
		(end 461.065372 -378.229368)
		(width 0.254)
		(layer "F.Cu")
		(net "FAN_YELLOW_3")
	)
	(via
		(at 463.759804 -377.6345)
		(size 0.6604)
		(drill 0.3302)
		(layers "F.Cu" "B.Cu")
		(net "FAN_YELLOW_3")
	)
	(segment
		(start 319.262506 -378.67336)
		(end 317.909956 -378.67336)
		(width 0.254)
		(layer "F.Cu")
		(net "FAN_YELLOW_2")
	)
	(segment
		(start 317.856616 -378.6632)
		(end 317.899796 -378.6632)
		(width 0.254)
		(layer "F.Cu")
		(net "FAN_YELLOW_2")
	)
	(segment
		(start 316.705996 -373.3546)
		(end 316.705996 -377.51258)
		(width 0.254)
		(layer "F.Cu")
		(net "FAN_YELLOW_2")
	)
	(segment
		(start 316.705996 -377.51258)
		(end 317.856616 -378.6632)
		(width 0.254)
		(layer "F.Cu")
		(net "FAN_YELLOW_2")
	)
	(segment
		(start 317.909956 -378.67336)
		(end 317.899796 -378.6632)
		(width 0.254)
		(layer "F.Cu")
		(net "FAN_YELLOW_2")
	)
	(segment
		(start 315.588396 -372.237)
		(end 316.705996 -373.3546)
		(width 0.254)
		(layer "F.Cu")
		(net "FAN_YELLOW_2")
	)
	(via
		(at 317.899796 -378.6632)
		(size 0.6604)
		(drill 0.3302)
		(layers "F.Cu" "B.Cu")
		(net "FAN_YELLOW_2")
	)
	(segment
		(start 190.323216 -376.804936)
		(end 190.323216 -377.251976)
		(width 0.254)
		(layer "F.Cu")
		(net "FAN_YELLOW_1")
	)
	(segment
		(start 189.94628 -376.428)
		(end 190.323216 -376.804936)
		(width 0.254)
		(layer "F.Cu")
		(net "FAN_YELLOW_1")
	)
	(segment
		(start 190.323216 -377.251976)
		(end 190.016892 -377.5583)
		(width 0.254)
		(layer "F.Cu")
		(net "FAN_YELLOW_1")
	)
	(segment
		(start 185.807604 -373.881396)
		(end 185.077862 -374.611138)
		(width 0.254)
		(layer "F.Cu")
		(net "FAN_YELLOW_1")
	)
	(segment
		(start 187.095638 -373.881396)
		(end 185.807604 -373.881396)
		(width 0.254)
		(layer "F.Cu")
		(net "FAN_YELLOW_1")
	)
	(segment
		(start 185.077862 -375.77395)
		(end 185.731912 -376.428)
		(width 0.254)
		(layer "F.Cu")
		(net "FAN_YELLOW_1")
	)
	(segment
		(start 190.016892 -377.5583)
		(end 189.333124 -377.5583)
		(width 0.254)
		(layer "F.Cu")
		(net "FAN_YELLOW_1")
	)
	(segment
		(start 187.6933 -377.5583)
		(end 189.333124 -377.5583)
		(width 0.254)
		(layer "F.Cu")
		(net "FAN_YELLOW_1")
	)
	(segment
		(start 185.731912 -376.428)
		(end 189.94628 -376.428)
		(width 0.254)
		(layer "F.Cu")
		(net "FAN_YELLOW_1")
	)
	(segment
		(start 185.077862 -374.611138)
		(end 185.077862 -375.77395)
		(width 0.254)
		(layer "F.Cu")
		(net "FAN_YELLOW_1")
	)
	(via
		(at 189.333124 -377.5583)
		(size 0.6604)
		(drill 0.3302)
		(layers "F.Cu" "B.Cu")
		(net "FAN_YELLOW_1")
	)
	(segment
		(start 25.634696 -374.0277)
		(end 25.634696 -376.2121)
		(width 0.254)
		(layer "F.Cu")
		(net "FAN_YELLOW_0")
	)
	(segment
		(start 28.102306 -377.45416)
		(end 26.876756 -377.45416)
		(width 0.254)
		(layer "F.Cu")
		(net "FAN_YELLOW_0")
	)
	(segment
		(start 23.932896 -372.3259)
		(end 25.634696 -374.0277)
		(width 0.254)
		(layer "F.Cu")
		(net "FAN_YELLOW_0")
	)
	(segment
		(start 25.634696 -376.2121)
		(end 26.663396 -377.2408)
		(width 0.254)
		(layer "F.Cu")
		(net "FAN_YELLOW_0")
	)
	(segment
		(start 26.876756 -377.45416)
		(end 26.663396 -377.2408)
		(width 0.254)
		(layer "F.Cu")
		(net "FAN_YELLOW_0")
	)
	(via
		(at 26.663396 -377.2408)
		(size 0.6604)
		(drill 0.3302)
		(layers "F.Cu" "B.Cu")
		(net "FAN_YELLOW_0")
	)
	(segment
		(start 466.95995 -377.219972)
		(end 466.95995 -377.037854)
		(width 0.254)
		(layer "F.Cu")
		(net "FAN_LED_YELLOW_3")
	)
	(segment
		(start 468.128604 -375.8692)
		(end 468.128604 -374.4849)
		(width 0.254)
		(layer "F.Cu")
		(net "FAN_LED_YELLOW_3")
	)
	(segment
		(start 468.128604 -374.4849)
		(end 467.874604 -374.2309)
		(width 0.254)
		(layer "F.Cu")
		(net "FAN_LED_YELLOW_3")
	)
	(segment
		(start 466.95995 -377.037854)
		(end 468.128604 -375.8692)
		(width 0.254)
		(layer "F.Cu")
		(net "FAN_LED_YELLOW_3")
	)
	(segment
		(start 309.360062 -377.219972)
		(end 309.360062 -374.350534)
		(width 0.254)
		(layer "F.Cu")
		(net "FAN_LED_YELLOW_2")
	)
	(segment
		(start 311.473596 -372.237)
		(end 313.657996 -372.237)
		(width 0.254)
		(layer "F.Cu")
		(net "FAN_LED_YELLOW_2")
	)
	(segment
		(start 309.360062 -374.350534)
		(end 311.473596 -372.237)
		(width 0.254)
		(layer "F.Cu")
		(net "FAN_LED_YELLOW_2")
	)
	(segment
		(start 182.9943 -377.5583)
		(end 185.7629 -377.5583)
		(width 0.254)
		(layer "F.Cu")
		(net "FAN_LED_YELLOW_1")
	)
	(segment
		(start 176.555146 -376.2248)
		(end 181.6608 -376.2248)
		(width 0.254)
		(layer "F.Cu")
		(net "FAN_LED_YELLOW_1")
	)
	(segment
		(start 175.559974 -377.219972)
		(end 176.555146 -376.2248)
		(width 0.254)
		(layer "F.Cu")
		(net "FAN_LED_YELLOW_1")
	)
	(segment
		(start 181.6608 -376.2248)
		(end 182.9943 -377.5583)
		(width 0.254)
		(layer "F.Cu")
		(net "FAN_LED_YELLOW_1")
	)
	(segment
		(start 17.960086 -377.219972)
		(end 17.960086 -375.22531)
		(width 0.254)
		(layer "F.Cu")
		(net "FAN_LED_YELLOW_0")
	)
	(segment
		(start 20.859496 -372.3259)
		(end 22.002496 -372.3259)
		(width 0.254)
		(layer "F.Cu")
		(net "FAN_LED_YELLOW_0")
	)
	(segment
		(start 17.960086 -375.22531)
		(end 20.859496 -372.3259)
		(width 0.254)
		(layer "F.Cu")
		(net "FAN_LED_YELLOW_0")
	)
	(via
		(at 299.0469 -151.839168)
		(size 0.5588)
		(drill 0.3048)
		(layers "F.Cu" "B.Cu")
		(net "SCC_B_FAULT_LED")
	)
	(segment
		(start 299.043344 -151.835612)
		(end 299.0469 -151.839168)
		(width 0.14605)
		(layer "In2.Cu")
		(net "SCC_B_FAULT_LED")
	)
	(segment
		(start 292.19017 -219.569792)
		(end 292.19017 -191.099694)
		(width 0.14605)
		(layer "In2.Cu")
		(net "SCC_B_FAULT_LED")
	)
	(segment
		(start 298.231814 -185.05805)
		(end 298.231814 -154.81173)
		(width 0.14605)
		(layer "In2.Cu")
		(net "SCC_B_FAULT_LED")
	)
	(segment
		(start 299.043344 -154.0002)
		(end 299.043344 -151.835612)
		(width 0.14605)
		(layer "In2.Cu")
		(net "SCC_B_FAULT_LED")
	)
	(segment
		(start 283.23667 -222.494348)
		(end 283.93898 -221.792038)
		(width 0.14605)
		(layer "In2.Cu")
		(net "SCC_B_FAULT_LED")
	)
	(segment
		(start 283.93898 -221.792038)
		(end 289.967924 -221.792038)
		(width 0.14605)
		(layer "In2.Cu")
		(net "SCC_B_FAULT_LED")
	)
	(segment
		(start 289.967924 -221.792038)
		(end 292.19017 -219.569792)
		(width 0.14605)
		(layer "In2.Cu")
		(net "SCC_B_FAULT_LED")
	)
	(segment
		(start 292.19017 -191.099694)
		(end 298.231814 -185.05805)
		(width 0.14605)
		(layer "In2.Cu")
		(net "SCC_B_FAULT_LED")
	)
	(segment
		(start 298.231814 -154.81173)
		(end 299.043344 -154.0002)
		(width 0.14605)
		(layer "In2.Cu")
		(net "SCC_B_FAULT_LED")
	)
	(segment
		(start 243.837206 -97.575624)
		(end 250.976638 -104.715056)
		(width 0.14605)
		(layer "In5.Cu")
		(net "SCC_B_FAULT_LED")
	)
	(segment
		(start 277.018242 -120.688354)
		(end 280.180288 -120.688354)
		(width 0.14605)
		(layer "In5.Cu")
		(net "SCC_B_FAULT_LED")
	)
	(segment
		(start 226.200208 -77.600048)
		(end 225.561652 -78.238604)
		(width 0.14605)
		(layer "In5.Cu")
		(net "SCC_B_FAULT_LED")
	)
	(segment
		(start 280.180288 -120.688354)
		(end 283.002736 -123.510802)
		(width 0.14605)
		(layer "In5.Cu")
		(net "SCC_B_FAULT_LED")
	)
	(segment
		(start 284.294326 -123.510802)
		(end 300.501558 -139.718034)
		(width 0.14605)
		(layer "In5.Cu")
		(net "SCC_B_FAULT_LED")
	)
	(segment
		(start 250.976638 -104.715056)
		(end 261.044944 -104.715056)
		(width 0.14605)
		(layer "In5.Cu")
		(net "SCC_B_FAULT_LED")
	)
	(segment
		(start 261.044944 -104.715056)
		(end 277.018242 -120.688354)
		(width 0.14605)
		(layer "In5.Cu")
		(net "SCC_B_FAULT_LED")
	)
	(segment
		(start 300.501558 -139.718034)
		(end 300.501558 -150.38451)
		(width 0.14605)
		(layer "In5.Cu")
		(net "SCC_B_FAULT_LED")
	)
	(segment
		(start 225.561652 -78.238604)
		(end 225.561652 -80.401668)
		(width 0.14605)
		(layer "In5.Cu")
		(net "SCC_B_FAULT_LED")
	)
	(segment
		(start 226.590606 -85.547454)
		(end 227.602034 -86.558882)
		(width 0.14605)
		(layer "In5.Cu")
		(net "SCC_B_FAULT_LED")
	)
	(segment
		(start 226.590606 -81.430622)
		(end 226.590606 -85.547454)
		(width 0.14605)
		(layer "In5.Cu")
		(net "SCC_B_FAULT_LED")
	)
	(segment
		(start 237.781592 -97.575624)
		(end 243.837206 -97.575624)
		(width 0.14605)
		(layer "In5.Cu")
		(net "SCC_B_FAULT_LED")
	)
	(segment
		(start 283.002736 -123.510802)
		(end 284.294326 -123.510802)
		(width 0.14605)
		(layer "In5.Cu")
		(net "SCC_B_FAULT_LED")
	)
	(segment
		(start 227.602034 -86.558882)
		(end 227.602034 -87.396066)
		(width 0.14605)
		(layer "In5.Cu")
		(net "SCC_B_FAULT_LED")
	)
	(segment
		(start 300.501558 -150.38451)
		(end 299.0469 -151.839168)
		(width 0.14605)
		(layer "In5.Cu")
		(net "SCC_B_FAULT_LED")
	)
	(segment
		(start 227.602034 -87.396066)
		(end 237.781592 -97.575624)
		(width 0.14605)
		(layer "In5.Cu")
		(net "SCC_B_FAULT_LED")
	)
	(segment
		(start 225.561652 -80.401668)
		(end 226.590606 -81.430622)
		(width 0.14605)
		(layer "In5.Cu")
		(net "SCC_B_FAULT_LED")
	)
	(segment
		(start 423.196004 -370.078)
		(end 423.196004 -368.9985)
		(width 0.254)
		(layer "F.Cu")
		(net "FANTACH_R3")
	)
	(segment
		(start 224.710244 -309.63108)
		(end 224.707958 -309.633366)
		(width 0.254)
		(layer "F.Cu")
		(net "FANTACH_R3")
	)
	(segment
		(start 423.196004 -368.9985)
		(end 423.132504 -368.935)
		(width 0.254)
		(layer "F.Cu")
		(net "FANTACH_R3")
	)
	(segment
		(start 421.616124 -364.617)
		(end 421.616124 -367.41862)
		(width 0.254)
		(layer "F.Cu")
		(net "FANTACH_R3")
	)
	(segment
		(start 421.616124 -367.41862)
		(end 423.132504 -368.935)
		(width 0.254)
		(layer "F.Cu")
		(net "FANTACH_R3")
	)
	(segment
		(start 421.616124 -362.959142)
		(end 421.616124 -364.617)
		(width 0.254)
		(layer "F.Cu")
		(net "FANTACH_R3")
	)
	(segment
		(start 305.031648 -349.746062)
		(end 315.917072 -349.746062)
		(width 0.254)
		(layer "F.Cu")
		(net "FANTACH_R3")
	)
	(segment
		(start 228.1936 -309.63108)
		(end 224.710244 -309.63108)
		(width 0.254)
		(layer "F.Cu")
		(net "FANTACH_R3")
	)
	(via
		(at 421.616124 -362.959142)
		(size 0.5588)
		(drill 0.3048)
		(layers "F.Cu" "B.Cu")
		(net "FANTACH_R3")
	)
	(via
		(at 315.917072 -349.746062)
		(size 0.5588)
		(drill 0.3048)
		(layers "F.Cu" "B.Cu")
		(net "FANTACH_R3")
	)
	(via
		(at 224.707958 -309.633366)
		(size 0.5588)
		(drill 0.3048)
		(layers "F.Cu" "B.Cu")
		(net "FANTACH_R3")
	)
	(via
		(at 421.616124 -364.617)
		(size 0.6604)
		(drill 0.3302)
		(layers "F.Cu" "B.Cu")
		(net "FANTACH_R3")
	)
	(segment
		(start 421.616124 -362.959142)
		(end 416.25647 -357.599488)
		(width 0.254)
		(layer "B.Cu")
		(net "FANTACH_R3")
	)
	(segment
		(start 315.917072 -353.712018)
		(end 315.917072 -349.746062)
		(width 0.254)
		(layer "B.Cu")
		(net "FANTACH_R3")
	)
	(segment
		(start 316.035944 -324.936104)
		(end 311.78119 -320.68135)
		(width 0.254)
		(layer "B.Cu")
		(net "FANTACH_R3")
	)
	(segment
		(start 311.78119 -320.68135)
		(end 235.755942 -320.68135)
		(width 0.254)
		(layer "B.Cu")
		(net "FANTACH_R3")
	)
	(segment
		(start 316.035944 -349.62719)
		(end 316.035944 -324.936104)
		(width 0.254)
		(layer "B.Cu")
		(net "FANTACH_R3")
	)
	(segment
		(start 416.25647 -357.599488)
		(end 329.006708 -357.599488)
		(width 0.254)
		(layer "B.Cu")
		(net "FANTACH_R3")
	)
	(segment
		(start 315.917072 -349.746062)
		(end 316.035944 -349.62719)
		(width 0.254)
		(layer "B.Cu")
		(net "FANTACH_R3")
	)
	(segment
		(start 235.755942 -320.68135)
		(end 224.707958 -309.633366)
		(width 0.254)
		(layer "B.Cu")
		(net "FANTACH_R3")
	)
	(segment
		(start 327.551796 -359.0544)
		(end 321.259454 -359.0544)
		(width 0.254)
		(layer "B.Cu")
		(net "FANTACH_R3")
	)
	(segment
		(start 329.006708 -357.599488)
		(end 327.551796 -359.0544)
		(width 0.254)
		(layer "B.Cu")
		(net "FANTACH_R3")
	)
	(segment
		(start 321.259454 -359.0544)
		(end 315.917072 -353.712018)
		(width 0.254)
		(layer "B.Cu")
		(net "FANTACH_R3")
	)
	(segment
		(start 228.1936 -308.3306)
		(end 226.069144 -308.3306)
		(width 0.254)
		(layer "F.Cu")
		(net "FANTACH_R2")
	)
	(segment
		(start 226.06 -308.339744)
		(end 226.05111 -308.339744)
		(width 0.254)
		(layer "F.Cu")
		(net "FANTACH_R2")
	)
	(segment
		(start 326.548496 -370.0145)
		(end 326.548496 -368.935)
		(width 0.254)
		(layer "F.Cu")
		(net "FANTACH_R2")
	)
	(segment
		(start 326.611996 -370.078)
		(end 326.548496 -370.0145)
		(width 0.254)
		(layer "F.Cu")
		(net "FANTACH_R2")
	)
	(segment
		(start 305.031648 -351.046542)
		(end 317.588138 -351.046542)
		(width 0.254)
		(layer "F.Cu")
		(net "FANTACH_R2")
	)
	(segment
		(start 324.516496 -359.744772)
		(end 324.516496 -366.903)
		(width 0.254)
		(layer "F.Cu")
		(net "FANTACH_R2")
	)
	(segment
		(start 324.516496 -357.939086)
		(end 324.516496 -359.744772)
		(width 0.254)
		(layer "F.Cu")
		(net "FANTACH_R2")
	)
	(segment
		(start 226.069144 -308.3306)
		(end 226.06 -308.339744)
		(width 0.254)
		(layer "F.Cu")
		(net "FANTACH_R2")
	)
	(segment
		(start 324.516496 -366.903)
		(end 326.548496 -368.935)
		(width 0.254)
		(layer "F.Cu")
		(net "FANTACH_R2")
	)
	(via
		(at 324.516496 -357.939086)
		(size 0.5588)
		(drill 0.3048)
		(layers "F.Cu" "B.Cu")
		(net "FANTACH_R2")
	)
	(via
		(at 317.588138 -351.046542)
		(size 0.5588)
		(drill 0.3048)
		(layers "F.Cu" "B.Cu")
		(net "FANTACH_R2")
	)
	(via
		(at 226.05111 -308.339744)
		(size 0.5588)
		(drill 0.3048)
		(layers "F.Cu" "B.Cu")
		(net "FANTACH_R2")
	)
	(via
		(at 324.516496 -359.744772)
		(size 0.6604)
		(drill 0.3302)
		(layers "F.Cu" "B.Cu")
		(net "FANTACH_R2")
	)
	(segment
		(start 237.376716 -319.66535)
		(end 226.05111 -308.339744)
		(width 0.254)
		(layer "B.Cu")
		(net "FANTACH_R2")
	)
	(segment
		(start 324.516496 -357.939086)
		(end 323.569076 -356.991666)
		(width 0.254)
		(layer "B.Cu")
		(net "FANTACH_R2")
	)
	(segment
		(start 317.588138 -351.046542)
		(end 317.588138 -324.115938)
		(width 0.254)
		(layer "B.Cu")
		(net "FANTACH_R2")
	)
	(segment
		(start 317.588138 -324.115938)
		(end 313.13755 -319.66535)
		(width 0.254)
		(layer "B.Cu")
		(net "FANTACH_R2")
	)
	(segment
		(start 313.13755 -319.66535)
		(end 237.376716 -319.66535)
		(width 0.254)
		(layer "B.Cu")
		(net "FANTACH_R2")
	)
	(segment
		(start 317.588138 -353.010724)
		(end 317.588138 -351.046542)
		(width 0.254)
		(layer "B.Cu")
		(net "FANTACH_R2")
	)
	(segment
		(start 321.56908 -356.991666)
		(end 317.588138 -353.010724)
		(width 0.254)
		(layer "B.Cu")
		(net "FANTACH_R2")
	)
	(segment
		(start 323.569076 -356.991666)
		(end 321.56908 -356.991666)
		(width 0.254)
		(layer "B.Cu")
		(net "FANTACH_R2")
	)
	(segment
		(start 305.031648 -352.347022)
		(end 320.350896 -352.347022)
		(width 0.254)
		(layer "F.Cu")
		(net "FANTACH_R1")
	)
	(segment
		(start 126.111 -372.872)
		(end 126.8095 -372.1735)
		(width 0.254)
		(layer "F.Cu")
		(net "FANTACH_R1")
	)
	(segment
		(start 126.111 -374.904)
		(end 126.111 -372.872)
		(width 0.254)
		(layer "F.Cu")
		(net "FANTACH_R1")
	)
	(segment
		(start 228.1936 -307.03012)
		(end 225.892868 -307.03012)
		(width 0.254)
		(layer "F.Cu")
		(net "FANTACH_R1")
	)
	(segment
		(start 128.143 -372.237)
		(end 128.0795 -372.1735)
		(width 0.254)
		(layer "F.Cu")
		(net "FANTACH_R1")
	)
	(segment
		(start 225.892868 -307.03012)
		(end 225.76155 -306.898802)
		(width 0.254)
		(layer "F.Cu")
		(net "FANTACH_R1")
	)
	(segment
		(start 126.8095 -372.1735)
		(end 127 -372.1735)
		(width 0.254)
		(layer "F.Cu")
		(net "FANTACH_R1")
	)
	(segment
		(start 128.0795 -372.1735)
		(end 127 -372.1735)
		(width 0.254)
		(layer "F.Cu")
		(net "FANTACH_R1")
	)
	(via
		(at 320.350896 -352.347022)
		(size 0.5588)
		(drill 0.3048)
		(layers "F.Cu" "B.Cu")
		(net "FANTACH_R1")
	)
	(via
		(at 215.361774 -304.541174)
		(size 0.6096)
		(drill 0.3048)
		(layers "F.Cu" "B.Cu")
		(net "FANTACH_R1")
	)
	(via
		(at 225.76155 -306.898802)
		(size 0.5588)
		(drill 0.3048)
		(layers "F.Cu" "B.Cu")
		(net "FANTACH_R1")
	)
	(via
		(at 126.111 -374.904)
		(size 0.5588)
		(drill 0.3048)
		(layers "F.Cu" "B.Cu")
		(net "FANTACH_R1")
	)
	(segment
		(start 228.113844 -306.575714)
		(end 228.090984 -306.552854)
		(width 0.254)
		(layer "B.Cu")
		(net "FANTACH_R1")
	)
	(segment
		(start 126.111 -374.904)
		(end 126.111 -373.634)
		(width 0.254)
		(layer "B.Cu")
		(net "FANTACH_R1")
	)
	(segment
		(start 228.401372 -306.575714)
		(end 228.113844 -306.575714)
		(width 0.254)
		(layer "B.Cu")
		(net "FANTACH_R1")
	)
	(segment
		(start 314.066682 -318.14135)
		(end 239.967008 -318.14135)
		(width 0.254)
		(layer "B.Cu")
		(net "FANTACH_R1")
	)
	(segment
		(start 126.111 -373.634)
		(end 124.333 -371.856)
		(width 0.254)
		(layer "B.Cu")
		(net "FANTACH_R1")
	)
	(segment
		(start 226.107498 -306.552854)
		(end 225.76155 -306.898802)
		(width 0.254)
		(layer "B.Cu")
		(net "FANTACH_R1")
	)
	(segment
		(start 50.17008 -312.975244)
		(end 169.878756 -312.975244)
		(width 0.254)
		(layer "B.Cu")
		(net "FANTACH_R1")
	)
	(segment
		(start 225.288348 -306.4256)
		(end 217.213434 -306.4256)
		(width 0.254)
		(layer "B.Cu")
		(net "FANTACH_R1")
	)
	(segment
		(start 90.221054 -371.856)
		(end 83.794854 -365.4298)
		(width 0.254)
		(layer "B.Cu")
		(net "FANTACH_R1")
	)
	(segment
		(start 124.333 -371.856)
		(end 90.221054 -371.856)
		(width 0.254)
		(layer "B.Cu")
		(net "FANTACH_R1")
	)
	(segment
		(start 36.866068 -359.34777)
		(end 36.866068 -326.279256)
		(width 0.254)
		(layer "B.Cu")
		(net "FANTACH_R1")
	)
	(segment
		(start 239.967008 -318.14135)
		(end 228.401372 -306.575714)
		(width 0.254)
		(layer "B.Cu")
		(net "FANTACH_R1")
	)
	(segment
		(start 217.213434 -306.4256)
		(end 215.437974 -304.65014)
		(width 0.254)
		(layer "B.Cu")
		(net "FANTACH_R1")
	)
	(segment
		(start 320.350896 -324.425564)
		(end 314.066682 -318.14135)
		(width 0.254)
		(layer "B.Cu")
		(net "FANTACH_R1")
	)
	(segment
		(start 42.948098 -365.4298)
		(end 36.866068 -359.34777)
		(width 0.254)
		(layer "B.Cu")
		(net "FANTACH_R1")
	)
	(segment
		(start 182.9562 -299.8978)
		(end 210.660234 -299.8978)
		(width 0.254)
		(layer "B.Cu")
		(net "FANTACH_R1")
	)
	(segment
		(start 215.437974 -304.617374)
		(end 215.361774 -304.541174)
		(width 0.254)
		(layer "B.Cu")
		(net "FANTACH_R1")
	)
	(segment
		(start 320.350896 -352.347022)
		(end 320.350896 -324.425564)
		(width 0.254)
		(layer "B.Cu")
		(net "FANTACH_R1")
	)
	(segment
		(start 36.866068 -326.279256)
		(end 50.17008 -312.975244)
		(width 0.254)
		(layer "B.Cu")
		(net "FANTACH_R1")
	)
	(segment
		(start 169.878756 -312.975244)
		(end 182.9562 -299.8978)
		(width 0.254)
		(layer "B.Cu")
		(net "FANTACH_R1")
	)
	(segment
		(start 215.285574 -304.464974)
		(end 215.361774 -304.541174)
		(width 0.254)
		(layer "B.Cu")
		(net "FANTACH_R1")
	)
	(segment
		(start 210.660234 -299.8978)
		(end 215.227408 -304.464974)
		(width 0.254)
		(layer "B.Cu")
		(net "FANTACH_R1")
	)
	(segment
		(start 228.090984 -306.552854)
		(end 226.107498 -306.552854)
		(width 0.254)
		(layer "B.Cu")
		(net "FANTACH_R1")
	)
	(segment
		(start 215.227408 -304.464974)
		(end 215.285574 -304.464974)
		(width 0.254)
		(layer "B.Cu")
		(net "FANTACH_R1")
	)
	(segment
		(start 215.437974 -304.65014)
		(end 215.437974 -304.617374)
		(width 0.254)
		(layer "B.Cu")
		(net "FANTACH_R1")
	)
	(segment
		(start 225.76155 -306.898802)
		(end 225.288348 -306.4256)
		(width 0.254)
		(layer "B.Cu")
		(net "FANTACH_R1")
	)
	(segment
		(start 83.794854 -365.4298)
		(end 42.948098 -365.4298)
		(width 0.254)
		(layer "B.Cu")
		(net "FANTACH_R1")
	)
	(segment
		(start 35.273996 -368.9985)
		(end 35.210496 -368.935)
		(width 0.254)
		(layer "F.Cu")
		(net "FANTACH_R0")
	)
	(segment
		(start 35.210496 -368.935)
		(end 34.359596 -368.935)
		(width 0.254)
		(layer "F.Cu")
		(net "FANTACH_R0")
	)
	(segment
		(start 228.1936 -305.72964)
		(end 226.8728 -305.72964)
		(width 0.254)
		(layer "F.Cu")
		(net "FANTACH_R0")
	)
	(segment
		(start 34.359596 -368.935)
		(end 34.334196 -368.9096)
		(width 0.254)
		(layer "F.Cu")
		(net "FANTACH_R0")
	)
	(segment
		(start 35.273996 -370.078)
		(end 35.273996 -368.9985)
		(width 0.254)
		(layer "F.Cu")
		(net "FANTACH_R0")
	)
	(segment
		(start 305.031648 -353.647502)
		(end 320.965068 -353.647502)
		(width 0.254)
		(layer "F.Cu")
		(net "FANTACH_R0")
	)
	(via
		(at 31.869126 -348.963488)
		(size 0.6096)
		(drill 0.3048)
		(layers "F.Cu" "B.Cu")
		(net "FANTACH_R0")
	)
	(via
		(at 34.334196 -368.9096)
		(size 0.5588)
		(drill 0.3048)
		(layers "F.Cu" "B.Cu")
		(net "FANTACH_R0")
	)
	(via
		(at 320.965068 -353.647502)
		(size 0.5588)
		(drill 0.3048)
		(layers "F.Cu" "B.Cu")
		(net "FANTACH_R0")
	)
	(via
		(at 226.8728 -305.72964)
		(size 0.5588)
		(drill 0.3048)
		(layers "F.Cu" "B.Cu")
		(net "FANTACH_R0")
	)
	(segment
		(start 320.965068 -353.647502)
		(end 320.965068 -324.32117)
		(width 0.254)
		(layer "B.Cu")
		(net "FANTACH_R0")
	)
	(segment
		(start 31.869126 -348.963488)
		(end 31.869126 -362.069126)
		(width 0.254)
		(layer "B.Cu")
		(net "FANTACH_R0")
	)
	(segment
		(start 211.036662 -299.3898)
		(end 182.379366 -299.3898)
		(width 0.254)
		(layer "B.Cu")
		(net "FANTACH_R0")
	)
	(segment
		(start 34.943796 -368.3)
		(end 34.334196 -368.9096)
		(width 0.254)
		(layer "B.Cu")
		(net "FANTACH_R0")
	)
	(segment
		(start 34.943796 -365.143796)
		(end 34.943796 -368.3)
		(width 0.254)
		(layer "B.Cu")
		(net "FANTACH_R0")
	)
	(segment
		(start 228.274118 -305.72964)
		(end 226.8728 -305.72964)
		(width 0.254)
		(layer "B.Cu")
		(net "FANTACH_R0")
	)
	(segment
		(start 182.379366 -299.3898)
		(end 169.730166 -312.039)
		(width 0.254)
		(layer "B.Cu")
		(net "FANTACH_R0")
	)
	(segment
		(start 226.8728 -305.72964)
		(end 217.376502 -305.72964)
		(width 0.254)
		(layer "B.Cu")
		(net "FANTACH_R0")
	)
	(segment
		(start 217.376502 -305.72964)
		(end 211.036662 -299.3898)
		(width 0.254)
		(layer "B.Cu")
		(net "FANTACH_R0")
	)
	(segment
		(start 320.965068 -324.32117)
		(end 314.277248 -317.63335)
		(width 0.254)
		(layer "B.Cu")
		(net "FANTACH_R0")
	)
	(segment
		(start 31.869126 -330.418186)
		(end 31.869126 -348.963488)
		(width 0.254)
		(layer "B.Cu")
		(net "FANTACH_R0")
	)
	(segment
		(start 50.248312 -312.039)
		(end 31.869126 -330.418186)
		(width 0.254)
		(layer "B.Cu")
		(net "FANTACH_R0")
	)
	(segment
		(start 31.869126 -362.069126)
		(end 34.943796 -365.143796)
		(width 0.254)
		(layer "B.Cu")
		(net "FANTACH_R0")
	)
	(segment
		(start 314.277248 -317.63335)
		(end 240.177828 -317.63335)
		(width 0.254)
		(layer "B.Cu")
		(net "FANTACH_R0")
	)
	(segment
		(start 169.730166 -312.039)
		(end 50.248312 -312.039)
		(width 0.254)
		(layer "B.Cu")
		(net "FANTACH_R0")
	)
	(segment
		(start 240.177828 -317.63335)
		(end 228.274118 -305.72964)
		(width 0.254)
		(layer "B.Cu")
		(net "FANTACH_R0")
	)
	(segment
		(start 305.031648 -350.396302)
		(end 316.725046 -350.396302)
		(width 0.254)
		(layer "F.Cu")
		(net "FANTACH_F3")
	)
	(segment
		(start 422.632124 -362.959142)
		(end 423.132504 -363.459522)
		(width 0.254)
		(layer "F.Cu")
		(net "FANTACH_F3")
	)
	(segment
		(start 423.196004 -365.379)
		(end 423.132504 -365.3155)
		(width 0.254)
		(layer "F.Cu")
		(net "FANTACH_F3")
	)
	(segment
		(start 423.132504 -363.459522)
		(end 423.132504 -364.236)
		(width 0.254)
		(layer "F.Cu")
		(net "FANTACH_F3")
	)
	(segment
		(start 423.132504 -365.3155)
		(end 423.132504 -364.236)
		(width 0.254)
		(layer "F.Cu")
		(net "FANTACH_F3")
	)
	(segment
		(start 228.1936 -308.98084)
		(end 225.3488 -308.98084)
		(width 0.254)
		(layer "F.Cu")
		(net "FANTACH_F3")
	)
	(via
		(at 316.725046 -350.396302)
		(size 0.5588)
		(drill 0.3048)
		(layers "F.Cu" "B.Cu")
		(net "FANTACH_F3")
	)
	(via
		(at 225.3488 -308.98084)
		(size 0.5588)
		(drill 0.3048)
		(layers "F.Cu" "B.Cu")
		(net "FANTACH_F3")
	)
	(via
		(at 422.632124 -362.959142)
		(size 0.5588)
		(drill 0.3048)
		(layers "F.Cu" "B.Cu")
		(net "FANTACH_F3")
	)
	(via
		(at 232.163874 -315.795914)
		(size 0.6096)
		(drill 0.3048)
		(layers "F.Cu" "B.Cu")
		(net "FANTACH_F3")
	)
	(segment
		(start 327.119996 -358.521)
		(end 321.8688 -358.521)
		(width 0.254)
		(layer "B.Cu")
		(net "FANTACH_F3")
	)
	(segment
		(start 321.8688 -358.521)
		(end 316.725046 -353.377246)
		(width 0.254)
		(layer "B.Cu")
		(net "FANTACH_F3")
	)
	(segment
		(start 312.415936 -320.17335)
		(end 316.725046 -324.48246)
		(width 0.254)
		(layer "B.Cu")
		(net "FANTACH_F3")
	)
	(segment
		(start 422.632124 -362.959142)
		(end 416.75812 -357.085138)
		(width 0.254)
		(layer "B.Cu")
		(net "FANTACH_F3")
	)
	(segment
		(start 416.75812 -357.085138)
		(end 328.555858 -357.085138)
		(width 0.254)
		(layer "B.Cu")
		(net "FANTACH_F3")
	)
	(segment
		(start 225.3488 -308.98084)
		(end 232.163874 -315.795914)
		(width 0.254)
		(layer "B.Cu")
		(net "FANTACH_F3")
	)
	(segment
		(start 236.54131 -320.17335)
		(end 312.415936 -320.17335)
		(width 0.254)
		(layer "B.Cu")
		(net "FANTACH_F3")
	)
	(segment
		(start 328.555858 -357.085138)
		(end 327.119996 -358.521)
		(width 0.254)
		(layer "B.Cu")
		(net "FANTACH_F3")
	)
	(segment
		(start 232.163874 -315.795914)
		(end 236.54131 -320.17335)
		(width 0.254)
		(layer "B.Cu")
		(net "FANTACH_F3")
	)
	(segment
		(start 316.725046 -324.48246)
		(end 316.725046 -350.396302)
		(width 0.254)
		(layer "B.Cu")
		(net "FANTACH_F3")
	)
	(segment
		(start 316.725046 -353.377246)
		(end 316.725046 -350.396302)
		(width 0.254)
		(layer "B.Cu")
		(net "FANTACH_F3")
	)
	(segment
		(start 325.532496 -363.22)
		(end 326.548496 -364.236)
		(width 0.254)
		(layer "F.Cu")
		(net "FANTACH_F2")
	)
	(segment
		(start 228.1936 -307.68036)
		(end 226.68484 -307.68036)
		(width 0.254)
		(layer "F.Cu")
		(net "FANTACH_F2")
	)
	(segment
		(start 326.611996 -365.379)
		(end 326.548496 -365.3155)
		(width 0.254)
		(layer "F.Cu")
		(net "FANTACH_F2")
	)
	(segment
		(start 325.532496 -362.106972)
		(end 325.532496 -363.22)
		(width 0.254)
		(layer "F.Cu")
		(net "FANTACH_F2")
	)
	(segment
		(start 305.031648 -351.696782)
		(end 318.30391 -351.696782)
		(width 0.254)
		(layer "F.Cu")
		(net "FANTACH_F2")
	)
	(segment
		(start 326.548496 -365.3155)
		(end 326.548496 -364.236)
		(width 0.254)
		(layer "F.Cu")
		(net "FANTACH_F2")
	)
	(segment
		(start 325.532496 -357.939086)
		(end 325.532496 -362.106972)
		(width 0.254)
		(layer "F.Cu")
		(net "FANTACH_F2")
	)
	(via
		(at 226.68484 -307.68036)
		(size 0.5588)
		(drill 0.3048)
		(layers "F.Cu" "B.Cu")
		(net "FANTACH_F2")
	)
	(via
		(at 325.532496 -362.106972)
		(size 0.6604)
		(drill 0.3302)
		(layers "F.Cu" "B.Cu")
		(net "FANTACH_F2")
	)
	(via
		(at 318.30391 -351.696782)
		(size 0.5588)
		(drill 0.3048)
		(layers "F.Cu" "B.Cu")
		(net "FANTACH_F2")
	)
	(via
		(at 325.532496 -357.939086)
		(size 0.5588)
		(drill 0.3048)
		(layers "F.Cu" "B.Cu")
		(net "FANTACH_F2")
	)
	(segment
		(start 318.30391 -352.710496)
		(end 318.30391 -351.696782)
		(width 0.254)
		(layer "B.Cu")
		(net "FANTACH_F2")
	)
	(segment
		(start 321.75958 -356.166166)
		(end 318.30391 -352.710496)
		(width 0.254)
		(layer "B.Cu")
		(net "FANTACH_F2")
	)
	(segment
		(start 318.30391 -323.81571)
		(end 313.64555 -319.15735)
		(width 0.254)
		(layer "B.Cu")
		(net "FANTACH_F2")
	)
	(segment
		(start 325.532496 -357.939086)
		(end 323.759576 -356.166166)
		(width 0.254)
		(layer "B.Cu")
		(net "FANTACH_F2")
	)
	(segment
		(start 238.16183 -319.15735)
		(end 226.68484 -307.68036)
		(width 0.254)
		(layer "B.Cu")
		(net "FANTACH_F2")
	)
	(segment
		(start 323.759576 -356.166166)
		(end 321.75958 -356.166166)
		(width 0.254)
		(layer "B.Cu")
		(net "FANTACH_F2")
	)
	(segment
		(start 318.30391 -351.696782)
		(end 318.30391 -323.81571)
		(width 0.254)
		(layer "B.Cu")
		(net "FANTACH_F2")
	)
	(segment
		(start 313.64555 -319.15735)
		(end 238.16183 -319.15735)
		(width 0.254)
		(layer "B.Cu")
		(net "FANTACH_F2")
	)
	(segment
		(start 228.1936 -306.37988)
		(end 227.30841 -306.37988)
		(width 0.254)
		(layer "F.Cu")
		(net "FANTACH_F1")
	)
	(segment
		(start 225.29165 -306.297584)
		(end 225.02622 -306.563014)
		(width 0.254)
		(layer "F.Cu")
		(net "FANTACH_F1")
	)
	(segment
		(start 227.30841 -306.37988)
		(end 227.226114 -306.297584)
		(width 0.254)
		(layer "F.Cu")
		(net "FANTACH_F1")
	)
	(segment
		(start 134.1755 -372.618)
		(end 134.1755 -373.6086)
		(width 0.254)
		(layer "F.Cu")
		(net "FANTACH_F1")
	)
	(segment
		(start 134.1755 -371.5131)
		(end 134.1755 -372.618)
		(width 0.254)
		(layer "F.Cu")
		(net "FANTACH_F1")
	)
	(segment
		(start 305.031648 -352.997262)
		(end 319.579498 -352.997262)
		(width 0.254)
		(layer "F.Cu")
		(net "FANTACH_F1")
	)
	(segment
		(start 227.226114 -306.297584)
		(end 225.29165 -306.297584)
		(width 0.254)
		(layer "F.Cu")
		(net "FANTACH_F1")
	)
	(segment
		(start 134.1628 -371.5004)
		(end 134.1755 -371.5131)
		(width 0.254)
		(layer "F.Cu")
		(net "FANTACH_F1")
	)
	(segment
		(start 225.02622 -306.563014)
		(end 225.02622 -307.476398)
		(width 0.254)
		(layer "F.Cu")
		(net "FANTACH_F1")
	)
	(via
		(at 225.02622 -307.476398)
		(size 0.5588)
		(drill 0.3048)
		(layers "F.Cu" "B.Cu")
		(net "FANTACH_F1")
	)
	(via
		(at 134.1755 -373.6086)
		(size 0.5588)
		(drill 0.3048)
		(layers "F.Cu" "B.Cu")
		(net "FANTACH_F1")
	)
	(via
		(at 319.579498 -352.997262)
		(size 0.5588)
		(drill 0.3048)
		(layers "F.Cu" "B.Cu")
		(net "FANTACH_F1")
	)
	(via
		(at 221.7928 -307.0098)
		(size 0.6096)
		(drill 0.3048)
		(layers "F.Cu" "B.Cu")
		(net "FANTACH_F1")
	)
	(segment
		(start 84.00542 -364.9218)
		(end 44.138596 -364.9218)
		(width 0.254)
		(layer "B.Cu")
		(net "FANTACH_F1")
	)
	(segment
		(start 132.9436 -373.6086)
		(end 130.683 -371.348)
		(width 0.254)
		(layer "B.Cu")
		(net "FANTACH_F1")
	)
	(segment
		(start 226.054666 -307.476398)
		(end 225.02622 -307.476398)
		(width 0.254)
		(layer "B.Cu")
		(net "FANTACH_F1")
	)
	(segment
		(start 37.374068 -326.489822)
		(end 50.380646 -313.483244)
		(width 0.254)
		(layer "B.Cu")
		(net "FANTACH_F1")
	)
	(segment
		(start 130.683 -371.348)
		(end 90.43162 -371.348)
		(width 0.254)
		(layer "B.Cu")
		(net "FANTACH_F1")
	)
	(segment
		(start 217.004138 -307.0098)
		(end 221.7928 -307.0098)
		(width 0.254)
		(layer "B.Cu")
		(net "FANTACH_F1")
	)
	(segment
		(start 44.138596 -364.9218)
		(end 37.374068 -358.157272)
		(width 0.254)
		(layer "B.Cu")
		(net "FANTACH_F1")
	)
	(segment
		(start 313.856116 -318.64935)
		(end 239.756442 -318.64935)
		(width 0.254)
		(layer "B.Cu")
		(net "FANTACH_F1")
	)
	(segment
		(start 50.380646 -313.483244)
		(end 170.089322 -313.483244)
		(width 0.254)
		(layer "B.Cu")
		(net "FANTACH_F1")
	)
	(segment
		(start 183.166766 -300.4058)
		(end 210.400138 -300.4058)
		(width 0.254)
		(layer "B.Cu")
		(net "FANTACH_F1")
	)
	(segment
		(start 221.7928 -307.0098)
		(end 224.559622 -307.0098)
		(width 0.254)
		(layer "B.Cu")
		(net "FANTACH_F1")
	)
	(segment
		(start 228.190806 -307.083714)
		(end 226.44735 -307.083714)
		(width 0.254)
		(layer "B.Cu")
		(net "FANTACH_F1")
	)
	(segment
		(start 224.559622 -307.0098)
		(end 225.02622 -307.476398)
		(width 0.254)
		(layer "B.Cu")
		(net "FANTACH_F1")
	)
	(segment
		(start 239.756442 -318.64935)
		(end 228.190806 -307.083714)
		(width 0.254)
		(layer "B.Cu")
		(net "FANTACH_F1")
	)
	(segment
		(start 226.44735 -307.083714)
		(end 226.054666 -307.476398)
		(width 0.254)
		(layer "B.Cu")
		(net "FANTACH_F1")
	)
	(segment
		(start 319.579498 -324.372732)
		(end 313.856116 -318.64935)
		(width 0.254)
		(layer "B.Cu")
		(net "FANTACH_F1")
	)
	(segment
		(start 90.43162 -371.348)
		(end 84.00542 -364.9218)
		(width 0.254)
		(layer "B.Cu")
		(net "FANTACH_F1")
	)
	(segment
		(start 170.089322 -313.483244)
		(end 183.166766 -300.4058)
		(width 0.254)
		(layer "B.Cu")
		(net "FANTACH_F1")
	)
	(segment
		(start 319.579498 -352.997262)
		(end 319.579498 -324.372732)
		(width 0.254)
		(layer "B.Cu")
		(net "FANTACH_F1")
	)
	(segment
		(start 134.1755 -373.6086)
		(end 132.9436 -373.6086)
		(width 0.254)
		(layer "B.Cu")
		(net "FANTACH_F1")
	)
	(segment
		(start 37.374068 -358.157272)
		(end 37.374068 -326.489822)
		(width 0.254)
		(layer "B.Cu")
		(net "FANTACH_F1")
	)
	(segment
		(start 210.400138 -300.4058)
		(end 217.004138 -307.0098)
		(width 0.254)
		(layer "B.Cu")
		(net "FANTACH_F1")
	)
	(segment
		(start 35.210496 -365.3155)
		(end 35.210496 -364.236)
		(width 0.254)
		(layer "F.Cu")
		(net "FANTACH_F0")
	)
	(segment
		(start 33.101788 -364.239556)
		(end 33.105344 -364.236)
		(width 0.254)
		(layer "F.Cu")
		(net "FANTACH_F0")
	)
	(segment
		(start 226.2124 -305.0794)
		(end 226.187 -305.1048)
		(width 0.254)
		(layer "F.Cu")
		(net "FANTACH_F0")
	)
	(segment
		(start 228.1936 -305.0794)
		(end 226.2124 -305.0794)
		(width 0.254)
		(layer "F.Cu")
		(net "FANTACH_F0")
	)
	(segment
		(start 35.273996 -365.379)
		(end 35.210496 -365.3155)
		(width 0.254)
		(layer "F.Cu")
		(net "FANTACH_F0")
	)
	(segment
		(start 305.031648 -354.297742)
		(end 321.796156 -354.297742)
		(width 0.254)
		(layer "F.Cu")
		(net "FANTACH_F0")
	)
	(segment
		(start 33.105344 -364.236)
		(end 35.210496 -364.236)
		(width 0.254)
		(layer "F.Cu")
		(net "FANTACH_F0")
	)
	(via
		(at 226.187 -305.1048)
		(size 0.5588)
		(drill 0.3048)
		(layers "F.Cu" "B.Cu")
		(net "FANTACH_F0")
	)
	(via
		(at 33.101788 -364.239556)
		(size 0.5588)
		(drill 0.3048)
		(layers "F.Cu" "B.Cu")
		(net "FANTACH_F0")
	)
	(via
		(at 321.796156 -354.297742)
		(size 0.5588)
		(drill 0.3048)
		(layers "F.Cu" "B.Cu")
		(net "FANTACH_F0")
	)
	(via
		(at 30.605984 -357.009446)
		(size 0.6096)
		(drill 0.3048)
		(layers "F.Cu" "B.Cu")
		(net "FANTACH_F0")
	)
	(segment
		(start 211.303616 -298.8818)
		(end 217.526616 -305.1048)
		(width 0.254)
		(layer "B.Cu")
		(net "FANTACH_F0")
	)
	(segment
		(start 30.605984 -357.009446)
		(end 30.605984 -330.962762)
		(width 0.254)
		(layer "B.Cu")
		(net "FANTACH_F0")
	)
	(segment
		(start 50.037746 -311.531)
		(end 169.5196 -311.531)
		(width 0.254)
		(layer "B.Cu")
		(net "FANTACH_F0")
	)
	(segment
		(start 228.367844 -305.1048)
		(end 226.187 -305.1048)
		(width 0.254)
		(layer "B.Cu")
		(net "FANTACH_F0")
	)
	(segment
		(start 30.605984 -361.743752)
		(end 30.605984 -357.009446)
		(width 0.254)
		(layer "B.Cu")
		(net "FANTACH_F0")
	)
	(segment
		(start 314.487814 -317.12535)
		(end 240.388394 -317.12535)
		(width 0.254)
		(layer "B.Cu")
		(net "FANTACH_F0")
	)
	(segment
		(start 169.5196 -311.531)
		(end 182.1688 -298.8818)
		(width 0.254)
		(layer "B.Cu")
		(net "FANTACH_F0")
	)
	(segment
		(start 321.796156 -324.433692)
		(end 314.487814 -317.12535)
		(width 0.254)
		(layer "B.Cu")
		(net "FANTACH_F0")
	)
	(segment
		(start 182.1688 -298.8818)
		(end 211.303616 -298.8818)
		(width 0.254)
		(layer "B.Cu")
		(net "FANTACH_F0")
	)
	(segment
		(start 33.101788 -364.239556)
		(end 30.605984 -361.743752)
		(width 0.254)
		(layer "B.Cu")
		(net "FANTACH_F0")
	)
	(segment
		(start 240.388394 -317.12535)
		(end 228.367844 -305.1048)
		(width 0.254)
		(layer "B.Cu")
		(net "FANTACH_F0")
	)
	(segment
		(start 321.796156 -354.297742)
		(end 321.796156 -324.433692)
		(width 0.254)
		(layer "B.Cu")
		(net "FANTACH_F0")
	)
	(segment
		(start 30.605984 -330.962762)
		(end 50.037746 -311.531)
		(width 0.254)
		(layer "B.Cu")
		(net "FANTACH_F0")
	)
	(segment
		(start 217.526616 -305.1048)
		(end 226.187 -305.1048)
		(width 0.254)
		(layer "B.Cu")
		(net "FANTACH_F0")
	)
	(via
		(at 267.33119 -361.10672)
		(size 0.6604)
		(drill 0.3302)
		(layers "F.Cu" "B.Cu")
		(net "VCCP_IN")
	)
	(via
		(at 263.129522 -364.908846)
		(size 0.6604)
		(drill 0.3302)
		(layers "F.Cu" "B.Cu")
		(net "P3V3_IN_BIAS")
	)
	(via
		(at 263.377172 -353.463606)
		(size 0.6604)
		(drill 0.3302)
		(layers "F.Cu" "B.Cu")
		(net "MB3_CM_GATE_C")
	)
	(via
		(at 216.533222 -353.801172)
		(size 0.6604)
		(drill 0.3302)
		(layers "F.Cu" "B.Cu")
		(net "MB0_CM_GATE_C")
	)
	(segment
		(start 434.880004 -358.8004)
		(end 434.880004 -357.8098)
		(width 0.508)
		(layer "F.Cu")
		(net "GATE_FAN3_R")
	)
	(segment
		(start 441.026804 -359.4354)
		(end 440.722004 -359.7402)
		(width 0.508)
		(layer "F.Cu")
		(net "GATE_FAN3_R")
	)
	(segment
		(start 441.026804 -358.2924)
		(end 441.026804 -359.4354)
		(width 0.508)
		(layer "F.Cu")
		(net "GATE_FAN3_R")
	)
	(segment
		(start 434.205634 -357.9114)
		(end 433.737004 -357.9114)
		(width 0.508)
		(layer "F.Cu")
		(net "GATE_FAN3_R")
	)
	(segment
		(start 434.880004 -359.791)
		(end 435.870604 -359.791)
		(width 0.508)
		(layer "F.Cu")
		(net "GATE_FAN3_R")
	)
	(segment
		(start 434.880004 -359.791)
		(end 434.880004 -358.8004)
		(width 0.508)
		(layer "F.Cu")
		(net "GATE_FAN3_R")
	)
	(segment
		(start 433.127404 -356.0826)
		(end 433.737004 -356.6922)
		(width 0.508)
		(layer "F.Cu")
		(net "GATE_FAN3_R")
	)
	(segment
		(start 433.737004 -356.6922)
		(end 433.737004 -357.9114)
		(width 0.508)
		(layer "F.Cu")
		(net "GATE_FAN3_R")
	)
	(segment
		(start 432.213004 -356.0826)
		(end 433.127404 -356.0826)
		(width 0.508)
		(layer "F.Cu")
		(net "GATE_FAN3_R")
	)
	(segment
		(start 434.880004 -357.8098)
		(end 434.307234 -357.8098)
		(width 0.508)
		(layer "F.Cu")
		(net "GATE_FAN3_R")
	)
	(segment
		(start 434.307234 -357.8098)
		(end 434.205634 -357.9114)
		(width 0.508)
		(layer "F.Cu")
		(net "GATE_FAN3_R")
	)
	(via
		(at 435.870604 -359.791)
		(size 0.5588)
		(drill 0.3048)
		(layers "F.Cu" "B.Cu")
		(net "GATE_FAN3_R")
	)
	(via
		(at 434.880004 -358.8004)
		(size 0.6604)
		(drill 0.3302)
		(layers "F.Cu" "B.Cu")
		(net "GATE_FAN3_R")
	)
	(via
		(at 440.722004 -359.7402)
		(size 0.5588)
		(drill 0.3048)
		(layers "F.Cu" "B.Cu")
		(net "GATE_FAN3_R")
	)
	(segment
		(start 440.722004 -359.7402)
		(end 435.921404 -359.7402)
		(width 0.508)
		(layer "B.Cu")
		(net "GATE_FAN3_R")
	)
	(segment
		(start 435.921404 -359.7402)
		(end 435.870604 -359.791)
		(width 0.508)
		(layer "B.Cu")
		(net "GATE_FAN3_R")
	)
	(segment
		(start 342.4174 -359.537)
		(end 342.2396 -359.7148)
		(width 0.508)
		(layer "F.Cu")
		(net "GATE_FAN2_R")
	)
	(segment
		(start 342.4174 -358.3178)
		(end 342.4174 -359.537)
		(width 0.508)
		(layer "F.Cu")
		(net "GATE_FAN2_R")
	)
	(segment
		(start 333.629 -356.0826)
		(end 334.5434 -356.0826)
		(width 0.508)
		(layer "F.Cu")
		(net "GATE_FAN2_R")
	)
	(segment
		(start 336.296 -358.8004)
		(end 336.296 -359.791)
		(width 0.508)
		(layer "F.Cu")
		(net "GATE_FAN2_R")
	)
	(segment
		(start 334.5434 -356.0826)
		(end 335.153 -356.6922)
		(width 0.508)
		(layer "F.Cu")
		(net "GATE_FAN2_R")
	)
	(segment
		(start 336.296 -357.759)
		(end 336.2706 -357.7336)
		(width 0.508)
		(layer "F.Cu")
		(net "GATE_FAN2_R")
	)
	(segment
		(start 335.153 -356.6922)
		(end 335.153 -357.9114)
		(width 0.508)
		(layer "F.Cu")
		(net "GATE_FAN2_R")
	)
	(segment
		(start 336.296 -358.8004)
		(end 336.296 -357.759)
		(width 0.508)
		(layer "F.Cu")
		(net "GATE_FAN2_R")
	)
	(segment
		(start 335.8134 -357.7336)
		(end 335.6356 -357.9114)
		(width 0.508)
		(layer "F.Cu")
		(net "GATE_FAN2_R")
	)
	(segment
		(start 336.296 -359.791)
		(end 337.2866 -359.791)
		(width 0.508)
		(layer "F.Cu")
		(net "GATE_FAN2_R")
	)
	(segment
		(start 336.2706 -357.7336)
		(end 335.8134 -357.7336)
		(width 0.508)
		(layer "F.Cu")
		(net "GATE_FAN2_R")
	)
	(segment
		(start 335.6356 -357.9114)
		(end 335.153 -357.9114)
		(width 0.508)
		(layer "F.Cu")
		(net "GATE_FAN2_R")
	)
	(via
		(at 342.2396 -359.7148)
		(size 0.5588)
		(drill 0.3048)
		(layers "F.Cu" "B.Cu")
		(net "GATE_FAN2_R")
	)
	(via
		(at 337.2866 -359.791)
		(size 0.5588)
		(drill 0.3048)
		(layers "F.Cu" "B.Cu")
		(net "GATE_FAN2_R")
	)
	(via
		(at 336.296 -358.8004)
		(size 0.6604)
		(drill 0.3302)
		(layers "F.Cu" "B.Cu")
		(net "GATE_FAN2_R")
	)
	(segment
		(start 337.2866 -359.791)
		(end 342.1634 -359.791)
		(width 0.508)
		(layer "B.Cu")
		(net "GATE_FAN2_R")
	)
	(segment
		(start 342.1634 -359.791)
		(end 342.2396 -359.7148)
		(width 0.508)
		(layer "B.Cu")
		(net "GATE_FAN2_R")
	)
	(segment
		(start 127.761746 -366.869218)
		(end 127.77089 -366.860074)
		(width 0.508)
		(layer "F.Cu")
		(net "GATE_FAN1_R")
	)
	(segment
		(start 127.77089 -365.285274)
		(end 127.77089 -366.860074)
		(width 0.508)
		(layer "F.Cu")
		(net "GATE_FAN1_R")
	)
	(segment
		(start 127.761746 -367.838228)
		(end 127.761746 -366.869218)
		(width 0.508)
		(layer "F.Cu")
		(net "GATE_FAN1_R")
	)
	(via
		(at 129.057146 -365.69777)
		(size 0.6096)
		(drill 0.3048)
		(layers "F.Cu" "B.Cu")
		(net "GATE_FAN1_R")
	)
	(via
		(at 127.77089 -366.860074)
		(size 0.5588)
		(drill 0.3048)
		(layers "F.Cu" "B.Cu")
		(net "GATE_FAN1_R")
	)
	(segment
		(start 130.250184 -365.393732)
		(end 130.263646 -365.38027)
		(width 0.508)
		(layer "B.Cu")
		(net "GATE_FAN1_R")
	)
	(segment
		(start 130.250184 -366.349788)
		(end 130.250184 -365.393732)
		(width 0.508)
		(layer "B.Cu")
		(net "GATE_FAN1_R")
	)
	(segment
		(start 127.431546 -365.26597)
		(end 127.431546 -366.52073)
		(width 0.508)
		(layer "B.Cu")
		(net "GATE_FAN1_R")
	)
	(segment
		(start 128.55829 -365.69777)
		(end 128.12649 -365.26597)
		(width 0.508)
		(layer "B.Cu")
		(net "GATE_FAN1_R")
	)
	(segment
		(start 129.057146 -365.69777)
		(end 128.55829 -365.69777)
		(width 0.508)
		(layer "B.Cu")
		(net "GATE_FAN1_R")
	)
	(segment
		(start 130.263646 -365.38027)
		(end 129.374646 -365.38027)
		(width 0.508)
		(layer "B.Cu")
		(net "GATE_FAN1_R")
	)
	(segment
		(start 129.374646 -365.38027)
		(end 129.057146 -365.69777)
		(width 0.508)
		(layer "B.Cu")
		(net "GATE_FAN1_R")
	)
	(segment
		(start 127.431546 -366.52073)
		(end 127.77089 -366.860074)
		(width 0.508)
		(layer "B.Cu")
		(net "GATE_FAN1_R")
	)
	(segment
		(start 128.12649 -365.26597)
		(end 127.431546 -365.26597)
		(width 0.508)
		(layer "B.Cu")
		(net "GATE_FAN1_R")
	)
	(segment
		(start 53.180996 -359.6894)
		(end 53.180996 -359.7402)
		(width 0.508)
		(layer "F.Cu")
		(net "GATE_FAN0_R")
	)
	(segment
		(start 46.440852 -357.9114)
		(end 45.814996 -357.9114)
		(width 0.508)
		(layer "F.Cu")
		(net "GATE_FAN0_R")
	)
	(segment
		(start 47.796196 -359.791)
		(end 47.821596 -359.8164)
		(width 0.508)
		(layer "F.Cu")
		(net "GATE_FAN0_R")
	)
	(segment
		(start 45.814996 -356.6922)
		(end 45.814996 -357.9114)
		(width 0.508)
		(layer "F.Cu")
		(net "GATE_FAN0_R")
	)
	(segment
		(start 46.957996 -357.8352)
		(end 46.517052 -357.8352)
		(width 0.508)
		(layer "F.Cu")
		(net "GATE_FAN0_R")
	)
	(segment
		(start 45.205396 -356.0826)
		(end 45.814996 -356.6922)
		(width 0.508)
		(layer "F.Cu")
		(net "GATE_FAN0_R")
	)
	(segment
		(start 46.517052 -357.8352)
		(end 46.440852 -357.9114)
		(width 0.508)
		(layer "F.Cu")
		(net "GATE_FAN0_R")
	)
	(segment
		(start 53.130196 -359.6386)
		(end 53.180996 -359.6894)
		(width 0.508)
		(layer "F.Cu")
		(net "GATE_FAN0_R")
	)
	(segment
		(start 53.130196 -358.3432)
		(end 53.130196 -359.6386)
		(width 0.508)
		(layer "F.Cu")
		(net "GATE_FAN0_R")
	)
	(segment
		(start 46.957996 -359.791)
		(end 47.796196 -359.791)
		(width 0.508)
		(layer "F.Cu")
		(net "GATE_FAN0_R")
	)
	(segment
		(start 46.957996 -358.8004)
		(end 46.957996 -357.8352)
		(width 0.508)
		(layer "F.Cu")
		(net "GATE_FAN0_R")
	)
	(segment
		(start 44.290996 -356.0826)
		(end 45.205396 -356.0826)
		(width 0.508)
		(layer "F.Cu")
		(net "GATE_FAN0_R")
	)
	(segment
		(start 46.957996 -359.791)
		(end 46.957996 -358.8004)
		(width 0.508)
		(layer "F.Cu")
		(net "GATE_FAN0_R")
	)
	(via
		(at 53.180996 -359.7402)
		(size 0.5588)
		(drill 0.3048)
		(layers "F.Cu" "B.Cu")
		(net "GATE_FAN0_R")
	)
	(via
		(at 46.957996 -358.8004)
		(size 0.6604)
		(drill 0.3302)
		(layers "F.Cu" "B.Cu")
		(net "GATE_FAN0_R")
	)
	(via
		(at 47.821596 -359.8164)
		(size 0.5588)
		(drill 0.3048)
		(layers "F.Cu" "B.Cu")
		(net "GATE_FAN0_R")
	)
	(segment
		(start 47.923196 -359.7148)
		(end 47.821596 -359.8164)
		(width 0.508)
		(layer "B.Cu")
		(net "GATE_FAN0_R")
	)
	(segment
		(start 53.155596 -359.7148)
		(end 47.923196 -359.7148)
		(width 0.508)
		(layer "B.Cu")
		(net "GATE_FAN0_R")
	)
	(segment
		(start 53.180996 -359.7402)
		(end 53.155596 -359.7148)
		(width 0.508)
		(layer "B.Cu")
		(net "GATE_FAN0_R")
	)
	(segment
		(start 406.554178 -180.975)
		(end 406.554178 -209.458306)
		(width 0.254)
		(layer "F.Cu")
		(net "FLT_HDD9_N")
	)
	(segment
		(start 409.299664 -179.669694)
		(end 407.859484 -179.669694)
		(width 0.254)
		(layer "F.Cu")
		(net "FLT_HDD9_N")
	)
	(segment
		(start 406.554178 -209.458306)
		(end 406.554178 -213.8045)
		(width 0.254)
		(layer "F.Cu")
		(net "FLT_HDD9_N")
	)
	(segment
		(start 407.859484 -179.669694)
		(end 406.554178 -180.975)
		(width 0.254)
		(layer "F.Cu")
		(net "FLT_HDD9_N")
	)
	(via
		(at 406.554178 -209.458306)
		(size 0.6604)
		(drill 0.3302)
		(layers "F.Cu" "B.Cu")
		(net "FLT_HDD9_N")
	)
	(segment
		(start 375.004076 -210.285076)
		(end 375.0056 -210.2866)
		(width 0.254)
		(layer "F.Cu")
		(net "FLT_HDD8_N")
	)
	(segment
		(start 375.004076 -180.975)
		(end 375.004076 -210.285076)
		(width 0.254)
		(layer "F.Cu")
		(net "FLT_HDD8_N")
	)
	(segment
		(start 376.309382 -179.669694)
		(end 375.004076 -180.975)
		(width 0.254)
		(layer "F.Cu")
		(net "FLT_HDD8_N")
	)
	(segment
		(start 375.004076 -213.8045)
		(end 375.004076 -210.288124)
		(width 0.254)
		(layer "F.Cu")
		(net "FLT_HDD8_N")
	)
	(segment
		(start 375.004076 -210.288124)
		(end 375.0056 -210.2866)
		(width 0.254)
		(layer "F.Cu")
		(net "FLT_HDD8_N")
	)
	(segment
		(start 377.749562 -179.669694)
		(end 376.309382 -179.669694)
		(width 0.254)
		(layer "F.Cu")
		(net "FLT_HDD8_N")
	)
	(via
		(at 375.0056 -210.2866)
		(size 0.6604)
		(drill 0.3302)
		(layers "F.Cu" "B.Cu")
		(net "FLT_HDD8_N")
	)
	(segment
		(start 344.104468 -180.32476)
		(end 344.104468 -194.0814)
		(width 0.254)
		(layer "F.Cu")
		(net "FLT_HDD7_N")
	)
	(segment
		(start 343.454228 -213.8045)
		(end 343.454228 -207.210152)
		(width 0.254)
		(layer "F.Cu")
		(net "FLT_HDD7_N")
	)
	(segment
		(start 344.759534 -179.669694)
		(end 344.104468 -180.32476)
		(width 0.254)
		(layer "F.Cu")
		(net "FLT_HDD7_N")
	)
	(segment
		(start 346.199714 -179.669694)
		(end 344.759534 -179.669694)
		(width 0.254)
		(layer "F.Cu")
		(net "FLT_HDD7_N")
	)
	(segment
		(start 343.454228 -207.210152)
		(end 344.104468 -206.559912)
		(width 0.254)
		(layer "F.Cu")
		(net "FLT_HDD7_N")
	)
	(segment
		(start 344.104468 -206.559912)
		(end 344.104468 -194.0814)
		(width 0.254)
		(layer "F.Cu")
		(net "FLT_HDD7_N")
	)
	(via
		(at 344.104468 -194.0814)
		(size 0.6604)
		(drill 0.3302)
		(layers "F.Cu" "B.Cu")
		(net "FLT_HDD7_N")
	)
	(segment
		(start 313.496706 -179.669694)
		(end 313.09945 -180.06695)
		(width 0.254)
		(layer "F.Cu")
		(net "FLT_HDD6_N")
	)
	(segment
		(start 311.904126 -213.139274)
		(end 313.09945 -211.94395)
		(width 0.254)
		(layer "F.Cu")
		(net "FLT_HDD6_N")
	)
	(segment
		(start 314.649612 -179.669694)
		(end 313.496706 -179.669694)
		(width 0.254)
		(layer "F.Cu")
		(net "FLT_HDD6_N")
	)
	(segment
		(start 313.09945 -211.94395)
		(end 313.09945 -187.5282)
		(width 0.254)
		(layer "F.Cu")
		(net "FLT_HDD6_N")
	)
	(segment
		(start 313.09945 -180.06695)
		(end 313.09945 -187.5282)
		(width 0.254)
		(layer "F.Cu")
		(net "FLT_HDD6_N")
	)
	(segment
		(start 311.904126 -213.8045)
		(end 311.904126 -213.139274)
		(width 0.254)
		(layer "F.Cu")
		(net "FLT_HDD6_N")
	)
	(via
		(at 313.09945 -187.5282)
		(size 0.6604)
		(drill 0.3302)
		(layers "F.Cu" "B.Cu")
		(net "FLT_HDD6_N")
	)
	(segment
		(start 170.95724 -180.24856)
		(end 170.95724 -208.011522)
		(width 0.254)
		(layer "F.Cu")
		(net "FLT_HDD5_N")
	)
	(segment
		(start 170.307 -213.7537)
		(end 170.307 -210.722464)
		(width 0.254)
		(layer "F.Cu")
		(net "FLT_HDD5_N")
	)
	(segment
		(start 170.307 -208.661762)
		(end 170.307 -210.722464)
		(width 0.254)
		(layer "F.Cu")
		(net "FLT_HDD5_N")
	)
	(segment
		(start 170.95724 -208.011522)
		(end 170.307 -208.661762)
		(width 0.254)
		(layer "F.Cu")
		(net "FLT_HDD5_N")
	)
	(segment
		(start 175.049688 -179.669694)
		(end 171.536106 -179.669694)
		(width 0.254)
		(layer "F.Cu")
		(net "FLT_HDD5_N")
	)
	(segment
		(start 171.536106 -179.669694)
		(end 170.95724 -180.24856)
		(width 0.254)
		(layer "F.Cu")
		(net "FLT_HDD5_N")
	)
	(via
		(at 170.307 -210.722464)
		(size 0.6604)
		(drill 0.3302)
		(layers "F.Cu" "B.Cu")
		(net "FLT_HDD5_N")
	)
	(segment
		(start 147.186396 -202.380342)
		(end 147.186396 -178.386486)
		(width 0.254)
		(layer "F.Cu")
		(net "FLT_HDD4_N")
	)
	(segment
		(start 144.078706 -177.361596)
		(end 143.499586 -177.940716)
		(width 0.254)
		(layer "F.Cu")
		(net "FLT_HDD4_N")
	)
	(segment
		(start 147.186396 -178.386486)
		(end 146.161506 -177.361596)
		(width 0.254)
		(layer "F.Cu")
		(net "FLT_HDD4_N")
	)
	(segment
		(start 146.161506 -177.361596)
		(end 144.078706 -177.361596)
		(width 0.254)
		(layer "F.Cu")
		(net "FLT_HDD4_N")
	)
	(segment
		(start 143.499586 -177.940716)
		(end 143.499586 -179.669694)
		(width 0.254)
		(layer "F.Cu")
		(net "FLT_HDD4_N")
	)
	(segment
		(start 150.79472 -205.988666)
		(end 147.186396 -202.380342)
		(width 0.254)
		(layer "F.Cu")
		(net "FLT_HDD4_N")
	)
	(segment
		(start 150.79472 -210.1596)
		(end 150.79472 -205.988666)
		(width 0.254)
		(layer "F.Cu")
		(net "FLT_HDD4_N")
	)
	(segment
		(start 150.79472 -210.1596)
		(end 150.79472 -214.0585)
		(width 0.254)
		(layer "F.Cu")
		(net "FLT_HDD4_N")
	)
	(via
		(at 150.79472 -210.1596)
		(size 0.6604)
		(drill 0.3302)
		(layers "F.Cu" "B.Cu")
		(net "FLT_HDD4_N")
	)
	(segment
		(start 110.347506 -179.669694)
		(end 109.1184 -180.8988)
		(width 0.254)
		(layer "F.Cu")
		(net "FLT_HDD3_N")
	)
	(segment
		(start 111.949738 -179.669694)
		(end 110.347506 -179.669694)
		(width 0.254)
		(layer "F.Cu")
		(net "FLT_HDD3_N")
	)
	(segment
		(start 109.1184 -180.8988)
		(end 109.1184 -193.365374)
		(width 0.254)
		(layer "F.Cu")
		(net "FLT_HDD3_N")
	)
	(segment
		(start 109.1184 -193.365374)
		(end 109.1184 -213.7537)
		(width 0.254)
		(layer "F.Cu")
		(net "FLT_HDD3_N")
	)
	(via
		(at 109.1184 -193.365374)
		(size 0.6604)
		(drill 0.3302)
		(layers "F.Cu" "B.Cu")
		(net "FLT_HDD3_N")
	)
	(segment
		(start 472.399614 -64.66967)
		(end 471.24493 -64.66967)
		(width 0.254)
		(layer "F.Cu")
		(net "FLT_HDD23_N")
	)
	(segment
		(start 461.264 -91.73718)
		(end 470.464642 -82.536538)
		(width 0.254)
		(layer "F.Cu")
		(net "FLT_HDD23_N")
	)
	(segment
		(start 461.264 -98.8949)
		(end 461.264 -91.73718)
		(width 0.254)
		(layer "F.Cu")
		(net "FLT_HDD23_N")
	)
	(segment
		(start 471.24493 -64.66967)
		(end 470.464642 -65.449958)
		(width 0.254)
		(layer "F.Cu")
		(net "FLT_HDD23_N")
	)
	(segment
		(start 470.464642 -82.536538)
		(end 470.464642 -76.962)
		(width 0.254)
		(layer "F.Cu")
		(net "FLT_HDD23_N")
	)
	(segment
		(start 470.464642 -65.449958)
		(end 470.464642 -76.962)
		(width 0.254)
		(layer "F.Cu")
		(net "FLT_HDD23_N")
	)
	(via
		(at 470.464642 -76.962)
		(size 0.6604)
		(drill 0.3302)
		(layers "F.Cu" "B.Cu")
		(net "FLT_HDD23_N")
	)
	(segment
		(start 440.849512 -64.66967)
		(end 440.849512 -64.050672)
		(width 0.254)
		(layer "F.Cu")
		(net "FLT_HDD22_N")
	)
	(segment
		(start 444.054484 -91.273884)
		(end 448.002914 -95.222314)
		(width 0.254)
		(layer "F.Cu")
		(net "FLT_HDD22_N")
	)
	(segment
		(start 440.849512 -64.050672)
		(end 441.403232 -63.496952)
		(width 0.254)
		(layer "F.Cu")
		(net "FLT_HDD22_N")
	)
	(segment
		(start 444.054484 -64.686688)
		(end 444.054484 -91.273884)
		(width 0.254)
		(layer "F.Cu")
		(net "FLT_HDD22_N")
	)
	(segment
		(start 448.002914 -95.222314)
		(end 448.002914 -98.754438)
		(width 0.254)
		(layer "F.Cu")
		(net "FLT_HDD22_N")
	)
	(segment
		(start 441.403232 -63.496952)
		(end 442.864748 -63.496952)
		(width 0.254)
		(layer "F.Cu")
		(net "FLT_HDD22_N")
	)
	(segment
		(start 442.864748 -63.496952)
		(end 444.054484 -64.686688)
		(width 0.254)
		(layer "F.Cu")
		(net "FLT_HDD22_N")
	)
	(via
		(at 448.002914 -95.222314)
		(size 0.6604)
		(drill 0.3302)
		(layers "F.Cu" "B.Cu")
		(net "FLT_HDD22_N")
	)
	(segment
		(start 407.204418 -95.096838)
		(end 407.204418 -77.4192)
		(width 0.254)
		(layer "F.Cu")
		(net "FLT_HDD21_N")
	)
	(segment
		(start 407.204418 -65.324736)
		(end 407.204418 -77.4192)
		(width 0.254)
		(layer "F.Cu")
		(net "FLT_HDD21_N")
	)
	(segment
		(start 406.554178 -95.747078)
		(end 407.204418 -95.096838)
		(width 0.254)
		(layer "F.Cu")
		(net "FLT_HDD21_N")
	)
	(segment
		(start 407.859484 -64.66967)
		(end 407.204418 -65.324736)
		(width 0.254)
		(layer "F.Cu")
		(net "FLT_HDD21_N")
	)
	(segment
		(start 409.299664 -64.66967)
		(end 407.859484 -64.66967)
		(width 0.254)
		(layer "F.Cu")
		(net "FLT_HDD21_N")
	)
	(segment
		(start 406.554178 -98.804476)
		(end 406.554178 -95.747078)
		(width 0.254)
		(layer "F.Cu")
		(net "FLT_HDD21_N")
	)
	(via
		(at 407.204418 -77.4192)
		(size 0.6604)
		(drill 0.3302)
		(layers "F.Cu" "B.Cu")
		(net "FLT_HDD21_N")
	)
	(segment
		(start 375.004076 -97.457768)
		(end 375.654316 -96.807528)
		(width 0.254)
		(layer "F.Cu")
		(net "FLT_HDD20_N")
	)
	(segment
		(start 375.004076 -98.804476)
		(end 375.004076 -97.457768)
		(width 0.254)
		(layer "F.Cu")
		(net "FLT_HDD20_N")
	)
	(segment
		(start 376.309382 -64.66967)
		(end 375.654316 -65.324736)
		(width 0.254)
		(layer "F.Cu")
		(net "FLT_HDD20_N")
	)
	(segment
		(start 377.749562 -64.66967)
		(end 376.309382 -64.66967)
		(width 0.254)
		(layer "F.Cu")
		(net "FLT_HDD20_N")
	)
	(segment
		(start 375.654316 -96.807528)
		(end 375.654316 -76.0476)
		(width 0.254)
		(layer "F.Cu")
		(net "FLT_HDD20_N")
	)
	(segment
		(start 375.654316 -65.324736)
		(end 375.654316 -76.0476)
		(width 0.254)
		(layer "F.Cu")
		(net "FLT_HDD20_N")
	)
	(via
		(at 375.654316 -76.0476)
		(size 0.6604)
		(drill 0.3302)
		(layers "F.Cu" "B.Cu")
		(net "FLT_HDD20_N")
	)
	(segment
		(start 77.5716 -180.975)
		(end 77.5716 -194.251072)
		(width 0.254)
		(layer "F.Cu")
		(net "FLT_HDD2_N")
	)
	(segment
		(start 77.5716 -194.251072)
		(end 77.5716 -213.8045)
		(width 0.254)
		(layer "F.Cu")
		(net "FLT_HDD2_N")
	)
	(segment
		(start 80.399636 -179.669694)
		(end 78.876906 -179.669694)
		(width 0.254)
		(layer "F.Cu")
		(net "FLT_HDD2_N")
	)
	(segment
		(start 78.876906 -179.669694)
		(end 77.5716 -180.975)
		(width 0.254)
		(layer "F.Cu")
		(net "FLT_HDD2_N")
	)
	(via
		(at 77.5716 -194.251072)
		(size 0.6604)
		(drill 0.3302)
		(layers "F.Cu" "B.Cu")
		(net "FLT_HDD2_N")
	)
	(segment
		(start 346.199714 -64.66967)
		(end 345.24569 -64.66967)
		(width 0.254)
		(layer "F.Cu")
		(net "FLT_HDD19_N")
	)
	(segment
		(start 345.058492 -92.102686)
		(end 345.058492 -78.105)
		(width 0.254)
		(layer "F.Cu")
		(net "FLT_HDD19_N")
	)
	(segment
		(start 345.24569 -64.66967)
		(end 345.058492 -64.856868)
		(width 0.254)
		(layer "F.Cu")
		(net "FLT_HDD19_N")
	)
	(segment
		(start 343.454228 -93.70695)
		(end 345.058492 -92.102686)
		(width 0.254)
		(layer "F.Cu")
		(net "FLT_HDD19_N")
	)
	(segment
		(start 343.454228 -98.804476)
		(end 343.454228 -93.70695)
		(width 0.254)
		(layer "F.Cu")
		(net "FLT_HDD19_N")
	)
	(segment
		(start 345.058492 -64.856868)
		(end 345.058492 -78.105)
		(width 0.254)
		(layer "F.Cu")
		(net "FLT_HDD19_N")
	)
	(via
		(at 345.058492 -78.105)
		(size 0.6604)
		(drill 0.3302)
		(layers "F.Cu" "B.Cu")
		(net "FLT_HDD19_N")
	)
	(segment
		(start 320.30924 -64.81064)
		(end 320.30924 -76.2)
		(width 0.254)
		(layer "F.Cu")
		(net "FLT_HDD18_N")
	)
	(segment
		(start 315.7982 -62.9412)
		(end 318.4398 -62.9412)
		(width 0.254)
		(layer "F.Cu")
		(net "FLT_HDD18_N")
	)
	(segment
		(start 318.4398 -62.9412)
		(end 320.30924 -64.81064)
		(width 0.254)
		(layer "F.Cu")
		(net "FLT_HDD18_N")
	)
	(segment
		(start 323.545962 -88.39581)
		(end 320.30924 -85.159088)
		(width 0.254)
		(layer "F.Cu")
		(net "FLT_HDD18_N")
	)
	(segment
		(start 323.545962 -98.764598)
		(end 323.545962 -88.39581)
		(width 0.254)
		(layer "F.Cu")
		(net "FLT_HDD18_N")
	)
	(segment
		(start 314.649612 -64.66967)
		(end 314.649612 -64.089788)
		(width 0.254)
		(layer "F.Cu")
		(net "FLT_HDD18_N")
	)
	(segment
		(start 314.649612 -64.089788)
		(end 315.7982 -62.9412)
		(width 0.254)
		(layer "F.Cu")
		(net "FLT_HDD18_N")
	)
	(segment
		(start 320.30924 -85.159088)
		(end 320.30924 -76.2)
		(width 0.254)
		(layer "F.Cu")
		(net "FLT_HDD18_N")
	)
	(via
		(at 320.30924 -76.2)
		(size 0.6604)
		(drill 0.3302)
		(layers "F.Cu" "B.Cu")
		(net "FLT_HDD18_N")
	)
	(segment
		(start 168.9354 -65.913)
		(end 168.9354 -70.000622)
		(width 0.254)
		(layer "F.Cu")
		(net "FLT_HDD17_N")
	)
	(segment
		(start 174.987712 -64.607694)
		(end 170.240706 -64.607694)
		(width 0.254)
		(layer "F.Cu")
		(net "FLT_HDD17_N")
	)
	(segment
		(start 175.049688 -64.66967)
		(end 174.987712 -64.607694)
		(width 0.254)
		(layer "F.Cu")
		(net "FLT_HDD17_N")
	)
	(segment
		(start 170.240706 -64.607694)
		(end 168.9354 -65.913)
		(width 0.254)
		(layer "F.Cu")
		(net "FLT_HDD17_N")
	)
	(segment
		(start 168.9354 -70.000622)
		(end 168.9354 -98.7679)
		(width 0.254)
		(layer "F.Cu")
		(net "FLT_HDD17_N")
	)
	(via
		(at 168.9354 -70.000622)
		(size 0.6604)
		(drill 0.3302)
		(layers "F.Cu" "B.Cu")
		(net "FLT_HDD17_N")
	)
	(segment
		(start 140.7414 -65.9892)
		(end 140.7414 -74.7522)
		(width 0.254)
		(layer "F.Cu")
		(net "FLT_HDD16_N")
	)
	(segment
		(start 140.7414 -74.7522)
		(end 140.7414 -98.8187)
		(width 0.254)
		(layer "F.Cu")
		(net "FLT_HDD16_N")
	)
	(segment
		(start 143.485362 -64.683894)
		(end 142.046706 -64.683894)
		(width 0.254)
		(layer "F.Cu")
		(net "FLT_HDD16_N")
	)
	(segment
		(start 142.046706 -64.683894)
		(end 140.7414 -65.9892)
		(width 0.254)
		(layer "F.Cu")
		(net "FLT_HDD16_N")
	)
	(segment
		(start 143.499586 -64.66967)
		(end 143.485362 -64.683894)
		(width 0.254)
		(layer "F.Cu")
		(net "FLT_HDD16_N")
	)
	(via
		(at 140.7414 -74.7522)
		(size 0.6604)
		(drill 0.3302)
		(layers "F.Cu" "B.Cu")
		(net "FLT_HDD16_N")
	)
	(segment
		(start 110.43793 -64.66967)
		(end 109.1946 -65.913)
		(width 0.254)
		(layer "F.Cu")
		(net "FLT_HDD15_N")
	)
	(segment
		(start 111.949738 -64.66967)
		(end 110.43793 -64.66967)
		(width 0.254)
		(layer "F.Cu")
		(net "FLT_HDD15_N")
	)
	(segment
		(start 109.1946 -70.730872)
		(end 109.1946 -98.7679)
		(width 0.254)
		(layer "F.Cu")
		(net "FLT_HDD15_N")
	)
	(segment
		(start 109.1946 -65.913)
		(end 109.1946 -70.730872)
		(width 0.254)
		(layer "F.Cu")
		(net "FLT_HDD15_N")
	)
	(via
		(at 109.1946 -70.730872)
		(size 0.6604)
		(drill 0.3302)
		(layers "F.Cu" "B.Cu")
		(net "FLT_HDD15_N")
	)
	(segment
		(start 77.5716 -98.8187)
		(end 77.5716 -80.72755)
		(width 0.254)
		(layer "F.Cu")
		(net "FLT_HDD14_N")
	)
	(segment
		(start 78.89113 -64.66967)
		(end 77.5716 -65.9892)
		(width 0.254)
		(layer "F.Cu")
		(net "FLT_HDD14_N")
	)
	(segment
		(start 80.399636 -64.66967)
		(end 78.89113 -64.66967)
		(width 0.254)
		(layer "F.Cu")
		(net "FLT_HDD14_N")
	)
	(segment
		(start 77.5716 -65.9892)
		(end 77.5716 -80.72755)
		(width 0.254)
		(layer "F.Cu")
		(net "FLT_HDD14_N")
	)
	(via
		(at 77.5716 -80.72755)
		(size 0.6604)
		(drill 0.3302)
		(layers "F.Cu" "B.Cu")
		(net "FLT_HDD14_N")
	)
	(segment
		(start 46.75124 -86.75624)
		(end 46.75124 -76.2762)
		(width 0.254)
		(layer "F.Cu")
		(net "FLT_HDD13_N")
	)
	(segment
		(start 51.7398 -91.7448)
		(end 46.75124 -86.75624)
		(width 0.254)
		(layer "F.Cu")
		(net "FLT_HDD13_N")
	)
	(segment
		(start 47.34433 -64.66967)
		(end 46.75124 -65.26276)
		(width 0.254)
		(layer "F.Cu")
		(net "FLT_HDD13_N")
	)
	(segment
		(start 46.75124 -65.26276)
		(end 46.75124 -76.2762)
		(width 0.254)
		(layer "F.Cu")
		(net "FLT_HDD13_N")
	)
	(segment
		(start 48.849534 -64.66967)
		(end 47.34433 -64.66967)
		(width 0.254)
		(layer "F.Cu")
		(net "FLT_HDD13_N")
	)
	(segment
		(start 51.7398 -98.7679)
		(end 51.7398 -91.7448)
		(width 0.254)
		(layer "F.Cu")
		(net "FLT_HDD13_N")
	)
	(via
		(at 46.75124 -76.2762)
		(size 0.6604)
		(drill 0.3302)
		(layers "F.Cu" "B.Cu")
		(net "FLT_HDD13_N")
	)
	(segment
		(start 16.10233 -64.66967)
		(end 15.50924 -65.26276)
		(width 0.254)
		(layer "F.Cu")
		(net "FLT_HDD12_N")
	)
	(segment
		(start 15.50924 -65.26276)
		(end 15.50924 -92.240354)
		(width 0.254)
		(layer "F.Cu")
		(net "FLT_HDD12_N")
	)
	(segment
		(start 17.670018 -94.401132)
		(end 17.670018 -96.718374)
		(width 0.254)
		(layer "F.Cu")
		(net "FLT_HDD12_N")
	)
	(segment
		(start 17.299686 -64.66967)
		(end 16.10233 -64.66967)
		(width 0.254)
		(layer "F.Cu")
		(net "FLT_HDD12_N")
	)
	(segment
		(start 17.670018 -96.718374)
		(end 17.670018 -98.830384)
		(width 0.254)
		(layer "F.Cu")
		(net "FLT_HDD12_N")
	)
	(segment
		(start 15.50924 -92.240354)
		(end 17.670018 -94.401132)
		(width 0.254)
		(layer "F.Cu")
		(net "FLT_HDD12_N")
	)
	(via
		(at 17.670018 -96.718374)
		(size 0.6604)
		(drill 0.3302)
		(layers "F.Cu" "B.Cu")
		(net "FLT_HDD12_N")
	)
	(segment
		(start 469.654128 -180.975)
		(end 469.654128 -210.157822)
		(width 0.254)
		(layer "F.Cu")
		(net "FLT_HDD11_N")
	)
	(segment
		(start 472.399614 -179.669694)
		(end 470.959434 -179.669694)
		(width 0.254)
		(layer "F.Cu")
		(net "FLT_HDD11_N")
	)
	(segment
		(start 470.959434 -179.669694)
		(end 469.654128 -180.975)
		(width 0.254)
		(layer "F.Cu")
		(net "FLT_HDD11_N")
	)
	(segment
		(start 469.654128 -210.157822)
		(end 469.654128 -213.8045)
		(width 0.254)
		(layer "F.Cu")
		(net "FLT_HDD11_N")
	)
	(via
		(at 469.654128 -210.157822)
		(size 0.6604)
		(drill 0.3302)
		(layers "F.Cu" "B.Cu")
		(net "FLT_HDD11_N")
	)
	(segment
		(start 438.754266 -211.119974)
		(end 438.754266 -194.11569)
		(width 0.254)
		(layer "F.Cu")
		(net "FLT_HDD10_N")
	)
	(segment
		(start 438.754266 -180.142134)
		(end 438.754266 -194.11569)
		(width 0.254)
		(layer "F.Cu")
		(net "FLT_HDD10_N")
	)
	(segment
		(start 439.226706 -179.669694)
		(end 438.754266 -180.142134)
		(width 0.254)
		(layer "F.Cu")
		(net "FLT_HDD10_N")
	)
	(segment
		(start 440.849512 -179.669694)
		(end 439.226706 -179.669694)
		(width 0.254)
		(layer "F.Cu")
		(net "FLT_HDD10_N")
	)
	(segment
		(start 438.104026 -211.770214)
		(end 438.754266 -211.119974)
		(width 0.254)
		(layer "F.Cu")
		(net "FLT_HDD10_N")
	)
	(segment
		(start 438.104026 -213.8045)
		(end 438.104026 -211.770214)
		(width 0.254)
		(layer "F.Cu")
		(net "FLT_HDD10_N")
	)
	(via
		(at 438.754266 -194.11569)
		(size 0.6604)
		(drill 0.3302)
		(layers "F.Cu" "B.Cu")
		(net "FLT_HDD10_N")
	)
	(segment
		(start 48.849534 -179.669694)
		(end 47.025306 -179.669694)
		(width 0.254)
		(layer "F.Cu")
		(net "FLT_HDD1_N")
	)
	(segment
		(start 46.0248 -195.6816)
		(end 45.7962 -195.453)
		(width 0.254)
		(layer "F.Cu")
		(net "FLT_HDD1_N")
	)
	(segment
		(start 46.0248 -213.5759)
		(end 46.0248 -195.6816)
		(width 0.254)
		(layer "F.Cu")
		(net "FLT_HDD1_N")
	)
	(segment
		(start 45.7962 -213.8045)
		(end 46.0248 -213.5759)
		(width 0.254)
		(layer "F.Cu")
		(net "FLT_HDD1_N")
	)
	(segment
		(start 47.025306 -179.669694)
		(end 45.7962 -180.8988)
		(width 0.254)
		(layer "F.Cu")
		(net "FLT_HDD1_N")
	)
	(segment
		(start 45.7962 -180.8988)
		(end 45.7962 -195.453)
		(width 0.254)
		(layer "F.Cu")
		(net "FLT_HDD1_N")
	)
	(via
		(at 45.7962 -195.453)
		(size 0.6604)
		(drill 0.3302)
		(layers "F.Cu" "B.Cu")
		(net "FLT_HDD1_N")
	)
	(segment
		(start 14.5542 -190.896748)
		(end 14.5542 -213.8045)
		(width 0.254)
		(layer "F.Cu")
		(net "FLT_HDD0_N")
	)
	(segment
		(start 17.299686 -179.669694)
		(end 15.859506 -179.669694)
		(width 0.254)
		(layer "F.Cu")
		(net "FLT_HDD0_N")
	)
	(segment
		(start 15.859506 -179.669694)
		(end 14.5542 -180.975)
		(width 0.254)
		(layer "F.Cu")
		(net "FLT_HDD0_N")
	)
	(segment
		(start 14.5542 -180.975)
		(end 14.5542 -190.896748)
		(width 0.254)
		(layer "F.Cu")
		(net "FLT_HDD0_N")
	)
	(via
		(at 14.5542 -190.896748)
		(size 0.6604)
		(drill 0.3302)
		(layers "F.Cu" "B.Cu")
		(net "FLT_HDD0_N")
	)
	(segment
		(start 405.792178 -205.8924)
		(end 405.792178 -193.838576)
		(width 0.254)
		(layer "F.Cu")
		(net "DRV_ACT_9_N")
	)
	(segment
		(start 410.300424 -178.549046)
		(end 409.983178 -178.2318)
		(width 0.254)
		(layer "F.Cu")
		(net "DRV_ACT_9_N")
	)
	(segment
		(start 401.891246 -214.860378)
		(end 401.891246 -209.793332)
		(width 0.254)
		(layer "F.Cu")
		(net "DRV_ACT_9_N")
	)
	(segment
		(start 405.792178 -180.3654)
		(end 405.792178 -193.838576)
		(width 0.254)
		(layer "F.Cu")
		(net "DRV_ACT_9_N")
	)
	(segment
		(start 409.983178 -178.2318)
		(end 407.925778 -178.2318)
		(width 0.254)
		(layer "F.Cu")
		(net "DRV_ACT_9_N")
	)
	(segment
		(start 407.925778 -178.2318)
		(end 405.792178 -180.3654)
		(width 0.254)
		(layer "F.Cu")
		(net "DRV_ACT_9_N")
	)
	(segment
		(start 410.300424 -179.669694)
		(end 410.300424 -178.549046)
		(width 0.254)
		(layer "F.Cu")
		(net "DRV_ACT_9_N")
	)
	(segment
		(start 401.891246 -209.793332)
		(end 405.792178 -205.8924)
		(width 0.254)
		(layer "F.Cu")
		(net "DRV_ACT_9_N")
	)
	(via
		(at 405.792178 -193.838576)
		(size 0.6604)
		(drill 0.3302)
		(layers "F.Cu" "B.Cu")
		(net "DRV_ACT_9_N")
	)
	(segment
		(start 370.341144 -214.860378)
		(end 370.341144 -209.735928)
		(width 0.254)
		(layer "F.Cu")
		(net "DRV_ACT_8_N")
	)
	(segment
		(start 376.528076 -178.0794)
		(end 374.242076 -180.3654)
		(width 0.254)
		(layer "F.Cu")
		(net "DRV_ACT_8_N")
	)
	(segment
		(start 378.280676 -178.0794)
		(end 376.528076 -178.0794)
		(width 0.254)
		(layer "F.Cu")
		(net "DRV_ACT_8_N")
	)
	(segment
		(start 378.750322 -179.669694)
		(end 378.750322 -178.549046)
		(width 0.254)
		(layer "F.Cu")
		(net "DRV_ACT_8_N")
	)
	(segment
		(start 378.750322 -178.549046)
		(end 378.280676 -178.0794)
		(width 0.254)
		(layer "F.Cu")
		(net "DRV_ACT_8_N")
	)
	(segment
		(start 370.398548 -209.735928)
		(end 372.108476 -208.026)
		(width 0.254)
		(layer "F.Cu")
		(net "DRV_ACT_8_N")
	)
	(segment
		(start 374.242076 -205.8924)
		(end 372.108476 -208.026)
		(width 0.254)
		(layer "F.Cu")
		(net "DRV_ACT_8_N")
	)
	(segment
		(start 374.242076 -180.3654)
		(end 374.242076 -205.8924)
		(width 0.254)
		(layer "F.Cu")
		(net "DRV_ACT_8_N")
	)
	(segment
		(start 370.341144 -209.735928)
		(end 370.398548 -209.735928)
		(width 0.254)
		(layer "F.Cu")
		(net "DRV_ACT_8_N")
	)
	(via
		(at 372.108476 -208.026)
		(size 0.6604)
		(drill 0.3302)
		(layers "F.Cu" "B.Cu")
		(net "DRV_ACT_8_N")
	)
	(segment
		(start 343.149428 -179.9082)
		(end 343.149428 -187.3758)
		(width 0.254)
		(layer "F.Cu")
		(net "DRV_ACT_7_N")
	)
	(segment
		(start 338.791296 -214.860378)
		(end 338.791296 -209.793332)
		(width 0.254)
		(layer "F.Cu")
		(net "DRV_ACT_7_N")
	)
	(segment
		(start 346.730828 -178.0794)
		(end 344.978228 -178.0794)
		(width 0.254)
		(layer "F.Cu")
		(net "DRV_ACT_7_N")
	)
	(segment
		(start 344.978228 -178.0794)
		(end 343.149428 -179.9082)
		(width 0.254)
		(layer "F.Cu")
		(net "DRV_ACT_7_N")
	)
	(segment
		(start 343.149428 -205.4352)
		(end 343.149428 -187.3758)
		(width 0.254)
		(layer "F.Cu")
		(net "DRV_ACT_7_N")
	)
	(segment
		(start 347.200474 -178.549046)
		(end 346.730828 -178.0794)
		(width 0.254)
		(layer "F.Cu")
		(net "DRV_ACT_7_N")
	)
	(segment
		(start 338.791296 -209.793332)
		(end 343.149428 -205.4352)
		(width 0.254)
		(layer "F.Cu")
		(net "DRV_ACT_7_N")
	)
	(segment
		(start 347.200474 -179.669694)
		(end 347.200474 -178.549046)
		(width 0.254)
		(layer "F.Cu")
		(net "DRV_ACT_7_N")
	)
	(via
		(at 343.149428 -187.3758)
		(size 0.6604)
		(drill 0.3302)
		(layers "F.Cu" "B.Cu")
		(net "DRV_ACT_7_N")
	)
	(segment
		(start 307.241194 -209.793332)
		(end 309.008526 -208.026)
		(width 0.254)
		(layer "F.Cu")
		(net "DRV_ACT_6_N")
	)
	(segment
		(start 312.33745 -204.697076)
		(end 309.008526 -208.026)
		(width 0.254)
		(layer "F.Cu")
		(net "DRV_ACT_6_N")
	)
	(segment
		(start 315.650372 -178.549046)
		(end 315.180726 -178.0794)
		(width 0.254)
		(layer "F.Cu")
		(net "DRV_ACT_6_N")
	)
	(segment
		(start 315.650372 -179.669694)
		(end 315.650372 -178.549046)
		(width 0.254)
		(layer "F.Cu")
		(net "DRV_ACT_6_N")
	)
	(segment
		(start 315.180726 -178.0794)
		(end 313.428126 -178.0794)
		(width 0.254)
		(layer "F.Cu")
		(net "DRV_ACT_6_N")
	)
	(segment
		(start 312.33745 -179.170076)
		(end 312.33745 -204.697076)
		(width 0.254)
		(layer "F.Cu")
		(net "DRV_ACT_6_N")
	)
	(segment
		(start 307.241194 -214.860378)
		(end 307.241194 -209.793332)
		(width 0.254)
		(layer "F.Cu")
		(net "DRV_ACT_6_N")
	)
	(segment
		(start 313.428126 -178.0794)
		(end 312.33745 -179.170076)
		(width 0.254)
		(layer "F.Cu")
		(net "DRV_ACT_6_N")
	)
	(via
		(at 309.008526 -208.026)
		(size 0.6604)
		(drill 0.3302)
		(layers "F.Cu" "B.Cu")
		(net "DRV_ACT_6_N")
	)
	(segment
		(start 170.0022 -179.832)
		(end 170.0022 -203.1238)
		(width 0.254)
		(layer "F.Cu")
		(net "DRV_ACT_5_N")
	)
	(segment
		(start 175.3743 -178.5747)
		(end 171.2595 -178.5747)
		(width 0.254)
		(layer "F.Cu")
		(net "DRV_ACT_5_N")
	)
	(segment
		(start 165.644068 -214.784178)
		(end 165.644068 -208.893664)
		(width 0.254)
		(layer "F.Cu")
		(net "DRV_ACT_5_N")
	)
	(segment
		(start 176.050448 -179.250848)
		(end 175.3743 -178.5747)
		(width 0.254)
		(layer "F.Cu")
		(net "DRV_ACT_5_N")
	)
	(segment
		(start 171.2595 -178.5747)
		(end 170.0022 -179.832)
		(width 0.254)
		(layer "F.Cu")
		(net "DRV_ACT_5_N")
	)
	(segment
		(start 176.050448 -179.669694)
		(end 176.050448 -179.250848)
		(width 0.254)
		(layer "F.Cu")
		(net "DRV_ACT_5_N")
	)
	(segment
		(start 165.644068 -207.481932)
		(end 165.644068 -208.893664)
		(width 0.254)
		(layer "F.Cu")
		(net "DRV_ACT_5_N")
	)
	(segment
		(start 170.0022 -203.1238)
		(end 165.644068 -207.481932)
		(width 0.254)
		(layer "F.Cu")
		(net "DRV_ACT_5_N")
	)
	(via
		(at 165.644068 -208.893664)
		(size 0.6604)
		(drill 0.3302)
		(layers "F.Cu" "B.Cu")
		(net "DRV_ACT_5_N")
	)
	(segment
		(start 144.500346 -178.76774)
		(end 144.500346 -179.669694)
		(width 0.254)
		(layer "F.Cu")
		(net "DRV_ACT_4_N")
	)
	(segment
		(start 146.087592 -210.28914)
		(end 146.087592 -178.871372)
		(width 0.254)
		(layer "F.Cu")
		(net "DRV_ACT_4_N")
	)
	(segment
		(start 145.696432 -178.480212)
		(end 144.787874 -178.480212)
		(width 0.254)
		(layer "F.Cu")
		(net "DRV_ACT_4_N")
	)
	(segment
		(start 146.087592 -214.91702)
		(end 146.087592 -210.28914)
		(width 0.254)
		(layer "F.Cu")
		(net "DRV_ACT_4_N")
	)
	(segment
		(start 144.787874 -178.480212)
		(end 144.500346 -178.76774)
		(width 0.254)
		(layer "F.Cu")
		(net "DRV_ACT_4_N")
	)
	(segment
		(start 146.087592 -178.871372)
		(end 145.696432 -178.480212)
		(width 0.254)
		(layer "F.Cu")
		(net "DRV_ACT_4_N")
	)
	(via
		(at 146.087592 -210.28914)
		(size 0.6604)
		(drill 0.3302)
		(layers "F.Cu" "B.Cu")
		(net "DRV_ACT_4_N")
	)
	(segment
		(start 108.16336 -180.48224)
		(end 108.16336 -205.27264)
		(width 0.254)
		(layer "F.Cu")
		(net "DRV_ACT_3_N")
	)
	(segment
		(start 112.950498 -178.711098)
		(end 112.395 -178.1556)
		(width 0.254)
		(layer "F.Cu")
		(net "DRV_ACT_3_N")
	)
	(segment
		(start 104.455468 -214.784178)
		(end 104.455468 -208.980532)
		(width 0.254)
		(layer "F.Cu")
		(net "DRV_ACT_3_N")
	)
	(segment
		(start 108.16336 -205.27264)
		(end 105.41 -208.026)
		(width 0.254)
		(layer "F.Cu")
		(net "DRV_ACT_3_N")
	)
	(segment
		(start 104.455468 -208.980532)
		(end 105.41 -208.026)
		(width 0.254)
		(layer "F.Cu")
		(net "DRV_ACT_3_N")
	)
	(segment
		(start 112.395 -178.1556)
		(end 110.49 -178.1556)
		(width 0.254)
		(layer "F.Cu")
		(net "DRV_ACT_3_N")
	)
	(segment
		(start 110.49 -178.1556)
		(end 108.16336 -180.48224)
		(width 0.254)
		(layer "F.Cu")
		(net "DRV_ACT_3_N")
	)
	(segment
		(start 112.950498 -179.669694)
		(end 112.950498 -178.711098)
		(width 0.254)
		(layer "F.Cu")
		(net "DRV_ACT_3_N")
	)
	(via
		(at 105.41 -208.026)
		(size 0.6604)
		(drill 0.3302)
		(layers "F.Cu" "B.Cu")
		(net "DRV_ACT_3_N")
	)
	(segment
		(start 456.601068 -99.950778)
		(end 456.601068 -94.629732)
		(width 0.254)
		(layer "F.Cu")
		(net "DRV_ACT_23_N")
	)
	(segment
		(start 469.3158 -81.915)
		(end 458.3684 -92.8624)
		(width 0.254)
		(layer "F.Cu")
		(net "DRV_ACT_23_N")
	)
	(segment
		(start 473.400374 -64.66967)
		(end 473.400374 -63.977774)
		(width 0.254)
		(layer "F.Cu")
		(net "DRV_ACT_23_N")
	)
	(segment
		(start 473.400374 -63.977774)
		(end 472.9734 -63.5508)
		(width 0.254)
		(layer "F.Cu")
		(net "DRV_ACT_23_N")
	)
	(segment
		(start 456.601068 -94.629732)
		(end 458.3684 -92.8624)
		(width 0.254)
		(layer "F.Cu")
		(net "DRV_ACT_23_N")
	)
	(segment
		(start 469.3158 -65.4558)
		(end 469.3158 -81.915)
		(width 0.254)
		(layer "F.Cu")
		(net "DRV_ACT_23_N")
	)
	(segment
		(start 471.2208 -63.5508)
		(end 469.3158 -65.4558)
		(width 0.254)
		(layer "F.Cu")
		(net "DRV_ACT_23_N")
	)
	(segment
		(start 472.9734 -63.5508)
		(end 471.2208 -63.5508)
		(width 0.254)
		(layer "F.Cu")
		(net "DRV_ACT_23_N")
	)
	(via
		(at 458.3684 -92.8624)
		(size 0.6604)
		(drill 0.3302)
		(layers "F.Cu" "B.Cu")
		(net "DRV_ACT_23_N")
	)
	(segment
		(start 443.034166 -91.862402)
		(end 443.034166 -65.044574)
		(width 0.254)
		(layer "F.Cu")
		(net "DRV_ACT_22_N")
	)
	(segment
		(start 444.4111 -93.239336)
		(end 443.034166 -91.862402)
		(width 0.254)
		(layer "F.Cu")
		(net "DRV_ACT_22_N")
	)
	(segment
		(start 444.4111 -95.720916)
		(end 444.4111 -95.796862)
		(width 0.254)
		(layer "F.Cu")
		(net "DRV_ACT_22_N")
	)
	(segment
		(start 443.034166 -65.044574)
		(end 442.659262 -64.66967)
		(width 0.254)
		(layer "F.Cu")
		(net "DRV_ACT_22_N")
	)
	(segment
		(start 444.4111 -95.720916)
		(end 444.4111 -93.239336)
		(width 0.254)
		(layer "F.Cu")
		(net "DRV_ACT_22_N")
	)
	(segment
		(start 444.407036 -95.800926)
		(end 444.407036 -98.753422)
		(width 0.254)
		(layer "F.Cu")
		(net "DRV_ACT_22_N")
	)
	(segment
		(start 442.659262 -64.66967)
		(end 441.850272 -64.66967)
		(width 0.254)
		(layer "F.Cu")
		(net "DRV_ACT_22_N")
	)
	(segment
		(start 444.4111 -95.796862)
		(end 444.407036 -95.800926)
		(width 0.254)
		(layer "F.Cu")
		(net "DRV_ACT_22_N")
	)
	(via
		(at 444.4111 -95.720916)
		(size 0.6604)
		(drill 0.3302)
		(layers "F.Cu" "B.Cu")
		(net "DRV_ACT_22_N")
	)
	(segment
		(start 406.249378 -64.908176)
		(end 406.249378 -90.435176)
		(width 0.254)
		(layer "F.Cu")
		(net "DRV_ACT_21_N")
	)
	(segment
		(start 410.300424 -63.549022)
		(end 409.830778 -63.079376)
		(width 0.254)
		(layer "F.Cu")
		(net "DRV_ACT_21_N")
	)
	(segment
		(start 409.830778 -63.079376)
		(end 408.078178 -63.079376)
		(width 0.254)
		(layer "F.Cu")
		(net "DRV_ACT_21_N")
	)
	(segment
		(start 401.891246 -94.793308)
		(end 403.658578 -93.025976)
		(width 0.254)
		(layer "F.Cu")
		(net "DRV_ACT_21_N")
	)
	(segment
		(start 410.300424 -64.66967)
		(end 410.300424 -63.549022)
		(width 0.254)
		(layer "F.Cu")
		(net "DRV_ACT_21_N")
	)
	(segment
		(start 401.891246 -99.860354)
		(end 401.891246 -94.793308)
		(width 0.254)
		(layer "F.Cu")
		(net "DRV_ACT_21_N")
	)
	(segment
		(start 408.078178 -63.079376)
		(end 406.249378 -64.908176)
		(width 0.254)
		(layer "F.Cu")
		(net "DRV_ACT_21_N")
	)
	(segment
		(start 406.249378 -90.435176)
		(end 403.658578 -93.025976)
		(width 0.254)
		(layer "F.Cu")
		(net "DRV_ACT_21_N")
	)
	(via
		(at 403.658578 -93.025976)
		(size 0.6604)
		(drill 0.3302)
		(layers "F.Cu" "B.Cu")
		(net "DRV_ACT_21_N")
	)
	(segment
		(start 374.699276 -64.908176)
		(end 374.699276 -90.435176)
		(width 0.254)
		(layer "F.Cu")
		(net "DRV_ACT_20_N")
	)
	(segment
		(start 378.750322 -63.549022)
		(end 378.280676 -63.079376)
		(width 0.254)
		(layer "F.Cu")
		(net "DRV_ACT_20_N")
	)
	(segment
		(start 374.699276 -90.435176)
		(end 372.108476 -93.025976)
		(width 0.254)
		(layer "F.Cu")
		(net "DRV_ACT_20_N")
	)
	(segment
		(start 376.528076 -63.079376)
		(end 374.699276 -64.908176)
		(width 0.254)
		(layer "F.Cu")
		(net "DRV_ACT_20_N")
	)
	(segment
		(start 378.280676 -63.079376)
		(end 376.528076 -63.079376)
		(width 0.254)
		(layer "F.Cu")
		(net "DRV_ACT_20_N")
	)
	(segment
		(start 370.341144 -99.860354)
		(end 370.341144 -94.793308)
		(width 0.254)
		(layer "F.Cu")
		(net "DRV_ACT_20_N")
	)
	(segment
		(start 370.341144 -94.793308)
		(end 372.108476 -93.025976)
		(width 0.254)
		(layer "F.Cu")
		(net "DRV_ACT_20_N")
	)
	(segment
		(start 378.750322 -64.66967)
		(end 378.750322 -63.549022)
		(width 0.254)
		(layer "F.Cu")
		(net "DRV_ACT_20_N")
	)
	(via
		(at 372.108476 -93.025976)
		(size 0.6604)
		(drill 0.3302)
		(layers "F.Cu" "B.Cu")
		(net "DRV_ACT_20_N")
	)
	(segment
		(start 72.908668 -214.860378)
		(end 72.908668 -209.793332)
		(width 0.254)
		(layer "F.Cu")
		(net "DRV_ACT_2_N")
	)
	(segment
		(start 76.61656 -206.08544)
		(end 74.676 -208.026)
		(width 0.254)
		(layer "F.Cu")
		(net "DRV_ACT_2_N")
	)
	(segment
		(start 76.61656 -180.55844)
		(end 76.61656 -206.08544)
		(width 0.254)
		(layer "F.Cu")
		(net "DRV_ACT_2_N")
	)
	(segment
		(start 80.8482 -178.0794)
		(end 79.0956 -178.0794)
		(width 0.254)
		(layer "F.Cu")
		(net "DRV_ACT_2_N")
	)
	(segment
		(start 81.400396 -178.631596)
		(end 80.8482 -178.0794)
		(width 0.254)
		(layer "F.Cu")
		(net "DRV_ACT_2_N")
	)
	(segment
		(start 72.908668 -209.793332)
		(end 74.676 -208.026)
		(width 0.254)
		(layer "F.Cu")
		(net "DRV_ACT_2_N")
	)
	(segment
		(start 79.0956 -178.0794)
		(end 76.61656 -180.55844)
		(width 0.254)
		(layer "F.Cu")
		(net "DRV_ACT_2_N")
	)
	(segment
		(start 81.400396 -179.669694)
		(end 81.400396 -178.631596)
		(width 0.254)
		(layer "F.Cu")
		(net "DRV_ACT_2_N")
	)
	(via
		(at 74.676 -208.026)
		(size 0.6604)
		(drill 0.3302)
		(layers "F.Cu" "B.Cu")
		(net "DRV_ACT_2_N")
	)
	(segment
		(start 346.730828 -63.079376)
		(end 345.124024 -63.079376)
		(width 0.254)
		(layer "F.Cu")
		(net "DRV_ACT_19_N")
	)
	(segment
		(start 344.296492 -63.906908)
		(end 344.296492 -89.233502)
		(width 0.254)
		(layer "F.Cu")
		(net "DRV_ACT_19_N")
	)
	(segment
		(start 338.791296 -99.860354)
		(end 338.791296 -94.738698)
		(width 0.254)
		(layer "F.Cu")
		(net "DRV_ACT_19_N")
	)
	(segment
		(start 344.296492 -89.233502)
		(end 341.09152 -92.438474)
		(width 0.254)
		(layer "F.Cu")
		(net "DRV_ACT_19_N")
	)
	(segment
		(start 347.200474 -63.549022)
		(end 346.730828 -63.079376)
		(width 0.254)
		(layer "F.Cu")
		(net "DRV_ACT_19_N")
	)
	(segment
		(start 347.200474 -64.66967)
		(end 347.200474 -63.549022)
		(width 0.254)
		(layer "F.Cu")
		(net "DRV_ACT_19_N")
	)
	(segment
		(start 345.124024 -63.079376)
		(end 344.296492 -63.906908)
		(width 0.254)
		(layer "F.Cu")
		(net "DRV_ACT_19_N")
	)
	(segment
		(start 338.791296 -94.738698)
		(end 341.09152 -92.438474)
		(width 0.254)
		(layer "F.Cu")
		(net "DRV_ACT_19_N")
	)
	(via
		(at 341.09152 -92.438474)
		(size 0.6604)
		(drill 0.3302)
		(layers "F.Cu" "B.Cu")
		(net "DRV_ACT_19_N")
	)
	(segment
		(start 315.650372 -64.66967)
		(end 318.18707 -64.66967)
		(width 0.254)
		(layer "F.Cu")
		(net "DRV_ACT_18_N")
	)
	(segment
		(start 318.18707 -64.66967)
		(end 319.278 -65.7606)
		(width 0.254)
		(layer "F.Cu")
		(net "DRV_ACT_18_N")
	)
	(segment
		(start 319.278 -65.7606)
		(end 319.278 -90.297)
		(width 0.254)
		(layer "F.Cu")
		(net "DRV_ACT_18_N")
	)
	(segment
		(start 318.88303 -93.51137)
		(end 319.278 -93.1164)
		(width 0.254)
		(layer "F.Cu")
		(net "DRV_ACT_18_N")
	)
	(segment
		(start 318.88303 -99.820476)
		(end 318.88303 -93.51137)
		(width 0.254)
		(layer "F.Cu")
		(net "DRV_ACT_18_N")
	)
	(segment
		(start 319.278 -93.1164)
		(end 319.278 -90.297)
		(width 0.254)
		(layer "F.Cu")
		(net "DRV_ACT_18_N")
	)
	(via
		(at 319.278 -90.297)
		(size 0.6604)
		(drill 0.3302)
		(layers "F.Cu" "B.Cu")
		(net "DRV_ACT_18_N")
	)
	(segment
		(start 164.272468 -99.798378)
		(end 164.272468 -94.731332)
		(width 0.254)
		(layer "F.Cu")
		(net "DRV_ACT_17_N")
	)
	(segment
		(start 167.98036 -91.02344)
		(end 166.0398 -92.964)
		(width 0.254)
		(layer "F.Cu")
		(net "DRV_ACT_17_N")
	)
	(segment
		(start 164.272468 -94.731332)
		(end 166.0398 -92.964)
		(width 0.254)
		(layer "F.Cu")
		(net "DRV_ACT_17_N")
	)
	(segment
		(start 175.641 -63.4746)
		(end 170.0022 -63.4746)
		(width 0.254)
		(layer "F.Cu")
		(net "DRV_ACT_17_N")
	)
	(segment
		(start 167.98036 -65.49644)
		(end 167.98036 -91.02344)
		(width 0.254)
		(layer "F.Cu")
		(net "DRV_ACT_17_N")
	)
	(segment
		(start 176.050448 -64.66967)
		(end 176.050448 -63.884048)
		(width 0.254)
		(layer "F.Cu")
		(net "DRV_ACT_17_N")
	)
	(segment
		(start 176.050448 -63.884048)
		(end 175.641 -63.4746)
		(width 0.254)
		(layer "F.Cu")
		(net "DRV_ACT_17_N")
	)
	(segment
		(start 170.0022 -63.4746)
		(end 167.98036 -65.49644)
		(width 0.254)
		(layer "F.Cu")
		(net "DRV_ACT_17_N")
	)
	(via
		(at 166.0398 -92.964)
		(size 0.6604)
		(drill 0.3302)
		(layers "F.Cu" "B.Cu")
		(net "DRV_ACT_17_N")
	)
	(segment
		(start 136.078468 -99.874578)
		(end 136.078468 -69.280532)
		(width 0.254)
		(layer "F.Cu")
		(net "DRV_ACT_16_N")
	)
	(segment
		(start 141.8844 -63.4746)
		(end 136.32561 -69.03339)
		(width 0.254)
		(layer "F.Cu")
		(net "DRV_ACT_16_N")
	)
	(segment
		(start 144.500346 -63.956946)
		(end 144.018 -63.4746)
		(width 0.254)
		(layer "F.Cu")
		(net "DRV_ACT_16_N")
	)
	(segment
		(start 144.018 -63.4746)
		(end 141.8844 -63.4746)
		(width 0.254)
		(layer "F.Cu")
		(net "DRV_ACT_16_N")
	)
	(segment
		(start 136.078468 -69.280532)
		(end 136.32561 -69.03339)
		(width 0.254)
		(layer "F.Cu")
		(net "DRV_ACT_16_N")
	)
	(segment
		(start 144.500346 -64.66967)
		(end 144.500346 -63.956946)
		(width 0.254)
		(layer "F.Cu")
		(net "DRV_ACT_16_N")
	)
	(via
		(at 136.32561 -69.03339)
		(size 0.6604)
		(drill 0.3302)
		(layers "F.Cu" "B.Cu")
		(net "DRV_ACT_16_N")
	)
	(segment
		(start 104.531668 -94.731332)
		(end 106.299 -92.964)
		(width 0.254)
		(layer "F.Cu")
		(net "DRV_ACT_15_N")
	)
	(segment
		(start 112.6236 -63.4746)
		(end 110.2614 -63.4746)
		(width 0.254)
		(layer "F.Cu")
		(net "DRV_ACT_15_N")
	)
	(segment
		(start 110.2614 -63.4746)
		(end 108.23956 -65.49644)
		(width 0.254)
		(layer "F.Cu")
		(net "DRV_ACT_15_N")
	)
	(segment
		(start 104.531668 -99.798378)
		(end 104.531668 -94.731332)
		(width 0.254)
		(layer "F.Cu")
		(net "DRV_ACT_15_N")
	)
	(segment
		(start 108.23956 -91.02344)
		(end 106.299 -92.964)
		(width 0.254)
		(layer "F.Cu")
		(net "DRV_ACT_15_N")
	)
	(segment
		(start 112.950498 -63.801498)
		(end 112.6236 -63.4746)
		(width 0.254)
		(layer "F.Cu")
		(net "DRV_ACT_15_N")
	)
	(segment
		(start 112.950498 -64.66967)
		(end 112.950498 -63.801498)
		(width 0.254)
		(layer "F.Cu")
		(net "DRV_ACT_15_N")
	)
	(segment
		(start 108.23956 -65.49644)
		(end 108.23956 -91.02344)
		(width 0.254)
		(layer "F.Cu")
		(net "DRV_ACT_15_N")
	)
	(via
		(at 106.299 -92.964)
		(size 0.6604)
		(drill 0.3302)
		(layers "F.Cu" "B.Cu")
		(net "DRV_ACT_15_N")
	)
	(segment
		(start 72.908668 -94.807532)
		(end 74.676 -93.0402)
		(width 0.254)
		(layer "F.Cu")
		(net "DRV_ACT_14_N")
	)
	(segment
		(start 81.400396 -64.66967)
		(end 81.400396 -63.798196)
		(width 0.254)
		(layer "F.Cu")
		(net "DRV_ACT_14_N")
	)
	(segment
		(start 81.153 -63.5508)
		(end 78.6384 -63.5508)
		(width 0.254)
		(layer "F.Cu")
		(net "DRV_ACT_14_N")
	)
	(segment
		(start 76.61656 -91.09964)
		(end 74.676 -93.0402)
		(width 0.254)
		(layer "F.Cu")
		(net "DRV_ACT_14_N")
	)
	(segment
		(start 81.400396 -63.798196)
		(end 81.153 -63.5508)
		(width 0.254)
		(layer "F.Cu")
		(net "DRV_ACT_14_N")
	)
	(segment
		(start 78.6384 -63.5508)
		(end 76.61656 -65.57264)
		(width 0.254)
		(layer "F.Cu")
		(net "DRV_ACT_14_N")
	)
	(segment
		(start 72.908668 -99.874578)
		(end 72.908668 -94.807532)
		(width 0.254)
		(layer "F.Cu")
		(net "DRV_ACT_14_N")
	)
	(segment
		(start 76.61656 -65.57264)
		(end 76.61656 -91.09964)
		(width 0.254)
		(layer "F.Cu")
		(net "DRV_ACT_14_N")
	)
	(via
		(at 74.676 -93.0402)
		(size 0.6604)
		(drill 0.3302)
		(layers "F.Cu" "B.Cu")
		(net "DRV_ACT_14_N")
	)
	(segment
		(start 49.4919 -63.5889)
		(end 47.0535 -63.5889)
		(width 0.254)
		(layer "F.Cu")
		(net "DRV_ACT_13_N")
	)
	(segment
		(start 45.7962 -87.249)
		(end 45.7962 -83.8962)
		(width 0.254)
		(layer "F.Cu")
		(net "DRV_ACT_13_N")
	)
	(segment
		(start 47.076868 -99.798378)
		(end 47.076868 -88.529668)
		(width 0.254)
		(layer "F.Cu")
		(net "DRV_ACT_13_N")
	)
	(segment
		(start 47.0535 -63.5889)
		(end 45.7962 -64.8462)
		(width 0.254)
		(layer "F.Cu")
		(net "DRV_ACT_13_N")
	)
	(segment
		(start 45.7962 -64.8462)
		(end 45.7962 -83.8962)
		(width 0.254)
		(layer "F.Cu")
		(net "DRV_ACT_13_N")
	)
	(segment
		(start 49.850294 -63.947294)
		(end 49.4919 -63.5889)
		(width 0.254)
		(layer "F.Cu")
		(net "DRV_ACT_13_N")
	)
	(segment
		(start 47.076868 -88.529668)
		(end 45.7962 -87.249)
		(width 0.254)
		(layer "F.Cu")
		(net "DRV_ACT_13_N")
	)
	(segment
		(start 49.850294 -64.66967)
		(end 49.850294 -63.947294)
		(width 0.254)
		(layer "F.Cu")
		(net "DRV_ACT_13_N")
	)
	(via
		(at 45.7962 -83.8962)
		(size 0.6604)
		(drill 0.3302)
		(layers "F.Cu" "B.Cu")
		(net "DRV_ACT_13_N")
	)
	(segment
		(start 18.300446 -64.66967)
		(end 18.300446 -63.944246)
		(width 0.254)
		(layer "F.Cu")
		(net "DRV_ACT_12_N")
	)
	(segment
		(start 13.007086 -94.01429)
		(end 13.643102 -93.378274)
		(width 0.254)
		(layer "F.Cu")
		(net "DRV_ACT_12_N")
	)
	(segment
		(start 13.007086 -99.886262)
		(end 13.007086 -94.01429)
		(width 0.254)
		(layer "F.Cu")
		(net "DRV_ACT_12_N")
	)
	(segment
		(start 17.9832 -63.627)
		(end 15.7734 -63.627)
		(width 0.254)
		(layer "F.Cu")
		(net "DRV_ACT_12_N")
	)
	(segment
		(start 15.7734 -63.627)
		(end 14.5542 -64.8462)
		(width 0.254)
		(layer "F.Cu")
		(net "DRV_ACT_12_N")
	)
	(segment
		(start 14.5542 -64.8462)
		(end 14.5542 -92.467176)
		(width 0.254)
		(layer "F.Cu")
		(net "DRV_ACT_12_N")
	)
	(segment
		(start 18.300446 -63.944246)
		(end 17.9832 -63.627)
		(width 0.254)
		(layer "F.Cu")
		(net "DRV_ACT_12_N")
	)
	(segment
		(start 14.5542 -92.467176)
		(end 13.643102 -93.378274)
		(width 0.254)
		(layer "F.Cu")
		(net "DRV_ACT_12_N")
	)
	(via
		(at 13.643102 -93.378274)
		(size 0.6604)
		(drill 0.3302)
		(layers "F.Cu" "B.Cu")
		(net "DRV_ACT_12_N")
	)
	(segment
		(start 468.892128 -180.3654)
		(end 468.892128 -189.73038)
		(width 0.254)
		(layer "F.Cu")
		(net "DRV_ACT_11_N")
	)
	(segment
		(start 473.400374 -178.549046)
		(end 472.930728 -178.0794)
		(width 0.254)
		(layer "F.Cu")
		(net "DRV_ACT_11_N")
	)
	(segment
		(start 464.991196 -214.860378)
		(end 464.991196 -209.793332)
		(width 0.254)
		(layer "F.Cu")
		(net "DRV_ACT_11_N")
	)
	(segment
		(start 468.892128 -205.8924)
		(end 468.892128 -189.73038)
		(width 0.254)
		(layer "F.Cu")
		(net "DRV_ACT_11_N")
	)
	(segment
		(start 473.400374 -179.669694)
		(end 473.400374 -178.549046)
		(width 0.254)
		(layer "F.Cu")
		(net "DRV_ACT_11_N")
	)
	(segment
		(start 464.991196 -209.793332)
		(end 468.892128 -205.8924)
		(width 0.254)
		(layer "F.Cu")
		(net "DRV_ACT_11_N")
	)
	(segment
		(start 472.930728 -178.0794)
		(end 471.178128 -178.0794)
		(width 0.254)
		(layer "F.Cu")
		(net "DRV_ACT_11_N")
	)
	(segment
		(start 471.178128 -178.0794)
		(end 468.892128 -180.3654)
		(width 0.254)
		(layer "F.Cu")
		(net "DRV_ACT_11_N")
	)
	(via
		(at 468.892128 -189.73038)
		(size 0.6604)
		(drill 0.3302)
		(layers "F.Cu" "B.Cu")
		(net "DRV_ACT_11_N")
	)
	(segment
		(start 441.850272 -178.549046)
		(end 441.380626 -178.0794)
		(width 0.254)
		(layer "F.Cu")
		(net "DRV_ACT_10_N")
	)
	(segment
		(start 438.6834 -178.0794)
		(end 437.799226 -178.963574)
		(width 0.254)
		(layer "F.Cu")
		(net "DRV_ACT_10_N")
	)
	(segment
		(start 433.441094 -214.860378)
		(end 433.441094 -209.793332)
		(width 0.254)
		(layer "F.Cu")
		(net "DRV_ACT_10_N")
	)
	(segment
		(start 433.441094 -209.793332)
		(end 437.799226 -205.4352)
		(width 0.254)
		(layer "F.Cu")
		(net "DRV_ACT_10_N")
	)
	(segment
		(start 437.799226 -205.4352)
		(end 437.799226 -197.5104)
		(width 0.254)
		(layer "F.Cu")
		(net "DRV_ACT_10_N")
	)
	(segment
		(start 441.850272 -179.669694)
		(end 441.850272 -178.549046)
		(width 0.254)
		(layer "F.Cu")
		(net "DRV_ACT_10_N")
	)
	(segment
		(start 437.799226 -178.963574)
		(end 437.799226 -197.5104)
		(width 0.254)
		(layer "F.Cu")
		(net "DRV_ACT_10_N")
	)
	(segment
		(start 441.380626 -178.0794)
		(end 438.6834 -178.0794)
		(width 0.254)
		(layer "F.Cu")
		(net "DRV_ACT_10_N")
	)
	(via
		(at 437.799226 -197.5104)
		(size 0.6604)
		(drill 0.3302)
		(layers "F.Cu" "B.Cu")
		(net "DRV_ACT_10_N")
	)
	(segment
		(start 40.726868 -210.112864)
		(end 42.037 -208.802732)
		(width 0.254)
		(layer "F.Cu")
		(net "DRV_ACT_1_N")
	)
	(segment
		(start 40.726868 -213.590378)
		(end 40.726868 -210.112864)
		(width 0.254)
		(layer "F.Cu")
		(net "DRV_ACT_1_N")
	)
	(segment
		(start 44.84116 -180.48224)
		(end 44.84116 -205.998572)
		(width 0.254)
		(layer "F.Cu")
		(net "DRV_ACT_1_N")
	)
	(segment
		(start 49.3014 -178.308)
		(end 47.0154 -178.308)
		(width 0.254)
		(layer "F.Cu")
		(net "DRV_ACT_1_N")
	)
	(segment
		(start 47.0154 -178.308)
		(end 44.84116 -180.48224)
		(width 0.254)
		(layer "F.Cu")
		(net "DRV_ACT_1_N")
	)
	(segment
		(start 44.84116 -205.998572)
		(end 42.037 -208.802732)
		(width 0.254)
		(layer "F.Cu")
		(net "DRV_ACT_1_N")
	)
	(segment
		(start 49.850294 -178.856894)
		(end 49.3014 -178.308)
		(width 0.254)
		(layer "F.Cu")
		(net "DRV_ACT_1_N")
	)
	(segment
		(start 49.850294 -179.669694)
		(end 49.850294 -178.856894)
		(width 0.254)
		(layer "F.Cu")
		(net "DRV_ACT_1_N")
	)
	(via
		(at 42.037 -208.802732)
		(size 0.6604)
		(drill 0.3302)
		(layers "F.Cu" "B.Cu")
		(net "DRV_ACT_1_N")
	)
	(segment
		(start 18.300446 -178.549046)
		(end 17.8308 -178.0794)
		(width 0.254)
		(layer "F.Cu")
		(net "DRV_ACT_0_N")
	)
	(segment
		(start 13.59916 -180.55844)
		(end 13.59916 -205.72984)
		(width 0.254)
		(layer "F.Cu")
		(net "DRV_ACT_0_N")
	)
	(segment
		(start 16.0782 -178.0794)
		(end 13.59916 -180.55844)
		(width 0.254)
		(layer "F.Cu")
		(net "DRV_ACT_0_N")
	)
	(segment
		(start 17.8308 -178.0794)
		(end 16.0782 -178.0794)
		(width 0.254)
		(layer "F.Cu")
		(net "DRV_ACT_0_N")
	)
	(segment
		(start 9.891268 -214.860378)
		(end 9.891268 -209.437732)
		(width 0.254)
		(layer "F.Cu")
		(net "DRV_ACT_0_N")
	)
	(segment
		(start 13.59916 -205.72984)
		(end 11.176 -208.153)
		(width 0.254)
		(layer "F.Cu")
		(net "DRV_ACT_0_N")
	)
	(segment
		(start 18.300446 -179.669694)
		(end 18.300446 -178.549046)
		(width 0.254)
		(layer "F.Cu")
		(net "DRV_ACT_0_N")
	)
	(segment
		(start 9.891268 -209.437732)
		(end 11.176 -208.153)
		(width 0.254)
		(layer "F.Cu")
		(net "DRV_ACT_0_N")
	)
	(via
		(at 11.176 -208.153)
		(size 0.6604)
		(drill 0.3302)
		(layers "F.Cu" "B.Cu")
		(net "DRV_ACT_0_N")
	)
	(via
		(at 215.4682 -215.3158)
		(size 0.5588)
		(drill 0.3048)
		(layers "F.Cu" "B.Cu")
		(net "SCC_B_RESET_N")
	)
	(segment
		(start 214.268304 -103.110284)
		(end 214.268304 -113.069116)
		(width 0.14605)
		(layer "In2.Cu")
		(net "SCC_B_RESET_N")
	)
	(segment
		(start 218.368118 -74.831956)
		(end 218.368118 -80.053688)
		(width 0.14605)
		(layer "In2.Cu")
		(net "SCC_B_RESET_N")
	)
	(segment
		(start 215.4682 -212.43798)
		(end 215.4682 -215.3158)
		(width 0.14605)
		(layer "In2.Cu")
		(net "SCC_B_RESET_N")
	)
	(segment
		(start 218.671648 -80.357218)
		(end 218.671648 -98.70694)
		(width 0.14605)
		(layer "In2.Cu")
		(net "SCC_B_RESET_N")
	)
	(segment
		(start 219.00007 -74.200004)
		(end 218.368118 -74.831956)
		(width 0.14605)
		(layer "In2.Cu")
		(net "SCC_B_RESET_N")
	)
	(segment
		(start 213.550754 -113.786666)
		(end 213.550754 -160.435544)
		(width 0.14605)
		(layer "In2.Cu")
		(net "SCC_B_RESET_N")
	)
	(segment
		(start 216.00414 -175.018192)
		(end 216.00414 -198.915274)
		(width 0.14605)
		(layer "In2.Cu")
		(net "SCC_B_RESET_N")
	)
	(segment
		(start 215.128602 -174.142654)
		(end 216.00414 -175.018192)
		(width 0.14605)
		(layer "In2.Cu")
		(net "SCC_B_RESET_N")
	)
	(segment
		(start 218.368118 -80.053688)
		(end 218.671648 -80.357218)
		(width 0.14605)
		(layer "In2.Cu")
		(net "SCC_B_RESET_N")
	)
	(segment
		(start 214.268304 -113.069116)
		(end 213.550754 -113.786666)
		(width 0.14605)
		(layer "In2.Cu")
		(net "SCC_B_RESET_N")
	)
	(segment
		(start 218.671648 -98.70694)
		(end 214.268304 -103.110284)
		(width 0.14605)
		(layer "In2.Cu")
		(net "SCC_B_RESET_N")
	)
	(segment
		(start 213.550754 -160.435544)
		(end 213.9188 -160.80359)
		(width 0.14605)
		(layer "In2.Cu")
		(net "SCC_B_RESET_N")
	)
	(segment
		(start 216.517728 -211.388452)
		(end 215.4682 -212.43798)
		(width 0.14605)
		(layer "In2.Cu")
		(net "SCC_B_RESET_N")
	)
	(segment
		(start 213.9188 -164.631878)
		(end 215.128602 -165.84168)
		(width 0.14605)
		(layer "In2.Cu")
		(net "SCC_B_RESET_N")
	)
	(segment
		(start 216.517728 -199.428862)
		(end 216.517728 -211.388452)
		(width 0.14605)
		(layer "In2.Cu")
		(net "SCC_B_RESET_N")
	)
	(segment
		(start 213.9188 -160.80359)
		(end 213.9188 -164.631878)
		(width 0.14605)
		(layer "In2.Cu")
		(net "SCC_B_RESET_N")
	)
	(segment
		(start 216.00414 -198.915274)
		(end 216.517728 -199.428862)
		(width 0.14605)
		(layer "In2.Cu")
		(net "SCC_B_RESET_N")
	)
	(segment
		(start 215.128602 -165.84168)
		(end 215.128602 -174.142654)
		(width 0.14605)
		(layer "In2.Cu")
		(net "SCC_B_RESET_N")
	)
	(segment
		(start 231.241346 -221.8944)
		(end 238.539782 -221.8944)
		(width 0.14605)
		(layer "In5.Cu")
		(net "SCC_B_RESET_N")
	)
	(segment
		(start 267.6398 -222.9612)
		(end 268.224 -222.377)
		(width 0.14605)
		(layer "In5.Cu")
		(net "SCC_B_RESET_N")
	)
	(segment
		(start 274.1422 -222.377)
		(end 274.663154 -221.856046)
		(width 0.14605)
		(layer "In5.Cu")
		(net "SCC_B_RESET_N")
	)
	(segment
		(start 230.909368 -221.562422)
		(end 231.241346 -221.8944)
		(width 0.14605)
		(layer "In5.Cu")
		(net "SCC_B_RESET_N")
	)
	(segment
		(start 281.19832 -221.856046)
		(end 281.836622 -222.494348)
		(width 0.14605)
		(layer "In5.Cu")
		(net "SCC_B_RESET_N")
	)
	(segment
		(start 274.663154 -221.856046)
		(end 281.19832 -221.856046)
		(width 0.14605)
		(layer "In5.Cu")
		(net "SCC_B_RESET_N")
	)
	(segment
		(start 239.696752 -223.05137)
		(end 244.801898 -223.05137)
		(width 0.14605)
		(layer "In5.Cu")
		(net "SCC_B_RESET_N")
	)
	(segment
		(start 245.857268 -221.996)
		(end 261.3914 -221.996)
		(width 0.14605)
		(layer "In5.Cu")
		(net "SCC_B_RESET_N")
	)
	(segment
		(start 268.224 -222.377)
		(end 274.1422 -222.377)
		(width 0.14605)
		(layer "In5.Cu")
		(net "SCC_B_RESET_N")
	)
	(segment
		(start 218.2114 -218.059)
		(end 227.4062 -218.059)
		(width 0.14605)
		(layer "In5.Cu")
		(net "SCC_B_RESET_N")
	)
	(segment
		(start 230.909368 -221.562168)
		(end 230.909368 -221.562422)
		(width 0.14605)
		(layer "In5.Cu")
		(net "SCC_B_RESET_N")
	)
	(segment
		(start 215.4682 -215.3158)
		(end 218.2114 -218.059)
		(width 0.14605)
		(layer "In5.Cu")
		(net "SCC_B_RESET_N")
	)
	(segment
		(start 244.801898 -223.05137)
		(end 245.857268 -221.996)
		(width 0.14605)
		(layer "In5.Cu")
		(net "SCC_B_RESET_N")
	)
	(segment
		(start 227.4062 -218.059)
		(end 230.909368 -221.562168)
		(width 0.14605)
		(layer "In5.Cu")
		(net "SCC_B_RESET_N")
	)
	(segment
		(start 238.539782 -221.8944)
		(end 239.696752 -223.05137)
		(width 0.14605)
		(layer "In5.Cu")
		(net "SCC_B_RESET_N")
	)
	(segment
		(start 262.3566 -222.9612)
		(end 267.6398 -222.9612)
		(width 0.14605)
		(layer "In5.Cu")
		(net "SCC_B_RESET_N")
	)
	(segment
		(start 261.3914 -221.996)
		(end 262.3566 -222.9612)
		(width 0.14605)
		(layer "In5.Cu")
		(net "SCC_B_RESET_N")
	)
	(segment
		(start 249.0978 -136.906)
		(end 249.9868 -136.906)
		(width 0.17145)
		(layer "F.Cu")
		(net "I2C_SCC_BUFF_READY")
	)
	(segment
		(start 248.557034 -137.446766)
		(end 249.0978 -136.906)
		(width 0.17145)
		(layer "F.Cu")
		(net "I2C_SCC_BUFF_READY")
	)
	(segment
		(start 251.191522 -136.906)
		(end 249.9868 -136.906)
		(width 0.17145)
		(layer "F.Cu")
		(net "I2C_SCC_BUFF_READY")
	)
	(segment
		(start 251.332492 -137.04697)
		(end 251.191522 -136.906)
		(width 0.17145)
		(layer "F.Cu")
		(net "I2C_SCC_BUFF_READY")
	)
	(segment
		(start 248.557034 -138.615674)
		(end 248.557034 -137.446766)
		(width 0.17145)
		(layer "F.Cu")
		(net "I2C_SCC_BUFF_READY")
	)
	(via
		(at 249.9868 -136.906)
		(size 0.6604)
		(drill 0.3302)
		(layers "F.Cu" "B.Cu")
		(net "I2C_SCC_BUFF_READY")
	)
	(segment
		(start 240.315242 -141.3764)
		(end 241.78641 -141.3764)
		(width 0.17145)
		(layer "F.Cu")
		(net "I2C_SCC_BUFF_EN")
	)
	(segment
		(start 244.416834 -140.566394)
		(end 243.811806 -140.566394)
		(width 0.17145)
		(layer "F.Cu")
		(net "I2C_SCC_BUFF_EN")
	)
	(segment
		(start 243.0018 -141.3764)
		(end 241.78641 -141.3764)
		(width 0.17145)
		(layer "F.Cu")
		(net "I2C_SCC_BUFF_EN")
	)
	(segment
		(start 243.811806 -140.566394)
		(end 243.0018 -141.3764)
		(width 0.17145)
		(layer "F.Cu")
		(net "I2C_SCC_BUFF_EN")
	)
	(via
		(at 241.78641 -141.3764)
		(size 0.6604)
		(drill 0.3302)
		(layers "F.Cu" "B.Cu")
		(net "I2C_SCC_BUFF_EN")
	)
	(segment
		(start 248.557034 -139.916154)
		(end 249.593354 -139.916154)
		(width 0.17145)
		(layer "F.Cu")
		(net "I2C_SCC_B_SDA_BUF")
	)
	(segment
		(start 248.882662 -145.848832)
		(end 246.490744 -143.456914)
		(width 0.17145)
		(layer "F.Cu")
		(net "I2C_SCC_B_SDA_BUF")
	)
	(segment
		(start 249.669554 -139.992354)
		(end 251.746766 -139.992354)
		(width 0.17145)
		(layer "F.Cu")
		(net "I2C_SCC_B_SDA_BUF")
	)
	(segment
		(start 246.490744 -140.254736)
		(end 246.829326 -139.916154)
		(width 0.17145)
		(layer "F.Cu")
		(net "I2C_SCC_B_SDA_BUF")
	)
	(segment
		(start 276.78634 -140.2842)
		(end 275.92401 -141.14653)
		(width 0.17145)
		(layer "F.Cu")
		(net "I2C_SCC_B_SDA_BUF")
	)
	(segment
		(start 265.900916 -141.14653)
		(end 261.198614 -145.848832)
		(width 0.17145)
		(layer "F.Cu")
		(net "I2C_SCC_B_SDA_BUF")
	)
	(segment
		(start 254.804164 -145.848832)
		(end 248.882662 -145.848832)
		(width 0.17145)
		(layer "F.Cu")
		(net "I2C_SCC_B_SDA_BUF")
	)
	(segment
		(start 275.92401 -141.14653)
		(end 265.900916 -141.14653)
		(width 0.17145)
		(layer "F.Cu")
		(net "I2C_SCC_B_SDA_BUF")
	)
	(segment
		(start 251.746766 -139.992354)
		(end 252.770894 -139.992354)
		(width 0.17145)
		(layer "F.Cu")
		(net "I2C_SCC_B_SDA_BUF")
	)
	(segment
		(start 282.83662 -141.09446)
		(end 282.02636 -140.2842)
		(width 0.17145)
		(layer "F.Cu")
		(net "I2C_SCC_B_SDA_BUF")
	)
	(segment
		(start 246.829326 -139.916154)
		(end 248.557034 -139.916154)
		(width 0.17145)
		(layer "F.Cu")
		(net "I2C_SCC_B_SDA_BUF")
	)
	(segment
		(start 252.770894 -139.992354)
		(end 253.007114 -140.228574)
		(width 0.17145)
		(layer "F.Cu")
		(net "I2C_SCC_B_SDA_BUF")
	)
	(segment
		(start 282.02636 -140.2842)
		(end 276.78634 -140.2842)
		(width 0.17145)
		(layer "F.Cu")
		(net "I2C_SCC_B_SDA_BUF")
	)
	(segment
		(start 246.490744 -143.456914)
		(end 246.490744 -140.254736)
		(width 0.17145)
		(layer "F.Cu")
		(net "I2C_SCC_B_SDA_BUF")
	)
	(segment
		(start 261.198614 -145.848832)
		(end 254.804164 -145.848832)
		(width 0.17145)
		(layer "F.Cu")
		(net "I2C_SCC_B_SDA_BUF")
	)
	(segment
		(start 249.593354 -139.916154)
		(end 249.669554 -139.992354)
		(width 0.17145)
		(layer "F.Cu")
		(net "I2C_SCC_B_SDA_BUF")
	)
	(via
		(at 254.804164 -145.848832)
		(size 0.6604)
		(drill 0.3302)
		(layers "F.Cu" "B.Cu")
		(net "I2C_SCC_B_SDA_BUF")
	)
	(segment
		(start 244.416834 -139.916154)
		(end 243.293646 -139.916154)
		(width 0.17145)
		(layer "F.Cu")
		(net "I2C_SCC_B_SCL_BUF")
	)
	(segment
		(start 240.529618 -139.824714)
		(end 240.304066 -140.050266)
		(width 0.17145)
		(layer "F.Cu")
		(net "I2C_SCC_B_SCL_BUF")
	)
	(segment
		(start 257.846322 -146.631152)
		(end 248.703846 -146.631152)
		(width 0.17145)
		(layer "F.Cu")
		(net "I2C_SCC_B_SCL_BUF")
	)
	(segment
		(start 248.703846 -146.631152)
		(end 245.81104 -143.738346)
		(width 0.17145)
		(layer "F.Cu")
		(net "I2C_SCC_B_SCL_BUF")
	)
	(segment
		(start 243.293646 -139.916154)
		(end 243.1034 -140.1064)
		(width 0.17145)
		(layer "F.Cu")
		(net "I2C_SCC_B_SCL_BUF")
	)
	(segment
		(start 266.389104 -141.82598)
		(end 261.583932 -146.631152)
		(width 0.17145)
		(layer "F.Cu")
		(net "I2C_SCC_B_SCL_BUF")
	)
	(segment
		(start 241.462306 -139.824714)
		(end 240.529618 -139.824714)
		(width 0.17145)
		(layer "F.Cu")
		(net "I2C_SCC_B_SCL_BUF")
	)
	(segment
		(start 284.236668 -141.09446)
		(end 283.505148 -141.82598)
		(width 0.17145)
		(layer "F.Cu")
		(net "I2C_SCC_B_SCL_BUF")
	)
	(segment
		(start 261.583932 -146.631152)
		(end 257.846322 -146.631152)
		(width 0.17145)
		(layer "F.Cu")
		(net "I2C_SCC_B_SCL_BUF")
	)
	(segment
		(start 245.81104 -140.349224)
		(end 245.37797 -139.916154)
		(width 0.17145)
		(layer "F.Cu")
		(net "I2C_SCC_B_SCL_BUF")
	)
	(segment
		(start 243.1034 -140.1064)
		(end 241.743992 -140.1064)
		(width 0.17145)
		(layer "F.Cu")
		(net "I2C_SCC_B_SCL_BUF")
	)
	(segment
		(start 283.505148 -141.82598)
		(end 266.389104 -141.82598)
		(width 0.17145)
		(layer "F.Cu")
		(net "I2C_SCC_B_SCL_BUF")
	)
	(segment
		(start 245.37797 -139.916154)
		(end 244.416834 -139.916154)
		(width 0.17145)
		(layer "F.Cu")
		(net "I2C_SCC_B_SCL_BUF")
	)
	(segment
		(start 245.81104 -143.738346)
		(end 245.81104 -140.349224)
		(width 0.17145)
		(layer "F.Cu")
		(net "I2C_SCC_B_SCL_BUF")
	)
	(segment
		(start 241.743992 -140.1064)
		(end 241.462306 -139.824714)
		(width 0.17145)
		(layer "F.Cu")
		(net "I2C_SCC_B_SCL_BUF")
	)
	(via
		(at 257.846322 -146.631152)
		(size 0.6604)
		(drill 0.3302)
		(layers "F.Cu" "B.Cu")
		(net "I2C_SCC_B_SCL_BUF")
	)
	(segment
		(start 247.958102 -130.501898)
		(end 248.3358 -130.1242)
		(width 0.17145)
		(layer "F.Cu")
		(net "I2C_DPB_BUFF_READY")
	)
	(segment
		(start 248.3358 -130.1242)
		(end 249.301 -130.1242)
		(width 0.17145)
		(layer "F.Cu")
		(net "I2C_DPB_BUFF_READY")
	)
	(segment
		(start 251.888752 -131.428998)
		(end 251.888752 -130.629152)
		(width 0.17145)
		(layer "F.Cu")
		(net "I2C_DPB_BUFF_READY")
	)
	(segment
		(start 251.3838 -130.1242)
		(end 249.301 -130.1242)
		(width 0.17145)
		(layer "F.Cu")
		(net "I2C_DPB_BUFF_READY")
	)
	(segment
		(start 247.958102 -131.982718)
		(end 247.958102 -130.501898)
		(width 0.17145)
		(layer "F.Cu")
		(net "I2C_DPB_BUFF_READY")
	)
	(segment
		(start 251.888752 -130.629152)
		(end 251.3838 -130.1242)
		(width 0.17145)
		(layer "F.Cu")
		(net "I2C_DPB_BUFF_READY")
	)
	(via
		(at 249.301 -130.1242)
		(size 0.6604)
		(drill 0.3302)
		(layers "F.Cu" "B.Cu")
		(net "I2C_DPB_BUFF_READY")
	)
	(segment
		(start 240.474754 -134.62508)
		(end 241.741706 -134.62508)
		(width 0.17145)
		(layer "F.Cu")
		(net "I2C_DPB_BUFF_EN")
	)
	(segment
		(start 243.180362 -133.933438)
		(end 242.48872 -134.62508)
		(width 0.17145)
		(layer "F.Cu")
		(net "I2C_DPB_BUFF_EN")
	)
	(segment
		(start 242.48872 -134.62508)
		(end 241.741706 -134.62508)
		(width 0.17145)
		(layer "F.Cu")
		(net "I2C_DPB_BUFF_EN")
	)
	(segment
		(start 240.242852 -134.393178)
		(end 240.474754 -134.62508)
		(width 0.17145)
		(layer "F.Cu")
		(net "I2C_DPB_BUFF_EN")
	)
	(segment
		(start 243.817902 -133.933438)
		(end 243.180362 -133.933438)
		(width 0.17145)
		(layer "F.Cu")
		(net "I2C_DPB_BUFF_EN")
	)
	(via
		(at 241.741706 -134.62508)
		(size 0.6604)
		(drill 0.3302)
		(layers "F.Cu" "B.Cu")
		(net "I2C_DPB_BUFF_EN")
	)
	(segment
		(start 263.41705 -368.655346)
		(end 264.458704 -369.697)
		(width 0.17145)
		(layer "F.Cu")
		(net "I2C_DPB_B_SDA_BUF")
	)
	(segment
		(start 281.836622 -215.294464)
		(end 280.994358 -214.4522)
		(width 0.17145)
		(layer "F.Cu")
		(net "I2C_DPB_B_SDA_BUF")
	)
	(segment
		(start 259.23875 -212.107018)
		(end 258.78663 -211.654898)
		(width 0.17145)
		(layer "F.Cu")
		(net "I2C_DPB_B_SDA_BUF")
	)
	(segment
		(start 258.78663 -211.654898)
		(end 255.171448 -211.654898)
		(width 0.17145)
		(layer "F.Cu")
		(net "I2C_DPB_B_SDA_BUF")
	)
	(segment
		(start 272.113756 -216.620598)
		(end 266.065508 -216.620598)
		(width 0.17145)
		(layer "F.Cu")
		(net "I2C_DPB_B_SDA_BUF")
	)
	(segment
		(start 255.635252 -134.381748)
		(end 267.208 -122.809)
		(width 0.17145)
		(layer "F.Cu")
		(net "I2C_DPB_B_SDA_BUF")
	)
	(segment
		(start 280.994358 -214.4522)
		(end 274.282154 -214.4522)
		(width 0.17145)
		(layer "F.Cu")
		(net "I2C_DPB_B_SDA_BUF")
	)
	(segment
		(start 255.635252 -135.087614)
		(end 255.635252 -134.381748)
		(width 0.17145)
		(layer "F.Cu")
		(net "I2C_DPB_B_SDA_BUF")
	)
	(segment
		(start 279.999948 -355.415342)
		(end 276.733 -355.415342)
		(width 0.17145)
		(layer "F.Cu")
		(net "I2C_DPB_B_SDA_BUF")
	)
	(segment
		(start 249.381772 -133.735572)
		(end 250.782582 -133.735572)
		(width 0.17145)
		(layer "F.Cu")
		(net "I2C_DPB_B_SDA_BUF")
	)
	(segment
		(start 266.065508 -216.620598)
		(end 261.551928 -212.107018)
		(width 0.17145)
		(layer "F.Cu")
		(net "I2C_DPB_B_SDA_BUF")
	)
	(segment
		(start 248.929398 -133.283198)
		(end 249.381772 -133.735572)
		(width 0.17145)
		(layer "F.Cu")
		(net "I2C_DPB_B_SDA_BUF")
	)
	(segment
		(start 282.702762 -122.809)
		(end 284.287468 -121.224294)
		(width 0.17145)
		(layer "F.Cu")
		(net "I2C_DPB_B_SDA_BUF")
	)
	(segment
		(start 459.3082 -13.7033)
		(end 459.3082 -14.3764)
		(width 0.17145)
		(layer "F.Cu")
		(net "I2C_DPB_B_SDA_BUF")
	)
	(segment
		(start 260.907022 -368.655346)
		(end 263.41705 -368.655346)
		(width 0.17145)
		(layer "F.Cu")
		(net "I2C_DPB_B_SDA_BUF")
	)
	(segment
		(start 247.958102 -133.283198)
		(end 248.929398 -133.283198)
		(width 0.17145)
		(layer "F.Cu")
		(net "I2C_DPB_B_SDA_BUF")
	)
	(segment
		(start 252.2982 -135.636)
		(end 251.80544 -135.14324)
		(width 0.17145)
		(layer "F.Cu")
		(net "I2C_DPB_B_SDA_BUF")
	)
	(segment
		(start 274.282154 -214.4522)
		(end 272.113756 -216.620598)
		(width 0.17145)
		(layer "F.Cu")
		(net "I2C_DPB_B_SDA_BUF")
	)
	(segment
		(start 254.2413 -212.64753)
		(end 254.210058 -212.616288)
		(width 0.17145)
		(layer "F.Cu")
		(net "I2C_DPB_B_SDA_BUF")
	)
	(segment
		(start 255.171448 -211.654898)
		(end 254.210058 -212.616288)
		(width 0.17145)
		(layer "F.Cu")
		(net "I2C_DPB_B_SDA_BUF")
	)
	(segment
		(start 250.782582 -133.735572)
		(end 251.879608 -133.735572)
		(width 0.17145)
		(layer "F.Cu")
		(net "I2C_DPB_B_SDA_BUF")
	)
	(segment
		(start 255.13284 -135.590026)
		(end 255.086866 -135.636)
		(width 0.17145)
		(layer "F.Cu")
		(net "I2C_DPB_B_SDA_BUF")
	)
	(segment
		(start 254.2413 -213.87054)
		(end 254.2413 -212.64753)
		(width 0.17145)
		(layer "F.Cu")
		(net "I2C_DPB_B_SDA_BUF")
	)
	(segment
		(start 251.895102 -134.474458)
		(end 251.895102 -133.720078)
		(width 0.17145)
		(layer "F.Cu")
		(net "I2C_DPB_B_SDA_BUF")
	)
	(segment
		(start 267.208 -122.809)
		(end 282.702762 -122.809)
		(width 0.17145)
		(layer "F.Cu")
		(net "I2C_DPB_B_SDA_BUF")
	)
	(segment
		(start 276.733 -355.415342)
		(end 276.008084 -354.690426)
		(width 0.17145)
		(layer "F.Cu")
		(net "I2C_DPB_B_SDA_BUF")
	)
	(segment
		(start 251.80544 -134.56412)
		(end 251.895102 -134.474458)
		(width 0.17145)
		(layer "F.Cu")
		(net "I2C_DPB_B_SDA_BUF")
	)
	(segment
		(start 251.80544 -135.14324)
		(end 251.80544 -134.56412)
		(width 0.17145)
		(layer "F.Cu")
		(net "I2C_DPB_B_SDA_BUF")
	)
	(segment
		(start 261.551928 -212.107018)
		(end 259.23875 -212.107018)
		(width 0.17145)
		(layer "F.Cu")
		(net "I2C_DPB_B_SDA_BUF")
	)
	(segment
		(start 251.879608 -133.735572)
		(end 251.895102 -133.720078)
		(width 0.17145)
		(layer "F.Cu")
		(net "I2C_DPB_B_SDA_BUF")
	)
	(segment
		(start 459.3082 -14.3764)
		(end 459.105 -14.5796)
		(width 0.17145)
		(layer "F.Cu")
		(net "I2C_DPB_B_SDA_BUF")
	)
	(segment
		(start 255.13284 -135.590026)
		(end 255.635252 -135.087614)
		(width 0.17145)
		(layer "F.Cu")
		(net "I2C_DPB_B_SDA_BUF")
	)
	(segment
		(start 255.086866 -135.636)
		(end 252.2982 -135.636)
		(width 0.17145)
		(layer "F.Cu")
		(net "I2C_DPB_B_SDA_BUF")
	)
	(segment
		(start 247.15978 -211.246212)
		(end 247.15978 -210.442048)
		(width 0.17145)
		(layer "F.Cu")
		(net "I2C_DPB_B_SDA_BUF")
	)
	(via
		(at 459.105 -14.5796)
		(size 0.5588)
		(drill 0.3048)
		(layers "F.Cu" "B.Cu")
		(net "I2C_DPB_B_SDA_BUF")
	)
	(via
		(at 321.2338 -4.1656)
		(size 0.5588)
		(drill 0.3048)
		(layers "F.Cu" "B.Cu")
		(net "I2C_DPB_B_SDA_BUF")
	)
	(via
		(at 296.3037 -147.1168)
		(size 0.5588)
		(drill 0.3048)
		(layers "F.Cu" "B.Cu")
		(net "I2C_DPB_B_SDA_BUF")
	)
	(via
		(at 277.48865 -327.144634)
		(size 0.5588)
		(drill 0.3048)
		(layers "F.Cu" "B.Cu")
		(net "I2C_DPB_B_SDA_BUF")
	)
	(via
		(at 284.287468 -121.224294)
		(size 0.5588)
		(drill 0.3048)
		(layers "F.Cu" "B.Cu")
		(net "I2C_DPB_B_SDA_BUF")
	)
	(via
		(at 254.210058 -212.616288)
		(size 0.5588)
		(drill 0.3048)
		(layers "F.Cu" "B.Cu")
		(net "I2C_DPB_B_SDA_BUF")
	)
	(via
		(at 255.13284 -135.590026)
		(size 0.6604)
		(drill 0.3302)
		(layers "F.Cu" "B.Cu")
		(net "I2C_DPB_B_SDA_BUF")
	)
	(via
		(at 276.008084 -354.690426)
		(size 0.5588)
		(drill 0.3048)
		(layers "F.Cu" "B.Cu")
		(net "I2C_DPB_B_SDA_BUF")
	)
	(via
		(at 264.458704 -369.697)
		(size 0.5588)
		(drill 0.3048)
		(layers "F.Cu" "B.Cu")
		(net "I2C_DPB_B_SDA_BUF")
	)
	(via
		(at 304.927 -114.808)
		(size 0.5588)
		(drill 0.3048)
		(layers "F.Cu" "B.Cu")
		(net "I2C_DPB_B_SDA_BUF")
	)
	(via
		(at 251.80544 -134.56412)
		(size 0.5588)
		(drill 0.3048)
		(layers "F.Cu" "B.Cu")
		(net "I2C_DPB_B_SDA_BUF")
	)
	(via
		(at 247.15978 -210.442048)
		(size 0.5588)
		(drill 0.3048)
		(layers "F.Cu" "B.Cu")
		(net "I2C_DPB_B_SDA_BUF")
	)
	(segment
		(start 268.467586 -364.715298)
		(end 264.458704 -368.72418)
		(width 0.17145)
		(layer "B.Cu")
		(net "I2C_DPB_B_SDA_BUF")
	)
	(segment
		(start 272.479008 -355.503734)
		(end 271.024096 -355.503734)
		(width 0.17145)
		(layer "B.Cu")
		(net "I2C_DPB_B_SDA_BUF")
	)
	(segment
		(start 276.008084 -354.690426)
		(end 273.292316 -354.690426)
		(width 0.17145)
		(layer "B.Cu")
		(net "I2C_DPB_B_SDA_BUF")
	)
	(segment
		(start 264.458704 -368.72418)
		(end 264.458704 -369.697)
		(width 0.17145)
		(layer "B.Cu")
		(net "I2C_DPB_B_SDA_BUF")
	)
	(segment
		(start 268.467586 -358.060244)
		(end 268.467586 -364.715298)
		(width 0.17145)
		(layer "B.Cu")
		(net "I2C_DPB_B_SDA_BUF")
	)
	(segment
		(start 273.292316 -354.690426)
		(end 272.479008 -355.503734)
		(width 0.17145)
		(layer "B.Cu")
		(net "I2C_DPB_B_SDA_BUF")
	)
	(segment
		(start 271.024096 -355.503734)
		(end 268.467586 -358.060244)
		(width 0.17145)
		(layer "B.Cu")
		(net "I2C_DPB_B_SDA_BUF")
	)
	(segment
		(start 321.769994 -86.546182)
		(end 321.769994 -92.22359)
		(width 0.14605)
		(layer "In2.Cu")
		(net "I2C_DPB_B_SDA_BUF")
	)
	(segment
		(start 321.770248 -94.461584)
		(end 322.148708 -94.840044)
		(width 0.14605)
		(layer "In2.Cu")
		(net "I2C_DPB_B_SDA_BUF")
	)
	(segment
		(start 275.110702 -215.83523)
		(end 276.432518 -214.513414)
		(width 0.14605)
		(layer "In2.Cu")
		(net "I2C_DPB_B_SDA_BUF")
	)
	(segment
		(start 289.541458 -187.7568)
		(end 295.615614 -181.682644)
		(width 0.14605)
		(layer "In2.Cu")
		(net "I2C_DPB_B_SDA_BUF")
	)
	(segment
		(start 321.76974 -93.128592)
		(end 321.770248 -93.1291)
		(width 0.14605)
		(layer "In2.Cu")
		(net "I2C_DPB_B_SDA_BUF")
	)
	(segment
		(start 294.281606 -277.124922)
		(end 294.281606 -271.433036)
		(width 0.14605)
		(layer "In2.Cu")
		(net "I2C_DPB_B_SDA_BUF")
	)
	(segment
		(start 276.432518 -214.513414)
		(end 281.055572 -214.513414)
		(width 0.14605)
		(layer "In2.Cu")
		(net "I2C_DPB_B_SDA_BUF")
	)
	(segment
		(start 321.2338 -4.1656)
		(end 321.2338 -4.699)
		(width 0.14605)
		(layer "In2.Cu")
		(net "I2C_DPB_B_SDA_BUF")
	)
	(segment
		(start 321.769994 -92.22359)
		(end 321.76974 -92.223844)
		(width 0.14605)
		(layer "In2.Cu")
		(net "I2C_DPB_B_SDA_BUF")
	)
	(segment
		(start 321.770248 -93.1291)
		(end 321.770248 -94.461584)
		(width 0.14605)
		(layer "In2.Cu")
		(net "I2C_DPB_B_SDA_BUF")
	)
	(segment
		(start 295.615614 -181.682644)
		(end 295.615614 -147.804886)
		(width 0.14605)
		(layer "In2.Cu")
		(net "I2C_DPB_B_SDA_BUF")
	)
	(segment
		(start 317.18885 -53.05425)
		(end 322.148708 -58.014108)
		(width 0.14605)
		(layer "In2.Cu")
		(net "I2C_DPB_B_SDA_BUF")
	)
	(segment
		(start 281.055572 -214.513414)
		(end 281.836622 -215.294464)
		(width 0.14605)
		(layer "In2.Cu")
		(net "I2C_DPB_B_SDA_BUF")
	)
	(segment
		(start 294.281352 -277.125176)
		(end 294.281606 -277.124922)
		(width 0.14605)
		(layer "In2.Cu")
		(net "I2C_DPB_B_SDA_BUF")
	)
	(segment
		(start 322.148708 -86.167468)
		(end 321.769994 -86.546182)
		(width 0.14605)
		(layer "In2.Cu")
		(net "I2C_DPB_B_SDA_BUF")
	)
	(segment
		(start 277.4442 -327.189084)
		(end 277.4442 -305.562)
		(width 0.14605)
		(layer "In2.Cu")
		(net "I2C_DPB_B_SDA_BUF")
	)
	(segment
		(start 277.4442 -305.562)
		(end 282.2448 -300.7614)
		(width 0.14605)
		(layer "In2.Cu")
		(net "I2C_DPB_B_SDA_BUF")
	)
	(segment
		(start 277.48865 -327.144634)
		(end 277.4442 -327.189084)
		(width 0.14605)
		(layer "In2.Cu")
		(net "I2C_DPB_B_SDA_BUF")
	)
	(segment
		(start 288.8869 -214.4268)
		(end 289.541458 -213.772242)
		(width 0.14605)
		(layer "In2.Cu")
		(net "I2C_DPB_B_SDA_BUF")
	)
	(segment
		(start 275.110702 -252.262132)
		(end 275.110702 -215.83523)
		(width 0.14605)
		(layer "In2.Cu")
		(net "I2C_DPB_B_SDA_BUF")
	)
	(segment
		(start 322.148708 -97.586292)
		(end 304.927 -114.808)
		(width 0.14605)
		(layer "In2.Cu")
		(net "I2C_DPB_B_SDA_BUF")
	)
	(segment
		(start 295.615614 -147.804886)
		(end 296.3037 -147.1168)
		(width 0.14605)
		(layer "In2.Cu")
		(net "I2C_DPB_B_SDA_BUF")
	)
	(segment
		(start 286.624522 -300.7614)
		(end 294.281352 -293.10457)
		(width 0.14605)
		(layer "In2.Cu")
		(net "I2C_DPB_B_SDA_BUF")
	)
	(segment
		(start 322.148708 -58.014108)
		(end 322.148708 -86.167468)
		(width 0.14605)
		(layer "In2.Cu")
		(net "I2C_DPB_B_SDA_BUF")
	)
	(segment
		(start 322.148708 -94.840044)
		(end 322.148708 -97.586292)
		(width 0.14605)
		(layer "In2.Cu")
		(net "I2C_DPB_B_SDA_BUF")
	)
	(segment
		(start 321.2338 -4.699)
		(end 317.18885 -8.74395)
		(width 0.14605)
		(layer "In2.Cu")
		(net "I2C_DPB_B_SDA_BUF")
	)
	(segment
		(start 321.76974 -92.223844)
		(end 321.76974 -93.128592)
		(width 0.14605)
		(layer "In2.Cu")
		(net "I2C_DPB_B_SDA_BUF")
	)
	(segment
		(start 317.18885 -8.74395)
		(end 317.18885 -53.05425)
		(width 0.14605)
		(layer "In2.Cu")
		(net "I2C_DPB_B_SDA_BUF")
	)
	(segment
		(start 294.281606 -271.433036)
		(end 275.110702 -252.262132)
		(width 0.14605)
		(layer "In2.Cu")
		(net "I2C_DPB_B_SDA_BUF")
	)
	(segment
		(start 289.541458 -213.772242)
		(end 289.541458 -187.7568)
		(width 0.14605)
		(layer "In2.Cu")
		(net "I2C_DPB_B_SDA_BUF")
	)
	(segment
		(start 282.704286 -214.4268)
		(end 288.8869 -214.4268)
		(width 0.14605)
		(layer "In2.Cu")
		(net "I2C_DPB_B_SDA_BUF")
	)
	(segment
		(start 294.281352 -293.10457)
		(end 294.281352 -277.125176)
		(width 0.14605)
		(layer "In2.Cu")
		(net "I2C_DPB_B_SDA_BUF")
	)
	(segment
		(start 281.836622 -215.294464)
		(end 282.704286 -214.4268)
		(width 0.14605)
		(layer "In2.Cu")
		(net "I2C_DPB_B_SDA_BUF")
	)
	(segment
		(start 282.2448 -300.7614)
		(end 286.624522 -300.7614)
		(width 0.14605)
		(layer "In2.Cu")
		(net "I2C_DPB_B_SDA_BUF")
	)
	(segment
		(start 251.80544 -134.56412)
		(end 252.499622 -135.258302)
		(width 0.14605)
		(layer "In5.Cu")
		(net "I2C_DPB_B_SDA_BUF")
	)
	(segment
		(start 253.087886 -135.258302)
		(end 264.844784 -147.0152)
		(width 0.14605)
		(layer "In5.Cu")
		(net "I2C_DPB_B_SDA_BUF")
	)
	(segment
		(start 247.15978 -210.442048)
		(end 248.088912 -209.512916)
		(width 0.14605)
		(layer "In5.Cu")
		(net "I2C_DPB_B_SDA_BUF")
	)
	(segment
		(start 302.895 -114.808)
		(end 304.927 -114.808)
		(width 0.14605)
		(layer "In5.Cu")
		(net "I2C_DPB_B_SDA_BUF")
	)
	(segment
		(start 252.499622 -135.258302)
		(end 253.087886 -135.258302)
		(width 0.14605)
		(layer "In5.Cu")
		(net "I2C_DPB_B_SDA_BUF")
	)
	(segment
		(start 296.2021 -147.0152)
		(end 296.3037 -147.1168)
		(width 0.14605)
		(layer "In5.Cu")
		(net "I2C_DPB_B_SDA_BUF")
	)
	(segment
		(start 276.008084 -353.294188)
		(end 276.008084 -354.690426)
		(width 0.14605)
		(layer "In5.Cu")
		(net "I2C_DPB_B_SDA_BUF")
	)
	(segment
		(start 277.70455 -327.360534)
		(end 277.70455 -351.597722)
		(width 0.14605)
		(layer "In5.Cu")
		(net "I2C_DPB_B_SDA_BUF")
	)
	(segment
		(start 284.287468 -121.224294)
		(end 284.620716 -121.557542)
		(width 0.14605)
		(layer "In5.Cu")
		(net "I2C_DPB_B_SDA_BUF")
	)
	(segment
		(start 296.145458 -121.557542)
		(end 302.895 -114.808)
		(width 0.14605)
		(layer "In5.Cu")
		(net "I2C_DPB_B_SDA_BUF")
	)
	(segment
		(start 277.70455 -351.597722)
		(end 276.008084 -353.294188)
		(width 0.14605)
		(layer "In5.Cu")
		(net "I2C_DPB_B_SDA_BUF")
	)
	(segment
		(start 248.088912 -209.512916)
		(end 250.967748 -209.512916)
		(width 0.14605)
		(layer "In5.Cu")
		(net "I2C_DPB_B_SDA_BUF")
	)
	(segment
		(start 264.844784 -147.0152)
		(end 296.2021 -147.0152)
		(width 0.14605)
		(layer "In5.Cu")
		(net "I2C_DPB_B_SDA_BUF")
	)
	(segment
		(start 321.2338 -4.1656)
		(end 452.6026 -4.1656)
		(width 0.14605)
		(layer "In5.Cu")
		(net "I2C_DPB_B_SDA_BUF")
	)
	(segment
		(start 277.48865 -327.144634)
		(end 277.70455 -327.360534)
		(width 0.14605)
		(layer "In5.Cu")
		(net "I2C_DPB_B_SDA_BUF")
	)
	(segment
		(start 254.07112 -212.616288)
		(end 254.210058 -212.616288)
		(width 0.14605)
		(layer "In5.Cu")
		(net "I2C_DPB_B_SDA_BUF")
	)
	(segment
		(start 284.620716 -121.557542)
		(end 296.145458 -121.557542)
		(width 0.14605)
		(layer "In5.Cu")
		(net "I2C_DPB_B_SDA_BUF")
	)
	(segment
		(start 459.105 -14.4526)
		(end 459.105 -14.5796)
		(width 0.14605)
		(layer "In5.Cu")
		(net "I2C_DPB_B_SDA_BUF")
	)
	(segment
		(start 457.5048 -9.0678)
		(end 457.5048 -12.8524)
		(width 0.14605)
		(layer "In5.Cu")
		(net "I2C_DPB_B_SDA_BUF")
	)
	(segment
		(start 452.6026 -4.1656)
		(end 457.5048 -9.0678)
		(width 0.14605)
		(layer "In5.Cu")
		(net "I2C_DPB_B_SDA_BUF")
	)
	(segment
		(start 250.967748 -209.512916)
		(end 254.07112 -212.616288)
		(width 0.14605)
		(layer "In5.Cu")
		(net "I2C_DPB_B_SDA_BUF")
	)
	(segment
		(start 457.5048 -12.8524)
		(end 459.105 -14.4526)
		(width 0.14605)
		(layer "In5.Cu")
		(net "I2C_DPB_B_SDA_BUF")
	)
	(segment
		(start 237.61446 -131.9657)
		(end 237.76178 -132.11302)
		(width 0.17145)
		(layer "F.Cu")
		(net "I2C_DPB_B_SCL_BUF")
	)
	(segment
		(start 283.224732 -215.294464)
		(end 282.410154 -216.109042)
		(width 0.17145)
		(layer "F.Cu")
		(net "I2C_DPB_B_SCL_BUF")
	)
	(segment
		(start 241.493802 -133.283198)
		(end 241.340132 -133.129528)
		(width 0.17145)
		(layer "F.Cu")
		(net "I2C_DPB_B_SCL_BUF")
	)
	(segment
		(start 258.445254 -212.334348)
		(end 255.625854 -212.334348)
		(width 0.17145)
		(layer "F.Cu")
		(net "I2C_DPB_B_SCL_BUF")
	)
	(segment
		(start 238.87176 -132.11302)
		(end 239.516158 -132.757418)
		(width 0.17145)
		(layer "F.Cu")
		(net "I2C_DPB_B_SCL_BUF")
	)
	(segment
		(start 458.0636 -14.42212)
		(end 458.11948 -14.478)
		(width 0.17145)
		(layer "F.Cu")
		(net "I2C_DPB_B_SCL_BUF")
	)
	(segment
		(start 282.410154 -216.109042)
		(end 273.658584 -216.109042)
		(width 0.17145)
		(layer "F.Cu")
		(net "I2C_DPB_B_SCL_BUF")
	)
	(segment
		(start 273.658584 -216.109042)
		(end 272.467578 -217.300048)
		(width 0.17145)
		(layer "F.Cu")
		(net "I2C_DPB_B_SCL_BUF")
	)
	(segment
		(start 255.3843 -213.87054)
		(end 255.3843 -212.666326)
		(width 0.17145)
		(layer "F.Cu")
		(net "I2C_DPB_B_SCL_BUF")
	)
	(segment
		(start 239.543844 -133.129528)
		(end 239.516158 -133.101842)
		(width 0.17145)
		(layer "F.Cu")
		(net "I2C_DPB_B_SCL_BUF")
	)
	(segment
		(start 239.516158 -132.757418)
		(end 239.516158 -133.101842)
		(width 0.17145)
		(layer "F.Cu")
		(net "I2C_DPB_B_SCL_BUF")
	)
	(segment
		(start 241.986562 -133.283198)
		(end 241.77244 -133.283198)
		(width 0.17145)
		(layer "F.Cu")
		(net "I2C_DPB_B_SCL_BUF")
	)
	(segment
		(start 272.467578 -217.300048)
		(end 265.783822 -217.300048)
		(width 0.17145)
		(layer "F.Cu")
		(net "I2C_DPB_B_SCL_BUF")
	)
	(segment
		(start 246.56796 -122.047)
		(end 237.61446 -131.0005)
		(width 0.17145)
		(layer "F.Cu")
		(net "I2C_DPB_B_SCL_BUF")
	)
	(segment
		(start 265.783822 -217.300048)
		(end 261.270242 -212.786468)
		(width 0.17145)
		(layer "F.Cu")
		(net "I2C_DPB_B_SCL_BUF")
	)
	(segment
		(start 282.852622 -120.927876)
		(end 281.733498 -122.047)
		(width 0.17145)
		(layer "F.Cu")
		(net "I2C_DPB_B_SCL_BUF")
	)
	(segment
		(start 261.270242 -212.786468)
		(end 258.897374 -212.786468)
		(width 0.17145)
		(layer "F.Cu")
		(net "I2C_DPB_B_SCL_BUF")
	)
	(segment
		(start 243.007896 -133.283198)
		(end 242.978686 -133.312408)
		(width 0.17145)
		(layer "F.Cu")
		(net "I2C_DPB_B_SCL_BUF")
	)
	(segment
		(start 243.817902 -133.283198)
		(end 243.007896 -133.283198)
		(width 0.17145)
		(layer "F.Cu")
		(net "I2C_DPB_B_SCL_BUF")
	)
	(segment
		(start 258.897374 -212.786468)
		(end 258.445254 -212.334348)
		(width 0.17145)
		(layer "F.Cu")
		(net "I2C_DPB_B_SCL_BUF")
	)
	(segment
		(start 241.340132 -133.129528)
		(end 240.687098 -133.129528)
		(width 0.17145)
		(layer "F.Cu")
		(net "I2C_DPB_B_SCL_BUF")
	)
	(segment
		(start 255.3843 -212.666326)
		(end 255.339088 -212.621114)
		(width 0.17145)
		(layer "F.Cu")
		(net "I2C_DPB_B_SCL_BUF")
	)
	(segment
		(start 248.30278 -211.246212)
		(end 248.30278 -210.469226)
		(width 0.17145)
		(layer "F.Cu")
		(net "I2C_DPB_B_SCL_BUF")
	)
	(segment
		(start 279.999948 -354.399342)
		(end 277.564342 -354.399342)
		(width 0.17145)
		(layer "F.Cu")
		(net "I2C_DPB_B_SCL_BUF")
	)
	(segment
		(start 263.023604 -369.798346)
		(end 260.907022 -369.798346)
		(width 0.17145)
		(layer "F.Cu")
		(net "I2C_DPB_B_SCL_BUF")
	)
	(segment
		(start 277.564342 -354.399342)
		(end 277.114 -353.949)
		(width 0.17145)
		(layer "F.Cu")
		(net "I2C_DPB_B_SCL_BUF")
	)
	(segment
		(start 255.625854 -212.334348)
		(end 255.339088 -212.621114)
		(width 0.17145)
		(layer "F.Cu")
		(net "I2C_DPB_B_SCL_BUF")
	)
	(segment
		(start 248.30278 -210.469226)
		(end 248.329704 -210.442302)
		(width 0.17145)
		(layer "F.Cu")
		(net "I2C_DPB_B_SCL_BUF")
	)
	(segment
		(start 237.61446 -131.0005)
		(end 237.61446 -131.9657)
		(width 0.17145)
		(layer "F.Cu")
		(net "I2C_DPB_B_SCL_BUF")
	)
	(segment
		(start 281.733498 -122.047)
		(end 246.56796 -122.047)
		(width 0.17145)
		(layer "F.Cu")
		(net "I2C_DPB_B_SCL_BUF")
	)
	(segment
		(start 240.687098 -133.129528)
		(end 239.543844 -133.129528)
		(width 0.17145)
		(layer "F.Cu")
		(net "I2C_DPB_B_SCL_BUF")
	)
	(segment
		(start 241.77244 -133.283198)
		(end 241.493802 -133.283198)
		(width 0.17145)
		(layer "F.Cu")
		(net "I2C_DPB_B_SCL_BUF")
	)
	(segment
		(start 458.0636 -13.6779)
		(end 458.0636 -14.42212)
		(width 0.17145)
		(layer "F.Cu")
		(net "I2C_DPB_B_SCL_BUF")
	)
	(segment
		(start 283.23667 -215.294464)
		(end 283.224732 -215.294464)
		(width 0.17145)
		(layer "F.Cu")
		(net "I2C_DPB_B_SCL_BUF")
	)
	(segment
		(start 242.015772 -133.312408)
		(end 241.986562 -133.283198)
		(width 0.17145)
		(layer "F.Cu")
		(net "I2C_DPB_B_SCL_BUF")
	)
	(segment
		(start 242.978686 -133.312408)
		(end 242.015772 -133.312408)
		(width 0.17145)
		(layer "F.Cu")
		(net "I2C_DPB_B_SCL_BUF")
	)
	(segment
		(start 237.76178 -132.11302)
		(end 238.87176 -132.11302)
		(width 0.17145)
		(layer "F.Cu")
		(net "I2C_DPB_B_SCL_BUF")
	)
	(via
		(at 305.054 -113.538)
		(size 0.5588)
		(drill 0.3048)
		(layers "F.Cu" "B.Cu")
		(net "I2C_DPB_B_SCL_BUF")
	)
	(via
		(at 458.11948 -14.478)
		(size 0.5588)
		(drill 0.3048)
		(layers "F.Cu" "B.Cu")
		(net "I2C_DPB_B_SCL_BUF")
	)
	(via
		(at 255.339088 -212.621114)
		(size 0.5588)
		(drill 0.3048)
		(layers "F.Cu" "B.Cu")
		(net "I2C_DPB_B_SCL_BUF")
	)
	(via
		(at 248.329704 -210.442302)
		(size 0.5588)
		(drill 0.3048)
		(layers "F.Cu" "B.Cu")
		(net "I2C_DPB_B_SCL_BUF")
	)
	(via
		(at 278.45512 -327.1901)
		(size 0.5588)
		(drill 0.3048)
		(layers "F.Cu" "B.Cu")
		(net "I2C_DPB_B_SCL_BUF")
	)
	(via
		(at 277.114 -353.949)
		(size 0.5588)
		(drill 0.3048)
		(layers "F.Cu" "B.Cu")
		(net "I2C_DPB_B_SCL_BUF")
	)
	(via
		(at 237.61446 -131.9657)
		(size 0.5588)
		(drill 0.3048)
		(layers "F.Cu" "B.Cu")
		(net "I2C_DPB_B_SCL_BUF")
	)
	(via
		(at 320.3194 -4.2164)
		(size 0.5588)
		(drill 0.3048)
		(layers "F.Cu" "B.Cu")
		(net "I2C_DPB_B_SCL_BUF")
	)
	(via
		(at 282.852622 -120.927876)
		(size 0.5588)
		(drill 0.3048)
		(layers "F.Cu" "B.Cu")
		(net "I2C_DPB_B_SCL_BUF")
	)
	(via
		(at 241.77244 -133.283198)
		(size 0.6604)
		(drill 0.3302)
		(layers "F.Cu" "B.Cu")
		(net "I2C_DPB_B_SCL_BUF")
	)
	(via
		(at 263.023604 -369.798346)
		(size 0.5588)
		(drill 0.3048)
		(layers "F.Cu" "B.Cu")
		(net "I2C_DPB_B_SCL_BUF")
	)
	(via
		(at 296.95775 -147.771104)
		(size 0.5588)
		(drill 0.3048)
		(layers "F.Cu" "B.Cu")
		(net "I2C_DPB_B_SCL_BUF")
	)
	(segment
		(start 263.023604 -369.198144)
		(end 267.788136 -364.433612)
		(width 0.17145)
		(layer "B.Cu")
		(net "I2C_DPB_B_SCL_BUF")
	)
	(segment
		(start 273.072606 -353.949)
		(end 277.114 -353.949)
		(width 0.17145)
		(layer "B.Cu")
		(net "I2C_DPB_B_SCL_BUF")
	)
	(segment
		(start 267.788136 -357.778558)
		(end 270.74241 -354.824284)
		(width 0.17145)
		(layer "B.Cu")
		(net "I2C_DPB_B_SCL_BUF")
	)
	(segment
		(start 267.788136 -364.433612)
		(end 267.788136 -357.778558)
		(width 0.17145)
		(layer "B.Cu")
		(net "I2C_DPB_B_SCL_BUF")
	)
	(segment
		(start 270.74241 -354.824284)
		(end 272.197322 -354.824284)
		(width 0.17145)
		(layer "B.Cu")
		(net "I2C_DPB_B_SCL_BUF")
	)
	(segment
		(start 263.023604 -369.798346)
		(end 263.023604 -369.198144)
		(width 0.17145)
		(layer "B.Cu")
		(net "I2C_DPB_B_SCL_BUF")
	)
	(segment
		(start 272.197322 -354.824284)
		(end 273.072606 -353.949)
		(width 0.17145)
		(layer "B.Cu")
		(net "I2C_DPB_B_SCL_BUF")
	)
	(segment
		(start 297.0784 -149.5679)
		(end 297.0784 -152.948132)
		(width 0.14605)
		(layer "In2.Cu")
		(net "I2C_DPB_B_SCL_BUF")
	)
	(segment
		(start 294.935656 -293.375334)
		(end 294.935656 -271.162018)
		(width 0.14605)
		(layer "In2.Cu")
		(net "I2C_DPB_B_SCL_BUF")
	)
	(segment
		(start 296.269664 -181.95798)
		(end 290.195508 -188.032136)
		(width 0.14605)
		(layer "In2.Cu")
		(net "I2C_DPB_B_SCL_BUF")
	)
	(segment
		(start 294.935656 -271.162018)
		(end 275.764752 -251.991114)
		(width 0.14605)
		(layer "In2.Cu")
		(net "I2C_DPB_B_SCL_BUF")
	)
	(segment
		(start 297.0784 -152.948132)
		(end 296.269664 -153.756868)
		(width 0.14605)
		(layer "In2.Cu")
		(net "I2C_DPB_B_SCL_BUF")
	)
	(segment
		(start 282.438856 -216.092278)
		(end 283.23667 -215.294464)
		(width 0.14605)
		(layer "In2.Cu")
		(net "I2C_DPB_B_SCL_BUF")
	)
	(segment
		(start 296.95775 -147.771104)
		(end 296.95775 -149.44725)
		(width 0.14605)
		(layer "In2.Cu")
		(net "I2C_DPB_B_SCL_BUF")
	)
	(segment
		(start 305.271932 -113.538)
		(end 305.054 -113.538)
		(width 0.14605)
		(layer "In2.Cu")
		(net "I2C_DPB_B_SCL_BUF")
	)
	(segment
		(start 284.069028 -216.126822)
		(end 283.23667 -215.294464)
		(width 0.14605)
		(layer "In2.Cu")
		(net "I2C_DPB_B_SCL_BUF")
	)
	(segment
		(start 290.195508 -214.156036)
		(end 288.224722 -216.126822)
		(width 0.14605)
		(layer "In2.Cu")
		(net "I2C_DPB_B_SCL_BUF")
	)
	(segment
		(start 321.116198 -93.400118)
		(end 321.116198 -94.732602)
		(width 0.14605)
		(layer "In2.Cu")
		(net "I2C_DPB_B_SCL_BUF")
	)
	(segment
		(start 321.11569 -93.39961)
		(end 321.116198 -93.400118)
		(width 0.14605)
		(layer "In2.Cu")
		(net "I2C_DPB_B_SCL_BUF")
	)
	(segment
		(start 275.764752 -216.971626)
		(end 276.6441 -216.092278)
		(width 0.14605)
		(layer "In2.Cu")
		(net "I2C_DPB_B_SCL_BUF")
	)
	(segment
		(start 321.494658 -85.89645)
		(end 321.115944 -86.275164)
		(width 0.14605)
		(layer "In2.Cu")
		(net "I2C_DPB_B_SCL_BUF")
	)
	(segment
		(start 296.269664 -153.756868)
		(end 296.269664 -181.95798)
		(width 0.14605)
		(layer "In2.Cu")
		(net "I2C_DPB_B_SCL_BUF")
	)
	(segment
		(start 316.5348 -8.001)
		(end 316.5348 -53.5432)
		(width 0.14605)
		(layer "In2.Cu")
		(net "I2C_DPB_B_SCL_BUF")
	)
	(segment
		(start 321.115944 -86.275164)
		(end 321.115944 -91.952572)
		(width 0.14605)
		(layer "In2.Cu")
		(net "I2C_DPB_B_SCL_BUF")
	)
	(segment
		(start 321.116198 -94.732602)
		(end 321.494658 -95.111062)
		(width 0.14605)
		(layer "In2.Cu")
		(net "I2C_DPB_B_SCL_BUF")
	)
	(segment
		(start 321.11569 -91.952826)
		(end 321.11569 -93.39961)
		(width 0.14605)
		(layer "In2.Cu")
		(net "I2C_DPB_B_SCL_BUF")
	)
	(segment
		(start 275.764752 -251.991114)
		(end 275.764752 -216.971626)
		(width 0.14605)
		(layer "In2.Cu")
		(net "I2C_DPB_B_SCL_BUF")
	)
	(segment
		(start 321.494658 -97.315274)
		(end 305.271932 -113.538)
		(width 0.14605)
		(layer "In2.Cu")
		(net "I2C_DPB_B_SCL_BUF")
	)
	(segment
		(start 290.195508 -188.032136)
		(end 290.195508 -214.156036)
		(width 0.14605)
		(layer "In2.Cu")
		(net "I2C_DPB_B_SCL_BUF")
	)
	(segment
		(start 321.494658 -58.503058)
		(end 321.494658 -85.89645)
		(width 0.14605)
		(layer "In2.Cu")
		(net "I2C_DPB_B_SCL_BUF")
	)
	(segment
		(start 278.45512 -305.476148)
		(end 282.515564 -301.415704)
		(width 0.14605)
		(layer "In2.Cu")
		(net "I2C_DPB_B_SCL_BUF")
	)
	(segment
		(start 282.515564 -301.415704)
		(end 286.895286 -301.415704)
		(width 0.14605)
		(layer "In2.Cu")
		(net "I2C_DPB_B_SCL_BUF")
	)
	(segment
		(start 296.95775 -149.44725)
		(end 297.0784 -149.5679)
		(width 0.14605)
		(layer "In2.Cu")
		(net "I2C_DPB_B_SCL_BUF")
	)
	(segment
		(start 278.45512 -327.1901)
		(end 278.45512 -305.476148)
		(width 0.14605)
		(layer "In2.Cu")
		(net "I2C_DPB_B_SCL_BUF")
	)
	(segment
		(start 276.6441 -216.092278)
		(end 282.438856 -216.092278)
		(width 0.14605)
		(layer "In2.Cu")
		(net "I2C_DPB_B_SCL_BUF")
	)
	(segment
		(start 320.3194 -4.2164)
		(end 316.5348 -8.001)
		(width 0.14605)
		(layer "In2.Cu")
		(net "I2C_DPB_B_SCL_BUF")
	)
	(segment
		(start 316.5348 -53.5432)
		(end 321.494658 -58.503058)
		(width 0.14605)
		(layer "In2.Cu")
		(net "I2C_DPB_B_SCL_BUF")
	)
	(segment
		(start 286.895286 -301.415704)
		(end 294.935656 -293.375334)
		(width 0.14605)
		(layer "In2.Cu")
		(net "I2C_DPB_B_SCL_BUF")
	)
	(segment
		(start 288.224722 -216.126822)
		(end 284.069028 -216.126822)
		(width 0.14605)
		(layer "In2.Cu")
		(net "I2C_DPB_B_SCL_BUF")
	)
	(segment
		(start 321.115944 -91.952572)
		(end 321.11569 -91.952826)
		(width 0.14605)
		(layer "In2.Cu")
		(net "I2C_DPB_B_SCL_BUF")
	)
	(segment
		(start 321.494658 -95.111062)
		(end 321.494658 -97.315274)
		(width 0.14605)
		(layer "In2.Cu")
		(net "I2C_DPB_B_SCL_BUF")
	)
	(segment
		(start 248.329704 -210.442302)
		(end 248.569734 -210.202272)
		(width 0.14605)
		(layer "In5.Cu")
		(net "I2C_DPB_B_SCL_BUF")
	)
	(segment
		(start 278.45512 -351.77222)
		(end 277.114 -353.11334)
		(width 0.14605)
		(layer "In5.Cu")
		(net "I2C_DPB_B_SCL_BUF")
	)
	(segment
		(start 237.61446 -131.9657)
		(end 239.999266 -134.350506)
		(width 0.14605)
		(layer "In5.Cu")
		(net "I2C_DPB_B_SCL_BUF")
	)
	(segment
		(start 277.114 -353.11334)
		(end 277.114 -353.949)
		(width 0.14605)
		(layer "In5.Cu")
		(net "I2C_DPB_B_SCL_BUF")
	)
	(segment
		(start 295.679876 -120.880124)
		(end 284.868366 -120.880124)
		(width 0.14605)
		(layer "In5.Cu")
		(net "I2C_DPB_B_SCL_BUF")
	)
	(segment
		(start 252.114558 -212.150452)
		(end 252.156214 -212.150452)
		(width 0.14605)
		(layer "In5.Cu")
		(net "I2C_DPB_B_SCL_BUF")
	)
	(segment
		(start 251.109734 -211.103972)
		(end 251.818648 -211.812886)
		(width 0.14605)
		(layer "In5.Cu")
		(net "I2C_DPB_B_SCL_BUF")
	)
	(segment
		(start 252.816868 -135.912352)
		(end 264.67562 -147.771104)
		(width 0.14605)
		(layer "In5.Cu")
		(net "I2C_DPB_B_SCL_BUF")
	)
	(segment
		(start 252.195838 -135.912352)
		(end 252.816868 -135.912352)
		(width 0.14605)
		(layer "In5.Cu")
		(net "I2C_DPB_B_SCL_BUF")
	)
	(segment
		(start 320.3194 -4.2164)
		(end 320.9798 -4.8768)
		(width 0.14605)
		(layer "In5.Cu")
		(net "I2C_DPB_B_SCL_BUF")
	)
	(segment
		(start 250.732036 -210.202272)
		(end 251.109734 -210.57997)
		(width 0.14605)
		(layer "In5.Cu")
		(net "I2C_DPB_B_SCL_BUF")
	)
	(segment
		(start 253.448312 -213.44255)
		(end 254.517652 -213.44255)
		(width 0.14605)
		(layer "In5.Cu")
		(net "I2C_DPB_B_SCL_BUF")
	)
	(segment
		(start 303.022 -113.538)
		(end 295.679876 -120.880124)
		(width 0.14605)
		(layer "In5.Cu")
		(net "I2C_DPB_B_SCL_BUF")
	)
	(segment
		(start 278.45512 -327.1901)
		(end 278.45512 -351.77222)
		(width 0.14605)
		(layer "In5.Cu")
		(net "I2C_DPB_B_SCL_BUF")
	)
	(segment
		(start 284.558232 -120.56999)
		(end 283.210508 -120.56999)
		(width 0.14605)
		(layer "In5.Cu")
		(net "I2C_DPB_B_SCL_BUF")
	)
	(segment
		(start 283.210508 -120.56999)
		(end 282.852622 -120.927876)
		(width 0.14605)
		(layer "In5.Cu")
		(net "I2C_DPB_B_SCL_BUF")
	)
	(segment
		(start 251.109734 -210.57997)
		(end 251.109734 -211.103972)
		(width 0.14605)
		(layer "In5.Cu")
		(net "I2C_DPB_B_SCL_BUF")
	)
	(segment
		(start 456.7936 -9.4234)
		(end 456.7936 -13.15212)
		(width 0.14605)
		(layer "In5.Cu")
		(net "I2C_DPB_B_SCL_BUF")
	)
	(segment
		(start 305.054 -113.538)
		(end 303.022 -113.538)
		(width 0.14605)
		(layer "In5.Cu")
		(net "I2C_DPB_B_SCL_BUF")
	)
	(segment
		(start 251.818648 -211.854542)
		(end 252.114558 -212.150452)
		(width 0.14605)
		(layer "In5.Cu")
		(net "I2C_DPB_B_SCL_BUF")
	)
	(segment
		(start 264.67562 -147.771104)
		(end 296.95775 -147.771104)
		(width 0.14605)
		(layer "In5.Cu")
		(net "I2C_DPB_B_SCL_BUF")
	)
	(segment
		(start 452.247 -4.8768)
		(end 456.7936 -9.4234)
		(width 0.14605)
		(layer "In5.Cu")
		(net "I2C_DPB_B_SCL_BUF")
	)
	(segment
		(start 456.7936 -13.15212)
		(end 458.11948 -14.478)
		(width 0.14605)
		(layer "In5.Cu")
		(net "I2C_DPB_B_SCL_BUF")
	)
	(segment
		(start 252.156214 -212.150452)
		(end 253.448312 -213.44255)
		(width 0.14605)
		(layer "In5.Cu")
		(net "I2C_DPB_B_SCL_BUF")
	)
	(segment
		(start 250.633992 -134.350506)
		(end 252.195838 -135.912352)
		(width 0.14605)
		(layer "In5.Cu")
		(net "I2C_DPB_B_SCL_BUF")
	)
	(segment
		(start 284.868366 -120.880124)
		(end 284.558232 -120.56999)
		(width 0.14605)
		(layer "In5.Cu")
		(net "I2C_DPB_B_SCL_BUF")
	)
	(segment
		(start 239.999266 -134.350506)
		(end 250.633992 -134.350506)
		(width 0.14605)
		(layer "In5.Cu")
		(net "I2C_DPB_B_SCL_BUF")
	)
	(segment
		(start 251.818648 -211.812886)
		(end 251.818648 -211.854542)
		(width 0.14605)
		(layer "In5.Cu")
		(net "I2C_DPB_B_SCL_BUF")
	)
	(segment
		(start 248.569734 -210.202272)
		(end 250.732036 -210.202272)
		(width 0.14605)
		(layer "In5.Cu")
		(net "I2C_DPB_B_SCL_BUF")
	)
	(segment
		(start 320.9798 -4.8768)
		(end 452.247 -4.8768)
		(width 0.14605)
		(layer "In5.Cu")
		(net "I2C_DPB_B_SCL_BUF")
	)
	(segment
		(start 254.517652 -213.44255)
		(end 255.339088 -212.621114)
		(width 0.14605)
		(layer "In5.Cu")
		(net "I2C_DPB_B_SCL_BUF")
	)
	(segment
		(start 211.800186 -74.200004)
		(end 211.165694 -74.834496)
		(width 0.17145)
		(layer "F.Cu")
		(net "I2C_DPB_A_SDA_BUF")
	)
	(segment
		(start 248.7295 -304.038)
		(end 249.555 -304.038)
		(width 0.17145)
		(layer "F.Cu")
		(net "I2C_DPB_A_SDA_BUF")
	)
	(segment
		(start 37.4777 -11.2776)
		(end 38.4048 -11.2776)
		(width 0.17145)
		(layer "F.Cu")
		(net "I2C_DPB_A_SDA_BUF")
	)
	(segment
		(start 211.165694 -74.834496)
		(end 211.165694 -79.198724)
		(width 0.17145)
		(layer "F.Cu")
		(net "I2C_DPB_A_SDA_BUF")
	)
	(segment
		(start 211.165694 -79.198724)
		(end 211.442808 -79.475838)
		(width 0.17145)
		(layer "F.Cu")
		(net "I2C_DPB_A_SDA_BUF")
	)
	(segment
		(start 211.442808 -110.273084)
		(end 207.07477 -114.641122)
		(width 0.17145)
		(layer "F.Cu")
		(net "I2C_DPB_A_SDA_BUF")
	)
	(segment
		(start 211.442808 -79.475838)
		(end 211.442808 -110.273084)
		(width 0.17145)
		(layer "F.Cu")
		(net "I2C_DPB_A_SDA_BUF")
	)
	(via
		(at 181.66207 -6.861048)
		(size 0.5588)
		(drill 0.3048)
		(layers "F.Cu" "B.Cu")
		(net "I2C_DPB_A_SDA_BUF")
	)
	(via
		(at 207.07477 -114.641122)
		(size 0.5588)
		(drill 0.3048)
		(layers "F.Cu" "B.Cu")
		(net "I2C_DPB_A_SDA_BUF")
	)
	(via
		(at 249.555 -304.038)
		(size 0.5588)
		(drill 0.3048)
		(layers "F.Cu" "B.Cu")
		(net "I2C_DPB_A_SDA_BUF")
	)
	(via
		(at 38.4048 -11.2776)
		(size 0.5588)
		(drill 0.3048)
		(layers "F.Cu" "B.Cu")
		(net "I2C_DPB_A_SDA_BUF")
	)
	(via
		(at 202.92568 -292.227)
		(size 0.5588)
		(drill 0.3048)
		(layers "F.Cu" "B.Cu")
		(net "I2C_DPB_A_SDA_BUF")
	)
	(via
		(at 241.737642 -299.102526)
		(size 0.6096)
		(drill 0.3048)
		(layers "F.Cu" "B.Cu")
		(net "I2C_DPB_A_SDA_BUF")
	)
	(segment
		(start 249.555 -303.0474)
		(end 245.610126 -299.102526)
		(width 0.17145)
		(layer "B.Cu")
		(net "I2C_DPB_A_SDA_BUF")
	)
	(segment
		(start 245.610126 -299.102526)
		(end 241.737642 -299.102526)
		(width 0.17145)
		(layer "B.Cu")
		(net "I2C_DPB_A_SDA_BUF")
	)
	(segment
		(start 202.92568 -292.227)
		(end 229.230428 -292.227)
		(width 0.17145)
		(layer "B.Cu")
		(net "I2C_DPB_A_SDA_BUF")
	)
	(segment
		(start 236.105954 -299.102526)
		(end 241.737642 -299.102526)
		(width 0.17145)
		(layer "B.Cu")
		(net "I2C_DPB_A_SDA_BUF")
	)
	(segment
		(start 229.230428 -292.227)
		(end 236.105954 -299.102526)
		(width 0.17145)
		(layer "B.Cu")
		(net "I2C_DPB_A_SDA_BUF")
	)
	(segment
		(start 249.555 -304.038)
		(end 249.555 -303.0474)
		(width 0.17145)
		(layer "B.Cu")
		(net "I2C_DPB_A_SDA_BUF")
	)
	(segment
		(start 185.45683 -11.641074)
		(end 181.66207 -7.846314)
		(width 0.14605)
		(layer "In2.Cu")
		(net "I2C_DPB_A_SDA_BUF")
	)
	(segment
		(start 203.362306 -252.194314)
		(end 203.36256 -252.19406)
		(width 0.14605)
		(layer "In2.Cu")
		(net "I2C_DPB_A_SDA_BUF")
	)
	(segment
		(start 204.181456 -236.735112)
		(end 204.838554 -236.078014)
		(width 0.14605)
		(layer "In2.Cu")
		(net "I2C_DPB_A_SDA_BUF")
	)
	(segment
		(start 185.45683 -20.767294)
		(end 185.45683 -11.641074)
		(width 0.14605)
		(layer "In2.Cu")
		(net "I2C_DPB_A_SDA_BUF")
	)
	(segment
		(start 203.383896 -245.38178)
		(end 204.181456 -244.58422)
		(width 0.14605)
		(layer "In2.Cu")
		(net "I2C_DPB_A_SDA_BUF")
	)
	(segment
		(start 208.907888 -203.208382)
		(end 208.907888 -169.111422)
		(width 0.14605)
		(layer "In2.Cu")
		(net "I2C_DPB_A_SDA_BUF")
	)
	(segment
		(start 203.362306 -245.403116)
		(end 203.383642 -245.38178)
		(width 0.14605)
		(layer "In2.Cu")
		(net "I2C_DPB_A_SDA_BUF")
	)
	(segment
		(start 209.48523 -208.9531)
		(end 209.48523 -203.785724)
		(width 0.14605)
		(layer "In2.Cu")
		(net "I2C_DPB_A_SDA_BUF")
	)
	(segment
		(start 207.07477 -157.22346)
		(end 207.07477 -114.641122)
		(width 0.14605)
		(layer "In2.Cu")
		(net "I2C_DPB_A_SDA_BUF")
	)
	(segment
		(start 208.247996 -158.396686)
		(end 207.07477 -157.22346)
		(width 0.14605)
		(layer "In2.Cu")
		(net "I2C_DPB_A_SDA_BUF")
	)
	(segment
		(start 208.437226 -216.276682)
		(end 208.437226 -210.001104)
		(width 0.14605)
		(layer "In2.Cu")
		(net "I2C_DPB_A_SDA_BUF")
	)
	(segment
		(start 185.845958 -21.159978)
		(end 185.550048 -20.864068)
		(width 0.14605)
		(layer "In2.Cu")
		(net "I2C_DPB_A_SDA_BUF")
	)
	(segment
		(start 208.247996 -168.45153)
		(end 208.247996 -158.396686)
		(width 0.14605)
		(layer "In2.Cu")
		(net "I2C_DPB_A_SDA_BUF")
	)
	(segment
		(start 203.055474 -74.027792)
		(end 193.56705 -64.539368)
		(width 0.14605)
		(layer "In2.Cu")
		(net "I2C_DPB_A_SDA_BUF")
	)
	(segment
		(start 208.16443 -216.549224)
		(end 208.164684 -216.549224)
		(width 0.14605)
		(layer "In2.Cu")
		(net "I2C_DPB_A_SDA_BUF")
	)
	(segment
		(start 193.56705 -28.877514)
		(end 185.849514 -21.159978)
		(width 0.14605)
		(layer "In2.Cu")
		(net "I2C_DPB_A_SDA_BUF")
	)
	(segment
		(start 208.164684 -216.549224)
		(end 208.437226 -216.276682)
		(width 0.14605)
		(layer "In2.Cu")
		(net "I2C_DPB_A_SDA_BUF")
	)
	(segment
		(start 204.838554 -225.175572)
		(end 207.749648 -222.264478)
		(width 0.14605)
		(layer "In2.Cu")
		(net "I2C_DPB_A_SDA_BUF")
	)
	(segment
		(start 185.849514 -21.159978)
		(end 185.845958 -21.159978)
		(width 0.14605)
		(layer "In2.Cu")
		(net "I2C_DPB_A_SDA_BUF")
	)
	(segment
		(start 203.055474 -109.53242)
		(end 203.055474 -74.027792)
		(width 0.14605)
		(layer "In2.Cu")
		(net "I2C_DPB_A_SDA_BUF")
	)
	(segment
		(start 209.48523 -203.785724)
		(end 208.907888 -203.208382)
		(width 0.14605)
		(layer "In2.Cu")
		(net "I2C_DPB_A_SDA_BUF")
	)
	(segment
		(start 193.56705 -64.539368)
		(end 193.56705 -28.877514)
		(width 0.14605)
		(layer "In2.Cu")
		(net "I2C_DPB_A_SDA_BUF")
	)
	(segment
		(start 185.550048 -20.864068)
		(end 185.550048 -20.860512)
		(width 0.14605)
		(layer "In2.Cu")
		(net "I2C_DPB_A_SDA_BUF")
	)
	(segment
		(start 185.550048 -20.860512)
		(end 185.45683 -20.767294)
		(width 0.14605)
		(layer "In2.Cu")
		(net "I2C_DPB_A_SDA_BUF")
	)
	(segment
		(start 203.362306 -291.790374)
		(end 203.362306 -252.194314)
		(width 0.14605)
		(layer "In2.Cu")
		(net "I2C_DPB_A_SDA_BUF")
	)
	(segment
		(start 207.07477 -113.551716)
		(end 203.055474 -109.53242)
		(width 0.14605)
		(layer "In2.Cu")
		(net "I2C_DPB_A_SDA_BUF")
	)
	(segment
		(start 204.181456 -244.58422)
		(end 204.181456 -236.735112)
		(width 0.14605)
		(layer "In2.Cu")
		(net "I2C_DPB_A_SDA_BUF")
	)
	(segment
		(start 203.36256 -246.690388)
		(end 203.362306 -246.690134)
		(width 0.14605)
		(layer "In2.Cu")
		(net "I2C_DPB_A_SDA_BUF")
	)
	(segment
		(start 207.749902 -216.963752)
		(end 208.16443 -216.549224)
		(width 0.14605)
		(layer "In2.Cu")
		(net "I2C_DPB_A_SDA_BUF")
	)
	(segment
		(start 207.749902 -216.964006)
		(end 207.749902 -216.963752)
		(width 0.14605)
		(layer "In2.Cu")
		(net "I2C_DPB_A_SDA_BUF")
	)
	(segment
		(start 208.907888 -169.111422)
		(end 208.247996 -168.45153)
		(width 0.14605)
		(layer "In2.Cu")
		(net "I2C_DPB_A_SDA_BUF")
	)
	(segment
		(start 203.362306 -246.690134)
		(end 203.362306 -245.403116)
		(width 0.14605)
		(layer "In2.Cu")
		(net "I2C_DPB_A_SDA_BUF")
	)
	(segment
		(start 208.437226 -210.001104)
		(end 209.48523 -208.9531)
		(width 0.14605)
		(layer "In2.Cu")
		(net "I2C_DPB_A_SDA_BUF")
	)
	(segment
		(start 203.36256 -252.19406)
		(end 203.36256 -246.690388)
		(width 0.14605)
		(layer "In2.Cu")
		(net "I2C_DPB_A_SDA_BUF")
	)
	(segment
		(start 202.92568 -292.227)
		(end 203.362306 -291.790374)
		(width 0.14605)
		(layer "In2.Cu")
		(net "I2C_DPB_A_SDA_BUF")
	)
	(segment
		(start 207.749648 -222.264478)
		(end 207.749648 -216.96426)
		(width 0.14605)
		(layer "In2.Cu")
		(net "I2C_DPB_A_SDA_BUF")
	)
	(segment
		(start 203.383642 -245.38178)
		(end 203.383896 -245.38178)
		(width 0.14605)
		(layer "In2.Cu")
		(net "I2C_DPB_A_SDA_BUF")
	)
	(segment
		(start 207.07477 -114.641122)
		(end 207.07477 -113.551716)
		(width 0.14605)
		(layer "In2.Cu")
		(net "I2C_DPB_A_SDA_BUF")
	)
	(segment
		(start 181.66207 -7.846314)
		(end 181.66207 -6.861048)
		(width 0.14605)
		(layer "In2.Cu")
		(net "I2C_DPB_A_SDA_BUF")
	)
	(segment
		(start 207.749648 -216.96426)
		(end 207.749902 -216.964006)
		(width 0.14605)
		(layer "In2.Cu")
		(net "I2C_DPB_A_SDA_BUF")
	)
	(segment
		(start 204.838554 -236.078014)
		(end 204.838554 -225.175572)
		(width 0.14605)
		(layer "In2.Cu")
		(net "I2C_DPB_A_SDA_BUF")
	)
	(segment
		(start 179.984146 -5.183124)
		(end 181.66207 -6.861048)
		(width 0.14605)
		(layer "In5.Cu")
		(net "I2C_DPB_A_SDA_BUF")
	)
	(segment
		(start 38.7096 -11.2776)
		(end 41.85031 -8.13689)
		(width 0.14605)
		(layer "In5.Cu")
		(net "I2C_DPB_A_SDA_BUF")
	)
	(segment
		(start 48.722026 -8.13689)
		(end 51.675792 -5.183124)
		(width 0.14605)
		(layer "In5.Cu")
		(net "I2C_DPB_A_SDA_BUF")
	)
	(segment
		(start 51.675792 -5.183124)
		(end 179.984146 -5.183124)
		(width 0.14605)
		(layer "In5.Cu")
		(net "I2C_DPB_A_SDA_BUF")
	)
	(segment
		(start 41.85031 -8.13689)
		(end 48.722026 -8.13689)
		(width 0.14605)
		(layer "In5.Cu")
		(net "I2C_DPB_A_SDA_BUF")
	)
	(segment
		(start 38.4048 -11.2776)
		(end 38.7096 -11.2776)
		(width 0.14605)
		(layer "In5.Cu")
		(net "I2C_DPB_A_SDA_BUF")
	)
	(segment
		(start 210.131152 -110.320836)
		(end 209.814668 -110.320836)
		(width 0.17145)
		(layer "F.Cu")
		(net "I2C_DPB_A_SCL_BUF")
	)
	(segment
		(start 210.688936 -109.446568)
		(end 210.688936 -109.763052)
		(width 0.17145)
		(layer "F.Cu")
		(net "I2C_DPB_A_SCL_BUF")
	)
	(segment
		(start 210.689444 -109.44606)
		(end 210.688936 -109.446568)
		(width 0.17145)
		(layer "F.Cu")
		(net "I2C_DPB_A_SCL_BUF")
	)
	(segment
		(start 210.638644 -73.961498)
		(end 210.638644 -79.417164)
		(width 0.17145)
		(layer "F.Cu")
		(net "I2C_DPB_A_SCL_BUF")
	)
	(segment
		(start 37.4777 -12.319)
		(end 38.4048 -12.319)
		(width 0.17145)
		(layer "F.Cu")
		(net "I2C_DPB_A_SCL_BUF")
	)
	(segment
		(start 248.7295 -305.054)
		(end 249.555 -305.054)
		(width 0.17145)
		(layer "F.Cu")
		(net "I2C_DPB_A_SCL_BUF")
	)
	(segment
		(start 210.688936 -109.763052)
		(end 210.131152 -110.320836)
		(width 0.17145)
		(layer "F.Cu")
		(net "I2C_DPB_A_SCL_BUF")
	)
	(segment
		(start 210.638644 -79.417164)
		(end 210.689444 -79.467964)
		(width 0.17145)
		(layer "F.Cu")
		(net "I2C_DPB_A_SCL_BUF")
	)
	(segment
		(start 210.689444 -79.467964)
		(end 210.689444 -109.44606)
		(width 0.17145)
		(layer "F.Cu")
		(net "I2C_DPB_A_SCL_BUF")
	)
	(segment
		(start 211.800186 -72.799956)
		(end 210.638644 -73.961498)
		(width 0.17145)
		(layer "F.Cu")
		(net "I2C_DPB_A_SCL_BUF")
	)
	(segment
		(start 209.814668 -110.320836)
		(end 206.319628 -113.815876)
		(width 0.17145)
		(layer "F.Cu")
		(net "I2C_DPB_A_SCL_BUF")
	)
	(via
		(at 180.683408 -6.82625)
		(size 0.5588)
		(drill 0.3048)
		(layers "F.Cu" "B.Cu")
		(net "I2C_DPB_A_SCL_BUF")
	)
	(via
		(at 249.555 -305.054)
		(size 0.5588)
		(drill 0.3048)
		(layers "F.Cu" "B.Cu")
		(net "I2C_DPB_A_SCL_BUF")
	)
	(via
		(at 201.9554 -292.2016)
		(size 0.5588)
		(drill 0.3048)
		(layers "F.Cu" "B.Cu")
		(net "I2C_DPB_A_SCL_BUF")
	)
	(via
		(at 239.129824 -300.358048)
		(size 0.6096)
		(drill 0.3048)
		(layers "F.Cu" "B.Cu")
		(net "I2C_DPB_A_SCL_BUF")
	)
	(via
		(at 38.4048 -12.319)
		(size 0.5588)
		(drill 0.3048)
		(layers "F.Cu" "B.Cu")
		(net "I2C_DPB_A_SCL_BUF")
	)
	(via
		(at 206.319628 -113.815876)
		(size 0.5588)
		(drill 0.3048)
		(layers "F.Cu" "B.Cu")
		(net "I2C_DPB_A_SCL_BUF")
	)
	(segment
		(start 236.244638 -300.358048)
		(end 229.319836 -293.433246)
		(width 0.17145)
		(layer "B.Cu")
		(net "I2C_DPB_A_SCL_BUF")
	)
	(segment
		(start 239.129824 -300.358048)
		(end 236.244638 -300.358048)
		(width 0.17145)
		(layer "B.Cu")
		(net "I2C_DPB_A_SCL_BUF")
	)
	(segment
		(start 229.319836 -293.433246)
		(end 203.187046 -293.433246)
		(width 0.17145)
		(layer "B.Cu")
		(net "I2C_DPB_A_SCL_BUF")
	)
	(segment
		(start 248.8184 -304.3174)
		(end 248.8184 -303.3268)
		(width 0.17145)
		(layer "B.Cu")
		(net "I2C_DPB_A_SCL_BUF")
	)
	(segment
		(start 203.187046 -293.433246)
		(end 201.9554 -292.2016)
		(width 0.17145)
		(layer "B.Cu")
		(net "I2C_DPB_A_SCL_BUF")
	)
	(segment
		(start 245.849648 -300.358048)
		(end 239.129824 -300.358048)
		(width 0.17145)
		(layer "B.Cu")
		(net "I2C_DPB_A_SCL_BUF")
	)
	(segment
		(start 248.8184 -303.3268)
		(end 245.849648 -300.358048)
		(width 0.17145)
		(layer "B.Cu")
		(net "I2C_DPB_A_SCL_BUF")
	)
	(segment
		(start 249.555 -305.054)
		(end 248.8184 -304.3174)
		(width 0.17145)
		(layer "B.Cu")
		(net "I2C_DPB_A_SCL_BUF")
	)
	(segment
		(start 202.70851 -251.923042)
		(end 202.70851 -246.961406)
		(width 0.14605)
		(layer "In2.Cu")
		(net "I2C_DPB_A_SCL_BUF")
	)
	(segment
		(start 180.683408 -7.792974)
		(end 180.683408 -6.82625)
		(width 0.14605)
		(layer "In2.Cu")
		(net "I2C_DPB_A_SCL_BUF")
	)
	(segment
		(start 202.70851 -246.961406)
		(end 202.708256 -246.961152)
		(width 0.14605)
		(layer "In2.Cu")
		(net "I2C_DPB_A_SCL_BUF")
	)
	(segment
		(start 202.401424 -74.451464)
		(end 192.913 -64.96304)
		(width 0.14605)
		(layer "In2.Cu")
		(net "I2C_DPB_A_SCL_BUF")
	)
	(segment
		(start 192.913 -64.96304)
		(end 192.913 -29.148532)
		(width 0.14605)
		(layer "In2.Cu")
		(net "I2C_DPB_A_SCL_BUF")
	)
	(segment
		(start 207.783176 -216.00541)
		(end 207.783176 -209.730086)
		(width 0.14605)
		(layer "In2.Cu")
		(net "I2C_DPB_A_SCL_BUF")
	)
	(segment
		(start 202.708256 -246.961152)
		(end 202.708256 -245.132098)
		(width 0.14605)
		(layer "In2.Cu")
		(net "I2C_DPB_A_SCL_BUF")
	)
	(segment
		(start 207.095598 -221.99346)
		(end 207.095598 -216.693242)
		(width 0.14605)
		(layer "In2.Cu")
		(net "I2C_DPB_A_SCL_BUF")
	)
	(segment
		(start 201.9554 -292.2016)
		(end 201.9554 -292.22319)
		(width 0.14605)
		(layer "In2.Cu")
		(net "I2C_DPB_A_SCL_BUF")
	)
	(segment
		(start 203.527406 -244.313202)
		(end 203.527406 -236.46384)
		(width 0.14605)
		(layer "In2.Cu")
		(net "I2C_DPB_A_SCL_BUF")
	)
	(segment
		(start 208.83118 -204.056742)
		(end 208.253838 -203.4794)
		(width 0.14605)
		(layer "In2.Cu")
		(net "I2C_DPB_A_SCL_BUF")
	)
	(segment
		(start 208.253838 -169.38244)
		(end 207.593946 -168.722548)
		(width 0.14605)
		(layer "In2.Cu")
		(net "I2C_DPB_A_SCL_BUF")
	)
	(segment
		(start 204.184504 -235.806742)
		(end 204.184504 -224.904554)
		(width 0.14605)
		(layer "In2.Cu")
		(net "I2C_DPB_A_SCL_BUF")
	)
	(segment
		(start 185.578496 -21.814028)
		(end 185.57494 -21.814028)
		(width 0.14605)
		(layer "In2.Cu")
		(net "I2C_DPB_A_SCL_BUF")
	)
	(segment
		(start 183.753506 -10.863072)
		(end 180.683408 -7.792974)
		(width 0.14605)
		(layer "In2.Cu")
		(net "I2C_DPB_A_SCL_BUF")
	)
	(segment
		(start 201.9554 -292.22319)
		(end 202.708256 -291.470334)
		(width 0.14605)
		(layer "In2.Cu")
		(net "I2C_DPB_A_SCL_BUF")
	)
	(segment
		(start 202.708256 -245.132098)
		(end 203.112624 -244.72773)
		(width 0.14605)
		(layer "In2.Cu")
		(net "I2C_DPB_A_SCL_BUF")
	)
	(segment
		(start 207.783176 -209.730086)
		(end 208.83118 -208.682082)
		(width 0.14605)
		(layer "In2.Cu")
		(net "I2C_DPB_A_SCL_BUF")
	)
	(segment
		(start 207.095598 -216.693242)
		(end 207.095852 -216.692988)
		(width 0.14605)
		(layer "In2.Cu")
		(net "I2C_DPB_A_SCL_BUF")
	)
	(segment
		(start 206.42072 -113.916968)
		(end 206.319628 -113.815876)
		(width 0.14605)
		(layer "In2.Cu")
		(net "I2C_DPB_A_SCL_BUF")
	)
	(segment
		(start 203.112878 -244.72773)
		(end 203.527406 -244.313202)
		(width 0.14605)
		(layer "In2.Cu")
		(net "I2C_DPB_A_SCL_BUF")
	)
	(segment
		(start 207.593946 -168.722548)
		(end 207.593946 -158.667704)
		(width 0.14605)
		(layer "In2.Cu")
		(net "I2C_DPB_A_SCL_BUF")
	)
	(segment
		(start 184.80278 -21.038312)
		(end 184.80278 -11.912092)
		(width 0.14605)
		(layer "In2.Cu")
		(net "I2C_DPB_A_SCL_BUF")
	)
	(segment
		(start 184.80278 -11.912092)
		(end 183.75376 -10.863072)
		(width 0.14605)
		(layer "In2.Cu")
		(net "I2C_DPB_A_SCL_BUF")
	)
	(segment
		(start 183.75376 -10.863072)
		(end 183.753506 -10.863072)
		(width 0.14605)
		(layer "In2.Cu")
		(net "I2C_DPB_A_SCL_BUF")
	)
	(segment
		(start 207.095852 -216.692734)
		(end 207.783176 -216.00541)
		(width 0.14605)
		(layer "In2.Cu")
		(net "I2C_DPB_A_SCL_BUF")
	)
	(segment
		(start 206.319628 -113.721642)
		(end 202.401424 -109.803438)
		(width 0.14605)
		(layer "In2.Cu")
		(net "I2C_DPB_A_SCL_BUF")
	)
	(segment
		(start 202.708256 -251.923296)
		(end 202.70851 -251.923042)
		(width 0.14605)
		(layer "In2.Cu")
		(net "I2C_DPB_A_SCL_BUF")
	)
	(segment
		(start 184.895998 -21.13153)
		(end 184.80278 -21.038312)
		(width 0.14605)
		(layer "In2.Cu")
		(net "I2C_DPB_A_SCL_BUF")
	)
	(segment
		(start 207.593946 -158.667704)
		(end 206.42072 -157.494478)
		(width 0.14605)
		(layer "In2.Cu")
		(net "I2C_DPB_A_SCL_BUF")
	)
	(segment
		(start 203.527406 -236.46384)
		(end 204.184504 -235.806742)
		(width 0.14605)
		(layer "In2.Cu")
		(net "I2C_DPB_A_SCL_BUF")
	)
	(segment
		(start 202.708256 -291.470334)
		(end 202.708256 -251.923296)
		(width 0.14605)
		(layer "In2.Cu")
		(net "I2C_DPB_A_SCL_BUF")
	)
	(segment
		(start 203.112624 -244.72773)
		(end 203.112878 -244.72773)
		(width 0.14605)
		(layer "In2.Cu")
		(net "I2C_DPB_A_SCL_BUF")
	)
	(segment
		(start 185.57494 -21.814028)
		(end 184.895998 -21.135086)
		(width 0.14605)
		(layer "In2.Cu")
		(net "I2C_DPB_A_SCL_BUF")
	)
	(segment
		(start 184.895998 -21.135086)
		(end 184.895998 -21.13153)
		(width 0.14605)
		(layer "In2.Cu")
		(net "I2C_DPB_A_SCL_BUF")
	)
	(segment
		(start 208.253838 -203.4794)
		(end 208.253838 -169.38244)
		(width 0.14605)
		(layer "In2.Cu")
		(net "I2C_DPB_A_SCL_BUF")
	)
	(segment
		(start 204.184504 -224.904554)
		(end 207.095598 -221.99346)
		(width 0.14605)
		(layer "In2.Cu")
		(net "I2C_DPB_A_SCL_BUF")
	)
	(segment
		(start 206.42072 -157.494478)
		(end 206.42072 -113.916968)
		(width 0.14605)
		(layer "In2.Cu")
		(net "I2C_DPB_A_SCL_BUF")
	)
	(segment
		(start 192.913 -29.148532)
		(end 185.578496 -21.814028)
		(width 0.14605)
		(layer "In2.Cu")
		(net "I2C_DPB_A_SCL_BUF")
	)
	(segment
		(start 206.319628 -113.815876)
		(end 206.319628 -113.721642)
		(width 0.14605)
		(layer "In2.Cu")
		(net "I2C_DPB_A_SCL_BUF")
	)
	(segment
		(start 207.095852 -216.692988)
		(end 207.095852 -216.692734)
		(width 0.14605)
		(layer "In2.Cu")
		(net "I2C_DPB_A_SCL_BUF")
	)
	(segment
		(start 202.401424 -109.803438)
		(end 202.401424 -74.451464)
		(width 0.14605)
		(layer "In2.Cu")
		(net "I2C_DPB_A_SCL_BUF")
	)
	(segment
		(start 208.83118 -208.682082)
		(end 208.83118 -204.056742)
		(width 0.14605)
		(layer "In2.Cu")
		(net "I2C_DPB_A_SCL_BUF")
	)
	(segment
		(start 52.018184 -6.009132)
		(end 179.86629 -6.009132)
		(width 0.14605)
		(layer "In5.Cu")
		(net "I2C_DPB_A_SCL_BUF")
	)
	(segment
		(start 38.4048 -12.319)
		(end 38.8366 -12.319)
		(width 0.14605)
		(layer "In5.Cu")
		(net "I2C_DPB_A_SCL_BUF")
	)
	(segment
		(start 38.8366 -12.319)
		(end 42.192702 -8.962898)
		(width 0.14605)
		(layer "In5.Cu")
		(net "I2C_DPB_A_SCL_BUF")
	)
	(segment
		(start 42.192702 -8.962898)
		(end 49.064418 -8.962898)
		(width 0.14605)
		(layer "In5.Cu")
		(net "I2C_DPB_A_SCL_BUF")
	)
	(segment
		(start 179.86629 -6.009132)
		(end 180.683408 -6.82625)
		(width 0.14605)
		(layer "In5.Cu")
		(net "I2C_DPB_A_SCL_BUF")
	)
	(segment
		(start 49.064418 -8.962898)
		(end 52.018184 -6.009132)
		(width 0.14605)
		(layer "In5.Cu")
		(net "I2C_DPB_A_SCL_BUF")
	)
	(segment
		(start 259.98678 -111.05642)
		(end 264.70356 -115.7732)
		(width 0.17145)
		(layer "F.Cu")
		(net "DPB_PWR_BTN_BUF_B")
	)
	(segment
		(start 254.561086 -109.171994)
		(end 256.445512 -111.05642)
		(width 0.17145)
		(layer "F.Cu")
		(net "DPB_PWR_BTN_BUF_B")
	)
	(segment
		(start 266.332462 -367.893346)
		(end 265.075924 -367.893346)
		(width 0.17145)
		(layer "F.Cu")
		(net "DPB_PWR_BTN_BUF_B")
	)
	(segment
		(start 264.70356 -115.7732)
		(end 278.1554 -115.7732)
		(width 0.17145)
		(layer "F.Cu")
		(net "DPB_PWR_BTN_BUF_B")
	)
	(segment
		(start 254.561086 -109.169962)
		(end 254.561086 -109.171994)
		(width 0.17145)
		(layer "F.Cu")
		(net "DPB_PWR_BTN_BUF_B")
	)
	(segment
		(start 256.445512 -111.05642)
		(end 258.205478 -111.05642)
		(width 0.17145)
		(layer "F.Cu")
		(net "DPB_PWR_BTN_BUF_B")
	)
	(segment
		(start 260.970522 -366.940846)
		(end 260.970522 -367.639346)
		(width 0.17145)
		(layer "F.Cu")
		(net "DPB_PWR_BTN_BUF_B")
	)
	(segment
		(start 258.205478 -111.05642)
		(end 259.98678 -111.05642)
		(width 0.17145)
		(layer "F.Cu")
		(net "DPB_PWR_BTN_BUF_B")
	)
	(segment
		(start 260.970522 -367.639346)
		(end 261.224522 -367.893346)
		(width 0.17145)
		(layer "F.Cu")
		(net "DPB_PWR_BTN_BUF_B")
	)
	(segment
		(start 263.728962 -367.893346)
		(end 265.075924 -367.893346)
		(width 0.17145)
		(layer "F.Cu")
		(net "DPB_PWR_BTN_BUF_B")
	)
	(segment
		(start 241.514122 -96.222058)
		(end 241.514122 -96.122998)
		(width 0.17145)
		(layer "F.Cu")
		(net "DPB_PWR_BTN_BUF_B")
	)
	(segment
		(start 241.514122 -96.122998)
		(end 254.561086 -109.169962)
		(width 0.17145)
		(layer "F.Cu")
		(net "DPB_PWR_BTN_BUF_B")
	)
	(segment
		(start 261.224522 -367.893346)
		(end 263.728962 -367.893346)
		(width 0.17145)
		(layer "F.Cu")
		(net "DPB_PWR_BTN_BUF_B")
	)
	(via
		(at 278.1554 -115.7732)
		(size 0.5588)
		(drill 0.3048)
		(layers "F.Cu" "B.Cu")
		(net "DPB_PWR_BTN_BUF_B")
	)
	(via
		(at 258.205478 -111.05642)
		(size 0.6604)
		(drill 0.3302)
		(layers "F.Cu" "B.Cu")
		(net "DPB_PWR_BTN_BUF_B")
	)
	(via
		(at 266.332462 -367.893346)
		(size 0.5588)
		(drill 0.3048)
		(layers "F.Cu" "B.Cu")
		(net "DPB_PWR_BTN_BUF_B")
	)
	(via
		(at 279.8064 -242.2398)
		(size 0.5588)
		(drill 0.3048)
		(layers "F.Cu" "B.Cu")
		(net "DPB_PWR_BTN_BUF_B")
	)
	(via
		(at 241.514122 -96.222058)
		(size 0.5588)
		(drill 0.3048)
		(layers "F.Cu" "B.Cu")
		(net "DPB_PWR_BTN_BUF_B")
	)
	(segment
		(start 226.200208 -76.542392)
		(end 225.5774 -77.1652)
		(width 0.17145)
		(layer "B.Cu")
		(net "DPB_PWR_BTN_BUF_B")
	)
	(segment
		(start 226.200208 -76.499974)
		(end 226.200208 -76.542392)
		(width 0.17145)
		(layer "B.Cu")
		(net "DPB_PWR_BTN_BUF_B")
	)
	(segment
		(start 235.12145 -88.993726)
		(end 235.587286 -89.459562)
		(width 0.17145)
		(layer "B.Cu")
		(net "DPB_PWR_BTN_BUF_B")
	)
	(segment
		(start 241.514122 -95.337122)
		(end 241.514122 -96.222058)
		(width 0.17145)
		(layer "B.Cu")
		(net "DPB_PWR_BTN_BUF_B")
	)
	(segment
		(start 235.636562 -89.459562)
		(end 241.514122 -95.337122)
		(width 0.17145)
		(layer "B.Cu")
		(net "DPB_PWR_BTN_BUF_B")
	)
	(segment
		(start 225.5774 -77.1652)
		(end 225.5774 -82.789522)
		(width 0.17145)
		(layer "B.Cu")
		(net "DPB_PWR_BTN_BUF_B")
	)
	(segment
		(start 235.587286 -89.459562)
		(end 235.636562 -89.459562)
		(width 0.17145)
		(layer "B.Cu")
		(net "DPB_PWR_BTN_BUF_B")
	)
	(segment
		(start 225.5774 -82.789522)
		(end 231.781604 -88.993726)
		(width 0.17145)
		(layer "B.Cu")
		(net "DPB_PWR_BTN_BUF_B")
	)
	(segment
		(start 231.781604 -88.993726)
		(end 235.12145 -88.993726)
		(width 0.17145)
		(layer "B.Cu")
		(net "DPB_PWR_BTN_BUF_B")
	)
	(segment
		(start 301.510446 -187.752736)
		(end 301.924974 -187.338208)
		(width 0.14605)
		(layer "In2.Cu")
		(net "DPB_PWR_BTN_BUF_B")
	)
	(segment
		(start 301.095664 -188.167264)
		(end 301.510192 -187.752736)
		(width 0.14605)
		(layer "In2.Cu")
		(net "DPB_PWR_BTN_BUF_B")
	)
	(segment
		(start 301.955962 -185.692288)
		(end 301.924974 -185.6613)
		(width 0.14605)
		(layer "In2.Cu")
		(net "DPB_PWR_BTN_BUF_B")
	)
	(segment
		(start 295.70045 -233.908854)
		(end 295.70045 -233.654346)
		(width 0.14605)
		(layer "In2.Cu")
		(net "DPB_PWR_BTN_BUF_B")
	)
	(segment
		(start 301.924974 -187.3377)
		(end 301.955962 -187.306712)
		(width 0.14605)
		(layer "In2.Cu")
		(net "DPB_PWR_BTN_BUF_B")
	)
	(segment
		(start 279.84323 -115.496848)
		(end 278.431752 -115.496848)
		(width 0.14605)
		(layer "In2.Cu")
		(net "DPB_PWR_BTN_BUF_B")
	)
	(segment
		(start 301.924974 -122.689874)
		(end 294.680894 -115.445794)
		(width 0.14605)
		(layer "In2.Cu")
		(net "DPB_PWR_BTN_BUF_B")
	)
	(segment
		(start 289.404552 -240.204752)
		(end 295.70045 -233.908854)
		(width 0.14605)
		(layer "In2.Cu")
		(net "DPB_PWR_BTN_BUF_B")
	)
	(segment
		(start 295.754298 -233.600498)
		(end 295.754298 -193.508376)
		(width 0.14605)
		(layer "In2.Cu")
		(net "DPB_PWR_BTN_BUF_B")
	)
	(segment
		(start 279.894284 -115.445794)
		(end 279.84323 -115.496848)
		(width 0.14605)
		(layer "In2.Cu")
		(net "DPB_PWR_BTN_BUF_B")
	)
	(segment
		(start 289.150044 -240.204752)
		(end 289.404552 -240.204752)
		(width 0.14605)
		(layer "In2.Cu")
		(net "DPB_PWR_BTN_BUF_B")
	)
	(segment
		(start 301.924974 -185.6613)
		(end 301.924974 -122.689874)
		(width 0.14605)
		(layer "In2.Cu")
		(net "DPB_PWR_BTN_BUF_B")
	)
	(segment
		(start 294.680894 -115.445794)
		(end 279.894284 -115.445794)
		(width 0.14605)
		(layer "In2.Cu")
		(net "DPB_PWR_BTN_BUF_B")
	)
	(segment
		(start 301.955962 -187.306712)
		(end 301.955962 -185.692288)
		(width 0.14605)
		(layer "In2.Cu")
		(net "DPB_PWR_BTN_BUF_B")
	)
	(segment
		(start 287.114996 -242.2398)
		(end 289.150044 -240.204752)
		(width 0.14605)
		(layer "In2.Cu")
		(net "DPB_PWR_BTN_BUF_B")
	)
	(segment
		(start 295.754298 -193.508376)
		(end 301.09541 -188.167264)
		(width 0.14605)
		(layer "In2.Cu")
		(net "DPB_PWR_BTN_BUF_B")
	)
	(segment
		(start 279.8064 -242.2398)
		(end 287.114996 -242.2398)
		(width 0.14605)
		(layer "In2.Cu")
		(net "DPB_PWR_BTN_BUF_B")
	)
	(segment
		(start 295.70045 -233.654346)
		(end 295.754298 -233.600498)
		(width 0.14605)
		(layer "In2.Cu")
		(net "DPB_PWR_BTN_BUF_B")
	)
	(segment
		(start 301.510192 -187.752736)
		(end 301.510446 -187.752736)
		(width 0.14605)
		(layer "In2.Cu")
		(net "DPB_PWR_BTN_BUF_B")
	)
	(segment
		(start 278.431752 -115.496848)
		(end 278.1554 -115.7732)
		(width 0.14605)
		(layer "In2.Cu")
		(net "DPB_PWR_BTN_BUF_B")
	)
	(segment
		(start 301.09541 -188.167264)
		(end 301.095664 -188.167264)
		(width 0.14605)
		(layer "In2.Cu")
		(net "DPB_PWR_BTN_BUF_B")
	)
	(segment
		(start 301.924974 -187.338208)
		(end 301.924974 -187.3377)
		(width 0.14605)
		(layer "In2.Cu")
		(net "DPB_PWR_BTN_BUF_B")
	)
	(segment
		(start 279.8064 -242.2398)
		(end 278.574754 -243.471446)
		(width 0.14605)
		(layer "In5.Cu")
		(net "DPB_PWR_BTN_BUF_B")
	)
	(segment
		(start 274.343368 -350.958658)
		(end 267.702792 -357.599234)
		(width 0.14605)
		(layer "In5.Cu")
		(net "DPB_PWR_BTN_BUF_B")
	)
	(segment
		(start 275.498052 -330.506578)
		(end 274.343368 -331.661262)
		(width 0.14605)
		(layer "In5.Cu")
		(net "DPB_PWR_BTN_BUF_B")
	)
	(segment
		(start 267.702792 -366.523016)
		(end 266.332462 -367.893346)
		(width 0.14605)
		(layer "In5.Cu")
		(net "DPB_PWR_BTN_BUF_B")
	)
	(segment
		(start 265.970512 -314.074048)
		(end 275.498052 -323.601588)
		(width 0.14605)
		(layer "In5.Cu")
		(net "DPB_PWR_BTN_BUF_B")
	)
	(segment
		(start 267.702792 -357.599234)
		(end 267.702792 -366.523016)
		(width 0.14605)
		(layer "In5.Cu")
		(net "DPB_PWR_BTN_BUF_B")
	)
	(segment
		(start 275.498052 -323.601588)
		(end 275.498052 -330.506578)
		(width 0.14605)
		(layer "In5.Cu")
		(net "DPB_PWR_BTN_BUF_B")
	)
	(segment
		(start 278.574754 -243.471446)
		(end 278.574754 -247.982994)
		(width 0.14605)
		(layer "In5.Cu")
		(net "DPB_PWR_BTN_BUF_B")
	)
	(segment
		(start 274.343368 -331.661262)
		(end 274.343368 -350.958658)
		(width 0.14605)
		(layer "In5.Cu")
		(net "DPB_PWR_BTN_BUF_B")
	)
	(segment
		(start 265.970512 -260.587236)
		(end 265.970512 -314.074048)
		(width 0.14605)
		(layer "In5.Cu")
		(net "DPB_PWR_BTN_BUF_B")
	)
	(segment
		(start 278.574754 -247.982994)
		(end 265.970512 -260.587236)
		(width 0.14605)
		(layer "In5.Cu")
		(net "DPB_PWR_BTN_BUF_B")
	)
	(segment
		(start 248.524522 -366.178846)
		(end 248.158508 -366.178846)
		(width 0.254)
		(layer "F.Cu")
		(net "MB3_HS_SENSE_P")
	)
	(segment
		(start 248.703084 -366.357408)
		(end 248.524522 -366.178846)
		(width 0.254)
		(layer "F.Cu")
		(net "MB3_HS_SENSE_P")
	)
	(segment
		(start 248.158508 -366.178846)
		(end 247.964706 -366.372648)
		(width 0.254)
		(layer "F.Cu")
		(net "MB3_HS_SENSE_P")
	)
	(segment
		(start 250.874022 -366.365282)
		(end 249.981466 -366.365282)
		(width 0.254)
		(layer "F.Cu")
		(net "MB3_HS_SENSE_P")
	)
	(segment
		(start 247.679718 -366.372648)
		(end 247.298718 -365.991648)
		(width 0.254)
		(layer "F.Cu")
		(net "MB3_HS_SENSE_P")
	)
	(segment
		(start 249.973592 -366.357408)
		(end 248.703084 -366.357408)
		(width 0.254)
		(layer "F.Cu")
		(net "MB3_HS_SENSE_P")
	)
	(segment
		(start 247.298718 -365.991648)
		(end 246.917718 -366.372648)
		(width 0.254)
		(layer "F.Cu")
		(net "MB3_HS_SENSE_P")
	)
	(segment
		(start 247.964706 -366.372648)
		(end 247.679718 -366.372648)
		(width 0.254)
		(layer "F.Cu")
		(net "MB3_HS_SENSE_P")
	)
	(segment
		(start 246.279924 -366.372648)
		(end 246.022622 -366.115346)
		(width 0.254)
		(layer "F.Cu")
		(net "MB3_HS_SENSE_P")
	)
	(segment
		(start 246.917718 -366.372648)
		(end 246.279924 -366.372648)
		(width 0.254)
		(layer "F.Cu")
		(net "MB3_HS_SENSE_P")
	)
	(segment
		(start 249.981466 -366.365282)
		(end 249.973592 -366.357408)
		(width 0.254)
		(layer "F.Cu")
		(net "MB3_HS_SENSE_P")
	)
	(via
		(at 247.298718 -365.991648)
		(size 0.6604)
		(drill 0.3302)
		(layers "F.Cu" "B.Cu")
		(net "MB3_HS_SENSE_P")
	)
	(segment
		(start 246.917718 -366.880648)
		(end 246.27332 -366.880648)
		(width 0.254)
		(layer "F.Cu")
		(net "MB3_HS_SENSE_N")
	)
	(segment
		(start 247.679718 -366.880648)
		(end 247.298718 -367.261648)
		(width 0.254)
		(layer "F.Cu")
		(net "MB3_HS_SENSE_N")
	)
	(segment
		(start 248.72696 -366.865408)
		(end 248.524522 -367.067846)
		(width 0.254)
		(layer "F.Cu")
		(net "MB3_HS_SENSE_N")
	)
	(segment
		(start 248.168922 -367.067846)
		(end 247.981724 -366.880648)
		(width 0.254)
		(layer "F.Cu")
		(net "MB3_HS_SENSE_N")
	)
	(segment
		(start 247.298718 -367.261648)
		(end 246.917718 -366.880648)
		(width 0.254)
		(layer "F.Cu")
		(net "MB3_HS_SENSE_N")
	)
	(segment
		(start 247.981724 -366.880648)
		(end 247.679718 -366.880648)
		(width 0.254)
		(layer "F.Cu")
		(net "MB3_HS_SENSE_N")
	)
	(segment
		(start 248.524522 -367.067846)
		(end 248.168922 -367.067846)
		(width 0.254)
		(layer "F.Cu")
		(net "MB3_HS_SENSE_N")
	)
	(segment
		(start 246.27332 -366.880648)
		(end 246.022622 -367.131346)
		(width 0.254)
		(layer "F.Cu")
		(net "MB3_HS_SENSE_N")
	)
	(segment
		(start 250.874022 -366.865408)
		(end 248.72696 -366.865408)
		(width 0.254)
		(layer "F.Cu")
		(net "MB3_HS_SENSE_N")
	)
	(via
		(at 247.298718 -367.261648)
		(size 0.6604)
		(drill 0.3302)
		(layers "F.Cu" "B.Cu")
		(net "MB3_HS_SENSE_N")
	)
	(segment
		(start 168.56075 -374.9675)
		(end 169.545 -374.9675)
		(width 0.254)
		(layer "F.Cu")
		(net "MB0_TEMP_E")
	)
	(segment
		(start 169.545 -374.9675)
		(end 170.815 -374.9675)
		(width 0.254)
		(layer "F.Cu")
		(net "MB0_TEMP_E")
	)
	(segment
		(start 167.29075 -376.2375)
		(end 167.3225 -376.20575)
		(width 0.254)
		(layer "F.Cu")
		(net "MB0_TEMP_E")
	)
	(segment
		(start 167.3225 -376.20575)
		(end 168.56075 -374.9675)
		(width 0.254)
		(layer "F.Cu")
		(net "MB0_TEMP_E")
	)
	(segment
		(start 165.862 -376.2375)
		(end 167.29075 -376.2375)
		(width 0.254)
		(layer "F.Cu")
		(net "MB0_TEMP_E")
	)
	(via
		(at 169.545 -374.9675)
		(size 0.6604)
		(drill 0.3302)
		(layers "F.Cu" "B.Cu")
		(net "MB0_TEMP_E")
	)
	(segment
		(start 169.2275 -377.19)
		(end 168.24325 -378.17425)
		(width 0.254)
		(layer "F.Cu")
		(net "MB0_TEMP_B")
	)
	(segment
		(start 171.831 -375.8565)
		(end 170.815 -375.8565)
		(width 0.254)
		(layer "F.Cu")
		(net "MB0_TEMP_B")
	)
	(segment
		(start 170.815 -377.19)
		(end 169.2275 -377.19)
		(width 0.254)
		(layer "F.Cu")
		(net "MB0_TEMP_B")
	)
	(segment
		(start 168.24325 -378.17425)
		(end 167.3225 -378.17425)
		(width 0.254)
		(layer "F.Cu")
		(net "MB0_TEMP_B")
	)
	(segment
		(start 170.815 -375.8565)
		(end 170.815 -377.19)
		(width 0.254)
		(layer "F.Cu")
		(net "MB0_TEMP_B")
	)
	(via
		(at 170.815 -377.19)
		(size 0.6604)
		(drill 0.3302)
		(layers "F.Cu" "B.Cu")
		(net "MB0_TEMP_B")
	)
	(segment
		(start 169.4688 -369.443)
		(end 169.928794 -369.443)
		(width 0.254)
		(layer "F.Cu")
		(net "MB0_HS_SENSE_P")
	)
	(segment
		(start 171.820078 -369.438936)
		(end 171.816268 -369.435126)
		(width 0.254)
		(layer "F.Cu")
		(net "MB0_HS_SENSE_P")
	)
	(segment
		(start 172.7835 -369.438936)
		(end 171.820078 -369.438936)
		(width 0.254)
		(layer "F.Cu")
		(net "MB0_HS_SENSE_P")
	)
	(segment
		(start 168.7068 -369.443)
		(end 169.0878 -369.062)
		(width 0.254)
		(layer "F.Cu")
		(net "MB0_HS_SENSE_P")
	)
	(segment
		(start 168.1607 -369.189)
		(end 168.4147 -369.443)
		(width 0.254)
		(layer "F.Cu")
		(net "MB0_HS_SENSE_P")
	)
	(segment
		(start 169.0878 -369.062)
		(end 169.4688 -369.443)
		(width 0.254)
		(layer "F.Cu")
		(net "MB0_HS_SENSE_P")
	)
	(segment
		(start 168.4147 -369.443)
		(end 168.7068 -369.443)
		(width 0.254)
		(layer "F.Cu")
		(net "MB0_HS_SENSE_P")
	)
	(segment
		(start 169.928794 -369.443)
		(end 170.119294 -369.2525)
		(width 0.254)
		(layer "F.Cu")
		(net "MB0_HS_SENSE_P")
	)
	(segment
		(start 171.816268 -369.435126)
		(end 170.30192 -369.435126)
		(width 0.254)
		(layer "F.Cu")
		(net "MB0_HS_SENSE_P")
	)
	(segment
		(start 170.30192 -369.435126)
		(end 170.119294 -369.2525)
		(width 0.254)
		(layer "F.Cu")
		(net "MB0_HS_SENSE_P")
	)
	(via
		(at 169.0878 -369.062)
		(size 0.5588)
		(drill 0.3048)
		(layers "F.Cu" "B.Cu")
		(net "MB0_HS_SENSE_P")
	)
	(segment
		(start 168.7068 -369.443)
		(end 169.0878 -369.062)
		(width 0.254)
		(layer "B.Cu")
		(net "MB0_HS_SENSE_P")
	)
	(segment
		(start 168.4147 -369.443)
		(end 168.7068 -369.443)
		(width 0.254)
		(layer "B.Cu")
		(net "MB0_HS_SENSE_P")
	)
	(segment
		(start 168.1607 -369.189)
		(end 168.4147 -369.443)
		(width 0.254)
		(layer "B.Cu")
		(net "MB0_HS_SENSE_P")
	)
	(segment
		(start 168.7068 -369.951)
		(end 169.0878 -370.332)
		(width 0.254)
		(layer "F.Cu")
		(net "MB0_HS_SENSE_N")
	)
	(segment
		(start 169.928794 -369.951)
		(end 170.119294 -370.1415)
		(width 0.254)
		(layer "F.Cu")
		(net "MB0_HS_SENSE_N")
	)
	(segment
		(start 171.820332 -369.939062)
		(end 171.816268 -369.943126)
		(width 0.254)
		(layer "F.Cu")
		(net "MB0_HS_SENSE_N")
	)
	(segment
		(start 171.816268 -369.943126)
		(end 170.317668 -369.943126)
		(width 0.254)
		(layer "F.Cu")
		(net "MB0_HS_SENSE_N")
	)
	(segment
		(start 169.0878 -370.332)
		(end 169.4688 -369.951)
		(width 0.254)
		(layer "F.Cu")
		(net "MB0_HS_SENSE_N")
	)
	(segment
		(start 168.1607 -370.205)
		(end 168.4147 -369.951)
		(width 0.254)
		(layer "F.Cu")
		(net "MB0_HS_SENSE_N")
	)
	(segment
		(start 168.4147 -369.951)
		(end 168.7068 -369.951)
		(width 0.254)
		(layer "F.Cu")
		(net "MB0_HS_SENSE_N")
	)
	(segment
		(start 169.4688 -369.951)
		(end 169.928794 -369.951)
		(width 0.254)
		(layer "F.Cu")
		(net "MB0_HS_SENSE_N")
	)
	(segment
		(start 172.7835 -369.939062)
		(end 171.820332 -369.939062)
		(width 0.254)
		(layer "F.Cu")
		(net "MB0_HS_SENSE_N")
	)
	(segment
		(start 170.317668 -369.943126)
		(end 170.119294 -370.1415)
		(width 0.254)
		(layer "F.Cu")
		(net "MB0_HS_SENSE_N")
	)
	(via
		(at 169.0878 -370.332)
		(size 0.5588)
		(drill 0.3048)
		(layers "F.Cu" "B.Cu")
		(net "MB0_HS_SENSE_N")
	)
	(segment
		(start 168.4147 -369.951)
		(end 168.7068 -369.951)
		(width 0.254)
		(layer "B.Cu")
		(net "MB0_HS_SENSE_N")
	)
	(segment
		(start 168.7068 -369.951)
		(end 169.0878 -370.332)
		(width 0.254)
		(layer "B.Cu")
		(net "MB0_HS_SENSE_N")
	)
	(segment
		(start 168.1607 -370.205)
		(end 168.4147 -369.951)
		(width 0.254)
		(layer "B.Cu")
		(net "MB0_HS_SENSE_N")
	)
	(segment
		(start 226.835208 -80.754728)
		(end 226.835208 -80.754982)
		(width 0.254)
		(layer "F.Cu")
		(net "SCC_B_STBY_PGOOD")
	)
	(segment
		(start 226.835208 -67.434968)
		(end 226.835208 -80.754728)
		(width 0.17145)
		(layer "F.Cu")
		(net "SCC_B_STBY_PGOOD")
	)
	(segment
		(start 278.9174 -114.8842)
		(end 280.1874 -116.1542)
		(width 0.254)
		(layer "F.Cu")
		(net "SCC_B_STBY_PGOOD")
	)
	(segment
		(start 255.484884 -109.076236)
		(end 256.740914 -110.332266)
		(width 0.254)
		(layer "F.Cu")
		(net "SCC_B_STBY_PGOOD")
	)
	(segment
		(start 255.281938 -108.87329)
		(end 255.484884 -109.076236)
		(width 0.254)
		(layer "F.Cu")
		(net "SCC_B_STBY_PGOOD")
	)
	(segment
		(start 264.992612 -114.8842)
		(end 278.9174 -114.8842)
		(width 0.254)
		(layer "F.Cu")
		(net "SCC_B_STBY_PGOOD")
	)
	(segment
		(start 260.440678 -110.332266)
		(end 264.992612 -114.8842)
		(width 0.254)
		(layer "F.Cu")
		(net "SCC_B_STBY_PGOOD")
	)
	(segment
		(start 226.835208 -80.754982)
		(end 229.268528 -83.188302)
		(width 0.254)
		(layer "F.Cu")
		(net "SCC_B_STBY_PGOOD")
	)
	(segment
		(start 255.281938 -108.179108)
		(end 255.281938 -108.87329)
		(width 0.254)
		(layer "F.Cu")
		(net "SCC_B_STBY_PGOOD")
	)
	(segment
		(start 226.200208 -66.799968)
		(end 226.835208 -67.434968)
		(width 0.17145)
		(layer "F.Cu")
		(net "SCC_B_STBY_PGOOD")
	)
	(segment
		(start 256.740914 -110.332266)
		(end 260.440678 -110.332266)
		(width 0.254)
		(layer "F.Cu")
		(net "SCC_B_STBY_PGOOD")
	)
	(segment
		(start 229.268528 -83.188302)
		(end 230.291132 -83.188302)
		(width 0.254)
		(layer "F.Cu")
		(net "SCC_B_STBY_PGOOD")
	)
	(segment
		(start 230.291132 -83.188302)
		(end 255.281938 -108.179108)
		(width 0.254)
		(layer "F.Cu")
		(net "SCC_B_STBY_PGOOD")
	)
	(via
		(at 255.484884 -109.076236)
		(size 0.6604)
		(drill 0.3302)
		(layers "F.Cu" "B.Cu")
		(net "SCC_B_STBY_PGOOD")
	)
	(via
		(at 280.1874 -116.1542)
		(size 0.5588)
		(drill 0.3048)
		(layers "F.Cu" "B.Cu")
		(net "SCC_B_STBY_PGOOD")
	)
	(segment
		(start 285.0388 -239.4966)
		(end 284.236668 -238.694468)
		(width 0.254)
		(layer "In2.Cu")
		(net "SCC_B_STBY_PGOOD")
	)
	(segment
		(start 301.216822 -122.983244)
		(end 301.216822 -187.044584)
		(width 0.254)
		(layer "In2.Cu")
		(net "SCC_B_STBY_PGOOD")
	)
	(segment
		(start 280.2382 -116.205)
		(end 294.438578 -116.205)
		(width 0.254)
		(layer "In2.Cu")
		(net "SCC_B_STBY_PGOOD")
	)
	(segment
		(start 294.992298 -193.268854)
		(end 294.992298 -233.615484)
		(width 0.254)
		(layer "In2.Cu")
		(net "SCC_B_STBY_PGOOD")
	)
	(segment
		(start 301.216822 -187.044584)
		(end 300.802294 -187.459112)
		(width 0.254)
		(layer "In2.Cu")
		(net "SCC_B_STBY_PGOOD")
	)
	(segment
		(start 294.992298 -233.615484)
		(end 289.111182 -239.4966)
		(width 0.254)
		(layer "In2.Cu")
		(net "SCC_B_STBY_PGOOD")
	)
	(segment
		(start 300.80204 -187.459112)
		(end 294.992298 -193.268854)
		(width 0.254)
		(layer "In2.Cu")
		(net "SCC_B_STBY_PGOOD")
	)
	(segment
		(start 289.111182 -239.4966)
		(end 285.0388 -239.4966)
		(width 0.254)
		(layer "In2.Cu")
		(net "SCC_B_STBY_PGOOD")
	)
	(segment
		(start 294.438578 -116.205)
		(end 301.216822 -122.983244)
		(width 0.254)
		(layer "In2.Cu")
		(net "SCC_B_STBY_PGOOD")
	)
	(segment
		(start 300.802294 -187.459112)
		(end 300.80204 -187.459112)
		(width 0.254)
		(layer "In2.Cu")
		(net "SCC_B_STBY_PGOOD")
	)
	(segment
		(start 280.1874 -116.1542)
		(end 280.2382 -116.205)
		(width 0.254)
		(layer "In2.Cu")
		(net "SCC_B_STBY_PGOOD")
	)
	(segment
		(start 23.040086 -377.219972)
		(end 22.027896 -376.207782)
		(width 0.254)
		(layer "F.Cu")
		(net "FAN_LED_BLUE0")
	)
	(segment
		(start 22.027896 -376.207782)
		(end 22.027896 -374.3071)
		(width 0.254)
		(layer "F.Cu")
		(net "FAN_LED_BLUE0")
	)
	(segment
		(start 456.546204 -373.3546)
		(end 456.546204 -373.4816)
		(width 0.254)
		(layer "F.Cu")
		(net "FAN_LED3")
	)
	(segment
		(start 456.546204 -373.7864)
		(end 457.005944 -374.24614)
		(width 0.254)
		(layer "F.Cu")
		(net "FAN_LED3")
	)
	(segment
		(start 457.181204 -372.999)
		(end 456.901804 -372.999)
		(width 0.254)
		(layer "F.Cu")
		(net "FAN_LED3")
	)
	(segment
		(start 456.546204 -373.4816)
		(end 456.546204 -373.7864)
		(width 0.254)
		(layer "F.Cu")
		(net "FAN_LED3")
	)
	(segment
		(start 457.653644 -371.7163)
		(end 457.653644 -372.52656)
		(width 0.254)
		(layer "F.Cu")
		(net "FAN_LED3")
	)
	(segment
		(start 456.901804 -372.999)
		(end 456.546204 -373.3546)
		(width 0.254)
		(layer "F.Cu")
		(net "FAN_LED3")
	)
	(segment
		(start 457.653644 -372.52656)
		(end 457.181204 -372.999)
		(width 0.254)
		(layer "F.Cu")
		(net "FAN_LED3")
	)
	(segment
		(start 457.005944 -374.24614)
		(end 457.005944 -375.15546)
		(width 0.254)
		(layer "F.Cu")
		(net "FAN_LED3")
	)
	(via
		(at 456.546204 -373.4816)
		(size 0.6604)
		(drill 0.3302)
		(layers "F.Cu" "B.Cu")
		(net "FAN_LED3")
	)
	(segment
		(start 322.090796 -375.0056)
		(end 322.573396 -374.523)
		(width 0.254)
		(layer "F.Cu")
		(net "FAN_LED2")
	)
	(segment
		(start 321.951096 -371.8687)
		(end 322.573396 -372.491)
		(width 0.254)
		(layer "F.Cu")
		(net "FAN_LED2")
	)
	(segment
		(start 321.242436 -371.8687)
		(end 321.951096 -371.8687)
		(width 0.254)
		(layer "F.Cu")
		(net "FAN_LED2")
	)
	(segment
		(start 321.252596 -375.0056)
		(end 322.090796 -375.0056)
		(width 0.254)
		(layer "F.Cu")
		(net "FAN_LED2")
	)
	(segment
		(start 322.573396 -374.523)
		(end 322.573396 -373.2022)
		(width 0.254)
		(layer "F.Cu")
		(net "FAN_LED2")
	)
	(segment
		(start 322.573396 -372.491)
		(end 322.573396 -373.2022)
		(width 0.254)
		(layer "F.Cu")
		(net "FAN_LED2")
	)
	(via
		(at 322.573396 -373.2022)
		(size 0.6604)
		(drill 0.3302)
		(layers "F.Cu" "B.Cu")
		(net "FAN_LED2")
	)
	(segment
		(start 191.041528 -368.815366)
		(end 189.744858 -370.112036)
		(width 0.254)
		(layer "F.Cu")
		(net "FAN_LED1")
	)
	(segment
		(start 189.298072 -370.137436)
		(end 188.806328 -370.137436)
		(width 0.254)
		(layer "F.Cu")
		(net "FAN_LED1")
	)
	(segment
		(start 189.744858 -370.112036)
		(end 189.323472 -370.112036)
		(width 0.254)
		(layer "F.Cu")
		(net "FAN_LED1")
	)
	(segment
		(start 191.041528 -368.435636)
		(end 191.041528 -368.815366)
		(width 0.254)
		(layer "F.Cu")
		(net "FAN_LED1")
	)
	(segment
		(start 189.659768 -366.949736)
		(end 190.597028 -366.949736)
		(width 0.254)
		(layer "F.Cu")
		(net "FAN_LED1")
	)
	(segment
		(start 189.323472 -370.112036)
		(end 189.298072 -370.137436)
		(width 0.254)
		(layer "F.Cu")
		(net "FAN_LED1")
	)
	(segment
		(start 191.041528 -367.394236)
		(end 191.041528 -368.435636)
		(width 0.254)
		(layer "F.Cu")
		(net "FAN_LED1")
	)
	(segment
		(start 190.597028 -366.949736)
		(end 191.041528 -367.394236)
		(width 0.254)
		(layer "F.Cu")
		(net "FAN_LED1")
	)
	(via
		(at 191.041528 -368.435636)
		(size 0.6604)
		(drill 0.3302)
		(layers "F.Cu" "B.Cu")
		(net "FAN_LED1")
	)
	(segment
		(start 30.600396 -373.888)
		(end 31.540196 -372.9482)
		(width 0.254)
		(layer "F.Cu")
		(net "FAN_LED0")
	)
	(segment
		(start 31.540196 -371.1448)
		(end 31.540196 -372.5164)
		(width 0.254)
		(layer "F.Cu")
		(net "FAN_LED0")
	)
	(segment
		(start 30.082236 -370.5733)
		(end 30.968696 -370.5733)
		(width 0.254)
		(layer "F.Cu")
		(net "FAN_LED0")
	)
	(segment
		(start 30.117796 -373.888)
		(end 30.600396 -373.888)
		(width 0.254)
		(layer "F.Cu")
		(net "FAN_LED0")
	)
	(segment
		(start 30.968696 -370.5733)
		(end 31.540196 -371.1448)
		(width 0.254)
		(layer "F.Cu")
		(net "FAN_LED0")
	)
	(segment
		(start 31.540196 -372.9482)
		(end 31.540196 -372.5164)
		(width 0.254)
		(layer "F.Cu")
		(net "FAN_LED0")
	)
	(via
		(at 31.540196 -372.5164)
		(size 0.6604)
		(drill 0.3302)
		(layers "F.Cu" "B.Cu")
		(net "FAN_LED0")
	)
	(segment
		(start 29.254196 -377.7234)
		(end 29.254196 -377.0376)
		(width 0.254)
		(layer "F.Cu")
		(net "FAN_BLUE_LED0")
	)
	(segment
		(start 27.323796 -375.9962)
		(end 27.882596 -375.9962)
		(width 0.254)
		(layer "F.Cu")
		(net "FAN_BLUE_LED0")
	)
	(segment
		(start 28.102306 -378.1044)
		(end 28.873196 -378.1044)
		(width 0.254)
		(layer "F.Cu")
		(net "FAN_BLUE_LED0")
	)
	(segment
		(start 29.254196 -377.0376)
		(end 29.012896 -376.7963)
		(width 0.254)
		(layer "F.Cu")
		(net "FAN_BLUE_LED0")
	)
	(segment
		(start 28.873196 -378.1044)
		(end 29.254196 -377.7234)
		(width 0.254)
		(layer "F.Cu")
		(net "FAN_BLUE_LED0")
	)
	(segment
		(start 26.790396 -375.09069)
		(end 26.790396 -375.4628)
		(width 0.254)
		(layer "F.Cu")
		(net "FAN_BLUE_LED0")
	)
	(segment
		(start 29.012896 -376.0216)
		(end 27.907996 -376.0216)
		(width 0.254)
		(layer "F.Cu")
		(net "FAN_BLUE_LED0")
	)
	(segment
		(start 26.790396 -375.4628)
		(end 27.323796 -375.9962)
		(width 0.254)
		(layer "F.Cu")
		(net "FAN_BLUE_LED0")
	)
	(segment
		(start 29.012896 -376.7963)
		(end 29.012896 -376.0216)
		(width 0.254)
		(layer "F.Cu")
		(net "FAN_BLUE_LED0")
	)
	(segment
		(start 27.907996 -376.0216)
		(end 27.882596 -375.9962)
		(width 0.254)
		(layer "F.Cu")
		(net "FAN_BLUE_LED0")
	)
	(via
		(at 27.882596 -375.9962)
		(size 0.6604)
		(drill 0.3302)
		(layers "F.Cu" "B.Cu")
		(net "FAN_BLUE_LED0")
	)
	(segment
		(start 189.909196 -375.181876)
		(end 191.192404 -376.465084)
		(width 0.254)
		(layer "F.Cu")
		(net "FAN_BLUE1")
	)
	(segment
		(start 190.358522 -379.5395)
		(end 189.500256 -379.5395)
		(width 0.254)
		(layer "F.Cu")
		(net "FAN_BLUE1")
	)
	(segment
		(start 191.192404 -378.705618)
		(end 190.358522 -379.5395)
		(width 0.254)
		(layer "F.Cu")
		(net "FAN_BLUE1")
	)
	(segment
		(start 189.145418 -375.181876)
		(end 189.909196 -375.181876)
		(width 0.254)
		(layer "F.Cu")
		(net "FAN_BLUE1")
	)
	(segment
		(start 187.6933 -379.5395)
		(end 189.500256 -379.5395)
		(width 0.254)
		(layer "F.Cu")
		(net "FAN_BLUE1")
	)
	(segment
		(start 191.192404 -376.465084)
		(end 191.192404 -378.705618)
		(width 0.254)
		(layer "F.Cu")
		(net "FAN_BLUE1")
	)
	(via
		(at 189.500256 -379.5395)
		(size 0.6604)
		(drill 0.3302)
		(layers "F.Cu" "B.Cu")
		(net "FAN_BLUE1")
	)
	(segment
		(start 24.682196 -378.2314)
		(end 26.714196 -380.2634)
		(width 0.254)
		(layer "F.Cu")
		(net "FAN_BLUE0")
	)
	(segment
		(start 24.682196 -375.031)
		(end 24.682196 -378.2314)
		(width 0.254)
		(layer "F.Cu")
		(net "FAN_BLUE0")
	)
	(segment
		(start 26.714196 -380.2634)
		(end 29.558996 -380.2634)
		(width 0.254)
		(layer "F.Cu")
		(net "FAN_BLUE0")
	)
	(segment
		(start 30.150308 -378.756418)
		(end 30.152086 -378.75464)
		(width 0.254)
		(layer "F.Cu")
		(net "FAN_BLUE0")
	)
	(segment
		(start 30.150308 -379.672088)
		(end 30.150308 -378.756418)
		(width 0.254)
		(layer "F.Cu")
		(net "FAN_BLUE0")
	)
	(segment
		(start 29.558996 -380.2634)
		(end 30.150308 -379.672088)
		(width 0.254)
		(layer "F.Cu")
		(net "FAN_BLUE0")
	)
	(segment
		(start 23.958296 -374.3071)
		(end 24.682196 -375.031)
		(width 0.254)
		(layer "F.Cu")
		(net "FAN_BLUE0")
	)
	(via
		(at 29.558996 -380.2634)
		(size 0.6604)
		(drill 0.3302)
		(layers "F.Cu" "B.Cu")
		(net "FAN_BLUE0")
	)
	(via
		(at 214.815928 -226.495102)
		(size 0.5588)
		(drill 0.3048)
		(layers "F.Cu" "B.Cu")
		(net "UART_SDB_B_TX")
	)
	(segment
		(start 214.6808 -222.162624)
		(end 217.3224 -219.521024)
		(width 0.14605)
		(layer "In2.Cu")
		(net "UART_SDB_B_TX")
	)
	(segment
		(start 214.6808 -226.359974)
		(end 214.6808 -222.162624)
		(width 0.14605)
		(layer "In2.Cu")
		(net "UART_SDB_B_TX")
	)
	(segment
		(start 214.858854 -114.328956)
		(end 215.576404 -113.611406)
		(width 0.14605)
		(layer "In2.Cu")
		(net "UART_SDB_B_TX")
	)
	(segment
		(start 216.436702 -173.600364)
		(end 216.436702 -161.278062)
		(width 0.14605)
		(layer "In2.Cu")
		(net "UART_SDB_B_TX")
	)
	(segment
		(start 217.3224 -219.521024)
		(end 217.3224 -214.619332)
		(width 0.14605)
		(layer "In2.Cu")
		(net "UART_SDB_B_TX")
	)
	(segment
		(start 216.436702 -161.278062)
		(end 214.858854 -159.700214)
		(width 0.14605)
		(layer "In2.Cu")
		(net "UART_SDB_B_TX")
	)
	(segment
		(start 217.825828 -174.98949)
		(end 216.436702 -173.600364)
		(width 0.14605)
		(layer "In2.Cu")
		(net "UART_SDB_B_TX")
	)
	(segment
		(start 214.815928 -226.495102)
		(end 214.6808 -226.359974)
		(width 0.14605)
		(layer "In2.Cu")
		(net "UART_SDB_B_TX")
	)
	(segment
		(start 220.156532 -76.043536)
		(end 220.800168 -75.3999)
		(width 0.14605)
		(layer "In2.Cu")
		(net "UART_SDB_B_TX")
	)
	(segment
		(start 214.858854 -159.700214)
		(end 214.858854 -114.328956)
		(width 0.14605)
		(layer "In2.Cu")
		(net "UART_SDB_B_TX")
	)
	(segment
		(start 215.576404 -113.611406)
		(end 215.576404 -103.65232)
		(width 0.14605)
		(layer "In2.Cu")
		(net "UART_SDB_B_TX")
	)
	(segment
		(start 217.825828 -214.115904)
		(end 217.825828 -174.98949)
		(width 0.14605)
		(layer "In2.Cu")
		(net "UART_SDB_B_TX")
	)
	(segment
		(start 220.156532 -99.072192)
		(end 220.156532 -76.043536)
		(width 0.14605)
		(layer "In2.Cu")
		(net "UART_SDB_B_TX")
	)
	(segment
		(start 215.576404 -103.65232)
		(end 220.156532 -99.072192)
		(width 0.14605)
		(layer "In2.Cu")
		(net "UART_SDB_B_TX")
	)
	(segment
		(start 217.3224 -214.619332)
		(end 217.825828 -214.115904)
		(width 0.14605)
		(layer "In2.Cu")
		(net "UART_SDB_B_TX")
	)
	(segment
		(start 239.09147 -224.53727)
		(end 238.76 -224.2058)
		(width 0.14605)
		(layer "In5.Cu")
		(net "UART_SDB_B_TX")
	)
	(segment
		(start 223.760792 -224.923096)
		(end 217.773504 -224.923096)
		(width 0.14605)
		(layer "In5.Cu")
		(net "UART_SDB_B_TX")
	)
	(segment
		(start 217.773504 -224.923096)
		(end 216.201498 -226.495102)
		(width 0.14605)
		(layer "In5.Cu")
		(net "UART_SDB_B_TX")
	)
	(segment
		(start 284.236668 -227.894388)
		(end 283.078682 -226.736402)
		(width 0.14605)
		(layer "In5.Cu")
		(net "UART_SDB_B_TX")
	)
	(segment
		(start 238.76 -224.2058)
		(end 224.478088 -224.2058)
		(width 0.14605)
		(layer "In5.Cu")
		(net "UART_SDB_B_TX")
	)
	(segment
		(start 224.478088 -224.2058)
		(end 223.760792 -224.923096)
		(width 0.14605)
		(layer "In5.Cu")
		(net "UART_SDB_B_TX")
	)
	(segment
		(start 271.01419 -225.095562)
		(end 254.432562 -225.095562)
		(width 0.14605)
		(layer "In5.Cu")
		(net "UART_SDB_B_TX")
	)
	(segment
		(start 216.201498 -226.495102)
		(end 214.815928 -226.495102)
		(width 0.14605)
		(layer "In5.Cu")
		(net "UART_SDB_B_TX")
	)
	(segment
		(start 253.088648 -223.751648)
		(end 246.755412 -223.751648)
		(width 0.14605)
		(layer "In5.Cu")
		(net "UART_SDB_B_TX")
	)
	(segment
		(start 245.96979 -224.53727)
		(end 239.09147 -224.53727)
		(width 0.14605)
		(layer "In5.Cu")
		(net "UART_SDB_B_TX")
	)
	(segment
		(start 246.755412 -223.751648)
		(end 245.96979 -224.53727)
		(width 0.14605)
		(layer "In5.Cu")
		(net "UART_SDB_B_TX")
	)
	(segment
		(start 272.65503 -226.736402)
		(end 271.01419 -225.095562)
		(width 0.14605)
		(layer "In5.Cu")
		(net "UART_SDB_B_TX")
	)
	(segment
		(start 254.432562 -225.095562)
		(end 253.088648 -223.751648)
		(width 0.14605)
		(layer "In5.Cu")
		(net "UART_SDB_B_TX")
	)
	(segment
		(start 283.078682 -226.736402)
		(end 272.65503 -226.736402)
		(width 0.14605)
		(layer "In5.Cu")
		(net "UART_SDB_B_TX")
	)
	(via
		(at 214.5792 -227.559108)
		(size 0.5588)
		(drill 0.3048)
		(layers "F.Cu" "B.Cu")
		(net "UART_SDB_B_RX")
	)
	(segment
		(start 214.204804 -159.971232)
		(end 214.204804 -114.057938)
		(width 0.14605)
		(layer "In2.Cu")
		(net "UART_SDB_B_RX")
	)
	(segment
		(start 217.171778 -199.157844)
		(end 216.65819 -198.644256)
		(width 0.14605)
		(layer "In2.Cu")
		(net "UART_SDB_B_RX")
	)
	(segment
		(start 214.5792 -227.559108)
		(end 213.881462 -226.86137)
		(width 0.14605)
		(layer "In2.Cu")
		(net "UART_SDB_B_RX")
	)
	(segment
		(start 216.370662 -212.797644)
		(end 217.171778 -211.996528)
		(width 0.14605)
		(layer "In2.Cu")
		(net "UART_SDB_B_RX")
	)
	(segment
		(start 219.654882 -75.145138)
		(end 220.800168 -73.999852)
		(width 0.14605)
		(layer "In2.Cu")
		(net "UART_SDB_B_RX")
	)
	(segment
		(start 217.171778 -211.996528)
		(end 217.171778 -199.157844)
		(width 0.14605)
		(layer "In2.Cu")
		(net "UART_SDB_B_RX")
	)
	(segment
		(start 214.922354 -113.340388)
		(end 214.922354 -103.381302)
		(width 0.14605)
		(layer "In2.Cu")
		(net "UART_SDB_B_RX")
	)
	(segment
		(start 216.370662 -219.394278)
		(end 216.370662 -212.797644)
		(width 0.14605)
		(layer "In2.Cu")
		(net "UART_SDB_B_RX")
	)
	(segment
		(start 213.881462 -221.883478)
		(end 216.370662 -219.394278)
		(width 0.14605)
		(layer "In2.Cu")
		(net "UART_SDB_B_RX")
	)
	(segment
		(start 216.65819 -198.644256)
		(end 216.65819 -174.747174)
		(width 0.14605)
		(layer "In2.Cu")
		(net "UART_SDB_B_RX")
	)
	(segment
		(start 215.782652 -161.54908)
		(end 214.204804 -159.971232)
		(width 0.14605)
		(layer "In2.Cu")
		(net "UART_SDB_B_RX")
	)
	(segment
		(start 219.44203 -79.705708)
		(end 219.654882 -79.492856)
		(width 0.14605)
		(layer "In2.Cu")
		(net "UART_SDB_B_RX")
	)
	(segment
		(start 213.881462 -226.86137)
		(end 213.881462 -221.883478)
		(width 0.14605)
		(layer "In2.Cu")
		(net "UART_SDB_B_RX")
	)
	(segment
		(start 214.922354 -103.381302)
		(end 219.44203 -98.861626)
		(width 0.14605)
		(layer "In2.Cu")
		(net "UART_SDB_B_RX")
	)
	(segment
		(start 216.65819 -174.747174)
		(end 215.782652 -173.871636)
		(width 0.14605)
		(layer "In2.Cu")
		(net "UART_SDB_B_RX")
	)
	(segment
		(start 215.782652 -173.871636)
		(end 215.782652 -161.54908)
		(width 0.14605)
		(layer "In2.Cu")
		(net "UART_SDB_B_RX")
	)
	(segment
		(start 219.654882 -79.492856)
		(end 219.654882 -75.145138)
		(width 0.14605)
		(layer "In2.Cu")
		(net "UART_SDB_B_RX")
	)
	(segment
		(start 214.204804 -114.057938)
		(end 214.922354 -113.340388)
		(width 0.14605)
		(layer "In2.Cu")
		(net "UART_SDB_B_RX")
	)
	(segment
		(start 219.44203 -98.861626)
		(end 219.44203 -79.705708)
		(width 0.14605)
		(layer "In2.Cu")
		(net "UART_SDB_B_RX")
	)
	(segment
		(start 254.161798 -225.749612)
		(end 254.114808 -225.796602)
		(width 0.14605)
		(layer "In5.Cu")
		(net "UART_SDB_B_RX")
	)
	(segment
		(start 270.743172 -225.749612)
		(end 254.161798 -225.749612)
		(width 0.14605)
		(layer "In5.Cu")
		(net "UART_SDB_B_RX")
	)
	(segment
		(start 239.781842 -227.08743)
		(end 221.80677 -227.08743)
		(width 0.14605)
		(layer "In5.Cu")
		(net "UART_SDB_B_RX")
	)
	(segment
		(start 277.219918 -227.45573)
		(end 272.44929 -227.45573)
		(width 0.14605)
		(layer "In5.Cu")
		(net "UART_SDB_B_RX")
	)
	(segment
		(start 277.42261 -227.253038)
		(end 277.219918 -227.45573)
		(width 0.14605)
		(layer "In5.Cu")
		(net "UART_SDB_B_RX")
	)
	(segment
		(start 249.02795 -226.71405)
		(end 247.591834 -226.71405)
		(width 0.14605)
		(layer "In5.Cu")
		(net "UART_SDB_B_RX")
	)
	(segment
		(start 272.44929 -227.45573)
		(end 270.743172 -225.749612)
		(width 0.14605)
		(layer "In5.Cu")
		(net "UART_SDB_B_RX")
	)
	(segment
		(start 247.591834 -226.71405)
		(end 246.069104 -225.19132)
		(width 0.14605)
		(layer "In5.Cu")
		(net "UART_SDB_B_RX")
	)
	(segment
		(start 254.114808 -225.796602)
		(end 249.945398 -225.796602)
		(width 0.14605)
		(layer "In5.Cu")
		(net "UART_SDB_B_RX")
	)
	(segment
		(start 215.05418 -228.034088)
		(end 214.5792 -227.559108)
		(width 0.14605)
		(layer "In5.Cu")
		(net "UART_SDB_B_RX")
	)
	(segment
		(start 282.83662 -227.894388)
		(end 282.19527 -227.253038)
		(width 0.14605)
		(layer "In5.Cu")
		(net "UART_SDB_B_RX")
	)
	(segment
		(start 241.677952 -225.19132)
		(end 239.781842 -227.08743)
		(width 0.14605)
		(layer "In5.Cu")
		(net "UART_SDB_B_RX")
	)
	(segment
		(start 246.069104 -225.19132)
		(end 241.677952 -225.19132)
		(width 0.14605)
		(layer "In5.Cu")
		(net "UART_SDB_B_RX")
	)
	(segment
		(start 282.19527 -227.253038)
		(end 277.42261 -227.253038)
		(width 0.14605)
		(layer "In5.Cu")
		(net "UART_SDB_B_RX")
	)
	(segment
		(start 220.860112 -228.034088)
		(end 215.05418 -228.034088)
		(width 0.14605)
		(layer "In5.Cu")
		(net "UART_SDB_B_RX")
	)
	(segment
		(start 249.945398 -225.796602)
		(end 249.02795 -226.71405)
		(width 0.14605)
		(layer "In5.Cu")
		(net "UART_SDB_B_RX")
	)
	(segment
		(start 221.80677 -227.08743)
		(end 220.860112 -228.034088)
		(width 0.14605)
		(layer "In5.Cu")
		(net "UART_SDB_B_RX")
	)
	(segment
		(start 300.9265 -227.6602)
		(end 300.9265 -226.7204)
		(width 0.17145)
		(layer "F.Cu")
		(net "SCC_B_TYPE_3")
	)
	(segment
		(start 283.000958 -230.858822)
		(end 281.836622 -229.694486)
		(width 0.17145)
		(layer "F.Cu")
		(net "SCC_B_TYPE_3")
	)
	(segment
		(start 290.120578 -230.858822)
		(end 283.000958 -230.858822)
		(width 0.17145)
		(layer "F.Cu")
		(net "SCC_B_TYPE_3")
	)
	(segment
		(start 300.9265 -226.7204)
		(end 294.259 -226.7204)
		(width 0.17145)
		(layer "F.Cu")
		(net "SCC_B_TYPE_3")
	)
	(segment
		(start 294.259 -226.7204)
		(end 290.120578 -230.858822)
		(width 0.17145)
		(layer "F.Cu")
		(net "SCC_B_TYPE_3")
	)
	(segment
		(start 288.343594 -171.554902)
		(end 289.785552 -172.99686)
		(width 0.17145)
		(layer "F.Cu")
		(net "SCC_B_TYPE_3")
	)
	(segment
		(start 280.35758 -171.554902)
		(end 288.343594 -171.554902)
		(width 0.17145)
		(layer "F.Cu")
		(net "SCC_B_TYPE_3")
	)
	(segment
		(start 289.785552 -172.99686)
		(end 308.522878 -172.99686)
		(width 0.17145)
		(layer "F.Cu")
		(net "SCC_B_TYPE_3")
	)
	(segment
		(start 308.522878 -172.99686)
		(end 313.05246 -172.99686)
		(width 0.17145)
		(layer "F.Cu")
		(net "SCC_B_TYPE_3")
	)
	(via
		(at 300.9265 -227.6602)
		(size 0.5588)
		(drill 0.3048)
		(layers "F.Cu" "B.Cu")
		(net "SCC_B_TYPE_3")
	)
	(via
		(at 313.05246 -172.99686)
		(size 0.5588)
		(drill 0.3048)
		(layers "F.Cu" "B.Cu")
		(net "SCC_B_TYPE_3")
	)
	(via
		(at 308.522878 -172.99686)
		(size 0.6604)
		(drill 0.3302)
		(layers "F.Cu" "B.Cu")
		(net "SCC_B_TYPE_3")
	)
	(via
		(at 280.35758 -171.554902)
		(size 0.5588)
		(drill 0.3048)
		(layers "F.Cu" "B.Cu")
		(net "SCC_B_TYPE_3")
	)
	(via
		(at 218.11996 -123.55322)
		(size 0.5588)
		(drill 0.3048)
		(layers "F.Cu" "B.Cu")
		(net "SCC_B_TYPE_3")
	)
	(segment
		(start 300.9265 -227.6602)
		(end 297.250358 -223.984058)
		(width 0.14605)
		(layer "In2.Cu")
		(net "SCC_B_TYPE_3")
	)
	(segment
		(start 225.604324 -79.393796)
		(end 225.604324 -106.2228)
		(width 0.14605)
		(layer "In2.Cu")
		(net "SCC_B_TYPE_3")
	)
	(segment
		(start 226.200208 -78.999842)
		(end 225.998278 -78.999842)
		(width 0.14605)
		(layer "In2.Cu")
		(net "SCC_B_TYPE_3")
	)
	(segment
		(start 312.547508 -190.864998)
		(end 312.547508 -173.501812)
		(width 0.14605)
		(layer "In2.Cu")
		(net "SCC_B_TYPE_3")
	)
	(segment
		(start 302.724312 -194.721734)
		(end 308.690772 -194.721734)
		(width 0.14605)
		(layer "In2.Cu")
		(net "SCC_B_TYPE_3")
	)
	(segment
		(start 312.547508 -173.501812)
		(end 313.05246 -172.99686)
		(width 0.14605)
		(layer "In2.Cu")
		(net "SCC_B_TYPE_3")
	)
	(segment
		(start 218.11996 -119.793258)
		(end 218.11996 -123.55322)
		(width 0.14605)
		(layer "In2.Cu")
		(net "SCC_B_TYPE_3")
	)
	(segment
		(start 297.250358 -200.195688)
		(end 302.724312 -194.721734)
		(width 0.14605)
		(layer "In2.Cu")
		(net "SCC_B_TYPE_3")
	)
	(segment
		(start 308.690772 -194.721734)
		(end 312.547508 -190.864998)
		(width 0.14605)
		(layer "In2.Cu")
		(net "SCC_B_TYPE_3")
	)
	(segment
		(start 225.998278 -78.999842)
		(end 225.604324 -79.393796)
		(width 0.14605)
		(layer "In2.Cu")
		(net "SCC_B_TYPE_3")
	)
	(segment
		(start 225.604324 -106.2228)
		(end 219.882974 -111.94415)
		(width 0.14605)
		(layer "In2.Cu")
		(net "SCC_B_TYPE_3")
	)
	(segment
		(start 219.369894 -112.456976)
		(end 219.369894 -118.543324)
		(width 0.14605)
		(layer "In2.Cu")
		(net "SCC_B_TYPE_3")
	)
	(segment
		(start 297.250358 -223.984058)
		(end 297.250358 -200.195688)
		(width 0.14605)
		(layer "In2.Cu")
		(net "SCC_B_TYPE_3")
	)
	(segment
		(start 219.88272 -111.94415)
		(end 219.369894 -112.456976)
		(width 0.14605)
		(layer "In2.Cu")
		(net "SCC_B_TYPE_3")
	)
	(segment
		(start 219.882974 -111.94415)
		(end 219.88272 -111.94415)
		(width 0.14605)
		(layer "In2.Cu")
		(net "SCC_B_TYPE_3")
	)
	(segment
		(start 219.369894 -118.543324)
		(end 218.11996 -119.793258)
		(width 0.14605)
		(layer "In2.Cu")
		(net "SCC_B_TYPE_3")
	)
	(segment
		(start 228.10089 -131.870958)
		(end 224.766124 -131.870958)
		(width 0.14605)
		(layer "In5.Cu")
		(net "SCC_B_TYPE_3")
	)
	(segment
		(start 263.10844 -150.114508)
		(end 253.697994 -140.704062)
		(width 0.14605)
		(layer "In5.Cu")
		(net "SCC_B_TYPE_3")
	)
	(segment
		(start 219.38234 -126.487174)
		(end 219.38234 -124.8156)
		(width 0.14605)
		(layer "In5.Cu")
		(net "SCC_B_TYPE_3")
	)
	(segment
		(start 292.563296 -151.593804)
		(end 291.084 -150.114508)
		(width 0.14605)
		(layer "In5.Cu")
		(net "SCC_B_TYPE_3")
	)
	(segment
		(start 236.933994 -140.704062)
		(end 228.10089 -131.870958)
		(width 0.14605)
		(layer "In5.Cu")
		(net "SCC_B_TYPE_3")
	)
	(segment
		(start 224.766124 -131.870958)
		(end 219.38234 -126.487174)
		(width 0.14605)
		(layer "In5.Cu")
		(net "SCC_B_TYPE_3")
	)
	(segment
		(start 280.35758 -171.554902)
		(end 281.405584 -171.554902)
		(width 0.14605)
		(layer "In5.Cu")
		(net "SCC_B_TYPE_3")
	)
	(segment
		(start 219.38234 -124.8156)
		(end 218.11996 -123.55322)
		(width 0.14605)
		(layer "In5.Cu")
		(net "SCC_B_TYPE_3")
	)
	(segment
		(start 291.084 -150.114508)
		(end 263.10844 -150.114508)
		(width 0.14605)
		(layer "In5.Cu")
		(net "SCC_B_TYPE_3")
	)
	(segment
		(start 292.563296 -160.39719)
		(end 292.563296 -151.593804)
		(width 0.14605)
		(layer "In5.Cu")
		(net "SCC_B_TYPE_3")
	)
	(segment
		(start 253.697994 -140.704062)
		(end 236.933994 -140.704062)
		(width 0.14605)
		(layer "In5.Cu")
		(net "SCC_B_TYPE_3")
	)
	(segment
		(start 281.405584 -171.554902)
		(end 292.563296 -160.39719)
		(width 0.14605)
		(layer "In5.Cu")
		(net "SCC_B_TYPE_3")
	)
	(segment
		(start 299.498766 -170.735498)
		(end 290.288472 -170.735498)
		(width 0.254)
		(layer "F.Cu")
		(net "SCC_B_STBY_PWR_EN")
	)
	(segment
		(start 290.288472 -170.735498)
		(end 289.87242 -171.15155)
		(width 0.254)
		(layer "F.Cu")
		(net "SCC_B_STBY_PWR_EN")
	)
	(via
		(at 289.90798 -230.0097)
		(size 0.5588)
		(drill 0.3048)
		(layers "F.Cu" "B.Cu")
		(net "SCC_B_STBY_PWR_EN")
	)
	(via
		(at 299.498766 -170.735498)
		(size 0.5588)
		(drill 0.3048)
		(layers "F.Cu" "B.Cu")
		(net "SCC_B_STBY_PWR_EN")
	)
	(via
		(at 240.133632 -96.205294)
		(size 0.5588)
		(drill 0.3048)
		(layers "F.Cu" "B.Cu")
		(net "SCC_B_STBY_PWR_EN")
	)
	(via
		(at 239.751616 -94.61119)
		(size 0.6096)
		(drill 0.3048)
		(layers "F.Cu" "B.Cu")
		(net "SCC_B_STBY_PWR_EN")
	)
	(via
		(at 289.87242 -171.15155)
		(size 0.5588)
		(drill 0.3048)
		(layers "F.Cu" "B.Cu")
		(net "SCC_B_STBY_PWR_EN")
	)
	(segment
		(start 234.822746 -89.714578)
		(end 235.288582 -90.180414)
		(width 0.254)
		(layer "B.Cu")
		(net "SCC_B_STBY_PWR_EN")
	)
	(segment
		(start 235.288582 -90.180414)
		(end 235.32084 -90.180414)
		(width 0.254)
		(layer "B.Cu")
		(net "SCC_B_STBY_PWR_EN")
	)
	(segment
		(start 231.4829 -89.714578)
		(end 234.822746 -89.714578)
		(width 0.254)
		(layer "B.Cu")
		(net "SCC_B_STBY_PWR_EN")
	)
	(segment
		(start 239.751616 -94.61119)
		(end 240.133632 -94.993206)
		(width 0.254)
		(layer "B.Cu")
		(net "SCC_B_STBY_PWR_EN")
	)
	(segment
		(start 226.0473 -75.3999)
		(end 224.856548 -76.590652)
		(width 0.254)
		(layer "B.Cu")
		(net "SCC_B_STBY_PWR_EN")
	)
	(segment
		(start 240.133632 -94.993206)
		(end 240.133632 -96.205294)
		(width 0.254)
		(layer "B.Cu")
		(net "SCC_B_STBY_PWR_EN")
	)
	(segment
		(start 289.90798 -235.05922)
		(end 289.90798 -230.0097)
		(width 0.254)
		(layer "B.Cu")
		(net "SCC_B_STBY_PWR_EN")
	)
	(segment
		(start 235.32084 -90.180414)
		(end 239.751616 -94.61119)
		(width 0.254)
		(layer "B.Cu")
		(net "SCC_B_STBY_PWR_EN")
	)
	(segment
		(start 226.200208 -75.3999)
		(end 226.0473 -75.3999)
		(width 0.254)
		(layer "B.Cu")
		(net "SCC_B_STBY_PWR_EN")
	)
	(segment
		(start 281.836622 -236.89437)
		(end 282.815792 -235.9152)
		(width 0.254)
		(layer "B.Cu")
		(net "SCC_B_STBY_PWR_EN")
	)
	(segment
		(start 224.856548 -76.590652)
		(end 224.856548 -83.088226)
		(width 0.254)
		(layer "B.Cu")
		(net "SCC_B_STBY_PWR_EN")
	)
	(segment
		(start 282.815792 -235.9152)
		(end 289.052 -235.9152)
		(width 0.254)
		(layer "B.Cu")
		(net "SCC_B_STBY_PWR_EN")
	)
	(segment
		(start 224.856548 -83.088226)
		(end 231.4829 -89.714578)
		(width 0.254)
		(layer "B.Cu")
		(net "SCC_B_STBY_PWR_EN")
	)
	(segment
		(start 289.052 -235.9152)
		(end 289.90798 -235.05922)
		(width 0.254)
		(layer "B.Cu")
		(net "SCC_B_STBY_PWR_EN")
	)
	(segment
		(start 299.665136 -170.915584)
		(end 299.729652 -170.9801)
		(width 0.254)
		(layer "In2.Cu")
		(net "SCC_B_STBY_PWR_EN")
	)
	(segment
		(start 299.665136 -185.344816)
		(end 299.665136 -186.217052)
		(width 0.254)
		(layer "In2.Cu")
		(net "SCC_B_STBY_PWR_EN")
	)
	(segment
		(start 299.729652 -170.9801)
		(end 299.729652 -185.2803)
		(width 0.254)
		(layer "In2.Cu")
		(net "SCC_B_STBY_PWR_EN")
	)
	(segment
		(start 299.665136 -186.217052)
		(end 293.512494 -192.369694)
		(width 0.254)
		(layer "In2.Cu")
		(net "SCC_B_STBY_PWR_EN")
	)
	(segment
		(start 299.498766 -170.735498)
		(end 299.665136 -170.901868)
		(width 0.254)
		(layer "In2.Cu")
		(net "SCC_B_STBY_PWR_EN")
	)
	(segment
		(start 293.512494 -226.405186)
		(end 289.90798 -230.0097)
		(width 0.254)
		(layer "In2.Cu")
		(net "SCC_B_STBY_PWR_EN")
	)
	(segment
		(start 293.512494 -192.369694)
		(end 293.512494 -226.405186)
		(width 0.254)
		(layer "In2.Cu")
		(net "SCC_B_STBY_PWR_EN")
	)
	(segment
		(start 299.665136 -170.901868)
		(end 299.665136 -170.915584)
		(width 0.254)
		(layer "In2.Cu")
		(net "SCC_B_STBY_PWR_EN")
	)
	(segment
		(start 299.729652 -185.2803)
		(end 299.665136 -185.344816)
		(width 0.254)
		(layer "In2.Cu")
		(net "SCC_B_STBY_PWR_EN")
	)
	(segment
		(start 251.51969 -103.568754)
		(end 261.44474 -103.568754)
		(width 0.254)
		(layer "In5.Cu")
		(net "SCC_B_STBY_PWR_EN")
	)
	(segment
		(start 301.720758 -140.265404)
		(end 301.720504 -140.265658)
		(width 0.254)
		(layer "In5.Cu")
		(net "SCC_B_STBY_PWR_EN")
	)
	(segment
		(start 301.720504 -140.265658)
		(end 301.720504 -152.157684)
		(width 0.254)
		(layer "In5.Cu")
		(net "SCC_B_STBY_PWR_EN")
	)
	(segment
		(start 240.79581 -96.867472)
		(end 244.818408 -96.867472)
		(width 0.254)
		(layer "In5.Cu")
		(net "SCC_B_STBY_PWR_EN")
	)
	(segment
		(start 263.271762 -105.395776)
		(end 263.346946 -105.395776)
		(width 0.254)
		(layer "In5.Cu")
		(net "SCC_B_STBY_PWR_EN")
	)
	(segment
		(start 301.305976 -152.572212)
		(end 301.305722 -152.572212)
		(width 0.254)
		(layer "In5.Cu")
		(net "SCC_B_STBY_PWR_EN")
	)
	(segment
		(start 301.720504 -138.677904)
		(end 301.720504 -139.315698)
		(width 0.254)
		(layer "In5.Cu")
		(net "SCC_B_STBY_PWR_EN")
	)
	(segment
		(start 296.80281 -164.093652)
		(end 289.87242 -171.024042)
		(width 0.254)
		(layer "In5.Cu")
		(net "SCC_B_STBY_PWR_EN")
	)
	(segment
		(start 301.720758 -139.315952)
		(end 301.720758 -140.265404)
		(width 0.254)
		(layer "In5.Cu")
		(net "SCC_B_STBY_PWR_EN")
	)
	(segment
		(start 283.3624 -122.3645)
		(end 285.4071 -122.3645)
		(width 0.254)
		(layer "In5.Cu")
		(net "SCC_B_STBY_PWR_EN")
	)
	(segment
		(start 277.445978 -119.494808)
		(end 280.492708 -119.494808)
		(width 0.254)
		(layer "In5.Cu")
		(net "SCC_B_STBY_PWR_EN")
	)
	(segment
		(start 296.80281 -157.075124)
		(end 296.80281 -164.093652)
		(width 0.254)
		(layer "In5.Cu")
		(net "SCC_B_STBY_PWR_EN")
	)
	(segment
		(start 261.44474 -103.568754)
		(end 263.271762 -105.395776)
		(width 0.254)
		(layer "In5.Cu")
		(net "SCC_B_STBY_PWR_EN")
	)
	(segment
		(start 301.305722 -152.572212)
		(end 296.80281 -157.075124)
		(width 0.254)
		(layer "In5.Cu")
		(net "SCC_B_STBY_PWR_EN")
	)
	(segment
		(start 244.818408 -96.867472)
		(end 251.51969 -103.568754)
		(width 0.254)
		(layer "In5.Cu")
		(net "SCC_B_STBY_PWR_EN")
	)
	(segment
		(start 280.492708 -119.494808)
		(end 283.3624 -122.3645)
		(width 0.254)
		(layer "In5.Cu")
		(net "SCC_B_STBY_PWR_EN")
	)
	(segment
		(start 263.346946 -105.395776)
		(end 277.445978 -119.494808)
		(width 0.254)
		(layer "In5.Cu")
		(net "SCC_B_STBY_PWR_EN")
	)
	(segment
		(start 301.720504 -152.157684)
		(end 301.305976 -152.572212)
		(width 0.254)
		(layer "In5.Cu")
		(net "SCC_B_STBY_PWR_EN")
	)
	(segment
		(start 285.4071 -122.3645)
		(end 301.720504 -138.677904)
		(width 0.254)
		(layer "In5.Cu")
		(net "SCC_B_STBY_PWR_EN")
	)
	(segment
		(start 240.133632 -96.205294)
		(end 240.79581 -96.867472)
		(width 0.254)
		(layer "In5.Cu")
		(net "SCC_B_STBY_PWR_EN")
	)
	(segment
		(start 289.87242 -171.024042)
		(end 289.87242 -171.15155)
		(width 0.254)
		(layer "In5.Cu")
		(net "SCC_B_STBY_PWR_EN")
	)
	(segment
		(start 301.720504 -139.315698)
		(end 301.720758 -139.315952)
		(width 0.254)
		(layer "In5.Cu")
		(net "SCC_B_STBY_PWR_EN")
	)
	(via
		(at 298.9834 -125.8062)
		(size 0.5588)
		(drill 0.3048)
		(layers "F.Cu" "B.Cu")
		(net "SCC_B_PWR_LED")
	)
	(via
		(at 261.076948 -105.186988)
		(size 0.6096)
		(drill 0.3048)
		(layers "F.Cu" "B.Cu")
		(net "SCC_B_PWR_LED")
	)
	(segment
		(start 226.835208 -78.091792)
		(end 226.835208 -83.027774)
		(width 0.254)
		(layer "B.Cu")
		(net "SCC_B_PWR_LED")
	)
	(segment
		(start 228.000052 -64.499998)
		(end 227.076 -65.42405)
		(width 0.254)
		(layer "B.Cu")
		(net "SCC_B_PWR_LED")
	)
	(segment
		(start 298.129452 -124.952252)
		(end 298.9834 -125.8062)
		(width 0.254)
		(layer "B.Cu")
		(net "SCC_B_PWR_LED")
	)
	(segment
		(start 275.92909 -120.03913)
		(end 275.92909 -120.588532)
		(width 0.254)
		(layer "B.Cu")
		(net "SCC_B_PWR_LED")
	)
	(segment
		(start 227.076 -65.42405)
		(end 227.076 -77.851)
		(width 0.254)
		(layer "B.Cu")
		(net "SCC_B_PWR_LED")
	)
	(segment
		(start 247.200674 -94.599252)
		(end 250.489212 -94.599252)
		(width 0.254)
		(layer "B.Cu")
		(net "SCC_B_PWR_LED")
	)
	(segment
		(start 250.489212 -94.599252)
		(end 261.076948 -105.186988)
		(width 0.254)
		(layer "B.Cu")
		(net "SCC_B_PWR_LED")
	)
	(segment
		(start 261.076948 -105.186988)
		(end 275.92909 -120.03913)
		(width 0.254)
		(layer "B.Cu")
		(net "SCC_B_PWR_LED")
	)
	(segment
		(start 232.080308 -88.272874)
		(end 235.420154 -88.272874)
		(width 0.254)
		(layer "B.Cu")
		(net "SCC_B_PWR_LED")
	)
	(segment
		(start 235.452412 -88.305132)
		(end 240.906554 -88.305132)
		(width 0.254)
		(layer "B.Cu")
		(net "SCC_B_PWR_LED")
	)
	(segment
		(start 235.420154 -88.272874)
		(end 235.452412 -88.305132)
		(width 0.254)
		(layer "B.Cu")
		(net "SCC_B_PWR_LED")
	)
	(segment
		(start 280.29281 -124.952252)
		(end 298.129452 -124.952252)
		(width 0.254)
		(layer "B.Cu")
		(net "SCC_B_PWR_LED")
	)
	(segment
		(start 226.835208 -83.027774)
		(end 232.080308 -88.272874)
		(width 0.254)
		(layer "B.Cu")
		(net "SCC_B_PWR_LED")
	)
	(segment
		(start 227.076 -77.851)
		(end 226.835208 -78.091792)
		(width 0.254)
		(layer "B.Cu")
		(net "SCC_B_PWR_LED")
	)
	(segment
		(start 240.906554 -88.305132)
		(end 247.200674 -94.599252)
		(width 0.254)
		(layer "B.Cu")
		(net "SCC_B_PWR_LED")
	)
	(segment
		(start 275.92909 -120.588532)
		(end 280.29281 -124.952252)
		(width 0.254)
		(layer "B.Cu")
		(net "SCC_B_PWR_LED")
	)
	(segment
		(start 290.261294 -222.50019)
		(end 292.898322 -219.863162)
		(width 0.254)
		(layer "In2.Cu")
		(net "SCC_B_PWR_LED")
	)
	(segment
		(start 290.233354 -222.50019)
		(end 290.261294 -222.50019)
		(width 0.254)
		(layer "In2.Cu")
		(net "SCC_B_PWR_LED")
	)
	(segment
		(start 284.236668 -224.294446)
		(end 285.163514 -223.3676)
		(width 0.254)
		(layer "In2.Cu")
		(net "SCC_B_PWR_LED")
	)
	(segment
		(start 293.004494 -219.72905)
		(end 293.004494 -192.159128)
		(width 0.254)
		(layer "In2.Cu")
		(net "SCC_B_PWR_LED")
	)
	(segment
		(start 298.939966 -155.1051)
		(end 299.751496 -154.29357)
		(width 0.254)
		(layer "In2.Cu")
		(net "SCC_B_PWR_LED")
	)
	(segment
		(start 293.004494 -192.159128)
		(end 298.939966 -186.223656)
		(width 0.254)
		(layer "In2.Cu")
		(net "SCC_B_PWR_LED")
	)
	(segment
		(start 292.898322 -219.863162)
		(end 292.898322 -219.835222)
		(width 0.254)
		(layer "In2.Cu")
		(net "SCC_B_PWR_LED")
	)
	(segment
		(start 298.939966 -186.223656)
		(end 298.939966 -155.1051)
		(width 0.254)
		(layer "In2.Cu")
		(net "SCC_B_PWR_LED")
	)
	(segment
		(start 299.751496 -154.29357)
		(end 299.751496 -126.574296)
		(width 0.254)
		(layer "In2.Cu")
		(net "SCC_B_PWR_LED")
	)
	(segment
		(start 292.898322 -219.835222)
		(end 293.004494 -219.72905)
		(width 0.254)
		(layer "In2.Cu")
		(net "SCC_B_PWR_LED")
	)
	(segment
		(start 285.163514 -223.3676)
		(end 289.365944 -223.3676)
		(width 0.254)
		(layer "In2.Cu")
		(net "SCC_B_PWR_LED")
	)
	(segment
		(start 289.365944 -223.3676)
		(end 290.233354 -222.50019)
		(width 0.254)
		(layer "In2.Cu")
		(net "SCC_B_PWR_LED")
	)
	(segment
		(start 299.751496 -126.574296)
		(end 298.9834 -125.8062)
		(width 0.254)
		(layer "In2.Cu")
		(net "SCC_B_PWR_LED")
	)
	(segment
		(start 258.319778 -237.14075)
		(end 258.319778 -238.51362)
		(width 0.254)
		(layer "F.Cu")
		(net "SCC_B_FULL_PWR_EN")
	)
	(segment
		(start 271.103598 -236.954568)
		(end 271.103598 -226.928172)
		(width 0.254)
		(layer "F.Cu")
		(net "SCC_B_FULL_PWR_EN")
	)
	(segment
		(start 34.678874 -360.82605)
		(end 34.678874 -360.141266)
		(width 0.254)
		(layer "F.Cu")
		(net "SCC_B_FULL_PWR_EN")
	)
	(segment
		(start 34.959036 -358.61244)
		(end 34.740596 -358.394)
		(width 0.254)
		(layer "F.Cu")
		(net "SCC_B_FULL_PWR_EN")
	)
	(segment
		(start 282.51404 -223.41459)
		(end 282.83662 -223.73717)
		(width 0.254)
		(layer "F.Cu")
		(net "SCC_B_FULL_PWR_EN")
	)
	(segment
		(start 34.678874 -360.141266)
		(end 34.959036 -359.861104)
		(width 0.254)
		(layer "F.Cu")
		(net "SCC_B_FULL_PWR_EN")
	)
	(segment
		(start 41.242996 -363.5883)
		(end 39.960296 -363.5883)
		(width 0.254)
		(layer "F.Cu")
		(net "SCC_B_FULL_PWR_EN")
	)
	(segment
		(start 34.959036 -359.861104)
		(end 34.959036 -358.61244)
		(width 0.254)
		(layer "F.Cu")
		(net "SCC_B_FULL_PWR_EN")
	)
	(segment
		(start 282.83662 -223.73717)
		(end 282.83662 -224.294446)
		(width 0.254)
		(layer "F.Cu")
		(net "SCC_B_FULL_PWR_EN")
	)
	(segment
		(start 273.229324 -239.080294)
		(end 271.103598 -236.954568)
		(width 0.254)
		(layer "F.Cu")
		(net "SCC_B_FULL_PWR_EN")
	)
	(segment
		(start 271.103598 -226.928172)
		(end 274.61718 -223.41459)
		(width 0.254)
		(layer "F.Cu")
		(net "SCC_B_FULL_PWR_EN")
	)
	(segment
		(start 36.94303 -361.4928)
		(end 35.345624 -361.4928)
		(width 0.254)
		(layer "F.Cu")
		(net "SCC_B_FULL_PWR_EN")
	)
	(segment
		(start 35.345624 -361.4928)
		(end 34.678874 -360.82605)
		(width 0.254)
		(layer "F.Cu")
		(net "SCC_B_FULL_PWR_EN")
	)
	(segment
		(start 258.319778 -238.51362)
		(end 260.128766 -240.322608)
		(width 0.254)
		(layer "F.Cu")
		(net "SCC_B_FULL_PWR_EN")
	)
	(segment
		(start 39.960296 -363.5883)
		(end 39.718996 -363.347)
		(width 0.254)
		(layer "F.Cu")
		(net "SCC_B_FULL_PWR_EN")
	)
	(segment
		(start 274.61718 -223.41459)
		(end 282.51404 -223.41459)
		(width 0.254)
		(layer "F.Cu")
		(net "SCC_B_FULL_PWR_EN")
	)
	(via
		(at 39.718996 -363.347)
		(size 0.5588)
		(drill 0.3048)
		(layers "F.Cu" "B.Cu")
		(net "SCC_B_FULL_PWR_EN")
	)
	(via
		(at 34.959036 -359.861104)
		(size 0.6604)
		(drill 0.3302)
		(layers "F.Cu" "B.Cu")
		(net "SCC_B_FULL_PWR_EN")
	)
	(via
		(at 212.586062 -259.969)
		(size 0.5588)
		(drill 0.3048)
		(layers "F.Cu" "B.Cu")
		(net "SCC_B_FULL_PWR_EN")
	)
	(via
		(at 273.229324 -239.080294)
		(size 0.5588)
		(drill 0.3048)
		(layers "F.Cu" "B.Cu")
		(net "SCC_B_FULL_PWR_EN")
	)
	(via
		(at 211.5312 -291.465)
		(size 0.5588)
		(drill 0.3048)
		(layers "F.Cu" "B.Cu")
		(net "SCC_B_FULL_PWR_EN")
	)
	(via
		(at 34.740596 -358.394)
		(size 0.5588)
		(drill 0.3048)
		(layers "F.Cu" "B.Cu")
		(net "SCC_B_FULL_PWR_EN")
	)
	(via
		(at 260.128766 -240.322608)
		(size 0.5588)
		(drill 0.3048)
		(layers "F.Cu" "B.Cu")
		(net "SCC_B_FULL_PWR_EN")
	)
	(segment
		(start 35.070796 -358.394)
		(end 39.718996 -363.0422)
		(width 0.254)
		(layer "B.Cu")
		(net "SCC_B_FULL_PWR_EN")
	)
	(segment
		(start 34.740596 -358.394)
		(end 35.070796 -358.394)
		(width 0.254)
		(layer "B.Cu")
		(net "SCC_B_FULL_PWR_EN")
	)
	(segment
		(start 39.718996 -363.0422)
		(end 39.718996 -363.347)
		(width 0.254)
		(layer "B.Cu")
		(net "SCC_B_FULL_PWR_EN")
	)
	(segment
		(start 219.903802 -109.918754)
		(end 219.903802 -108.361734)
		(width 0.254)
		(layer "In2.Cu")
		(net "SCC_B_FULL_PWR_EN")
	)
	(segment
		(start 211.5312 -291.465)
		(end 212.586062 -290.410138)
		(width 0.254)
		(layer "In2.Cu")
		(net "SCC_B_FULL_PWR_EN")
	)
	(segment
		(start 212.586062 -259.969)
		(end 212.586062 -236.86008)
		(width 0.254)
		(layer "In2.Cu")
		(net "SCC_B_FULL_PWR_EN")
	)
	(segment
		(start 219.84208 -215.2142)
		(end 219.84208 -170.279568)
		(width 0.254)
		(layer "In2.Cu")
		(net "SCC_B_FULL_PWR_EN")
	)
	(segment
		(start 212.586062 -290.410138)
		(end 212.586062 -259.969)
		(width 0.254)
		(layer "In2.Cu")
		(net "SCC_B_FULL_PWR_EN")
	)
	(segment
		(start 219.84208 -170.279568)
		(end 218.744292 -169.18178)
		(width 0.254)
		(layer "In2.Cu")
		(net "SCC_B_FULL_PWR_EN")
	)
	(segment
		(start 215.43645 -226.792536)
		(end 215.43645 -224.820988)
		(width 0.254)
		(layer "In2.Cu")
		(net "SCC_B_FULL_PWR_EN")
	)
	(segment
		(start 212.586062 -236.86008)
		(end 213.756748 -235.689394)
		(width 0.254)
		(layer "In2.Cu")
		(net "SCC_B_FULL_PWR_EN")
	)
	(segment
		(start 219.903802 -108.361734)
		(end 222.63608 -105.629456)
		(width 0.254)
		(layer "In2.Cu")
		(net "SCC_B_FULL_PWR_EN")
	)
	(segment
		(start 218.079574 -111.742982)
		(end 219.903802 -109.918754)
		(width 0.254)
		(layer "In2.Cu")
		(net "SCC_B_FULL_PWR_EN")
	)
	(segment
		(start 218.079574 -118.113302)
		(end 218.079574 -111.742982)
		(width 0.254)
		(layer "In2.Cu")
		(net "SCC_B_FULL_PWR_EN")
	)
	(segment
		(start 215.43645 -222.408496)
		(end 218.446096 -219.39885)
		(width 0.254)
		(layer "In2.Cu")
		(net "SCC_B_FULL_PWR_EN")
	)
	(segment
		(start 213.756748 -235.689394)
		(end 213.756748 -229.912164)
		(width 0.254)
		(layer "In2.Cu")
		(net "SCC_B_FULL_PWR_EN")
	)
	(segment
		(start 218.446096 -216.60993)
		(end 219.62618 -215.429846)
		(width 0.254)
		(layer "In2.Cu")
		(net "SCC_B_FULL_PWR_EN")
	)
	(segment
		(start 218.744292 -160.733994)
		(end 216.875106 -158.864808)
		(width 0.254)
		(layer "In2.Cu")
		(net "SCC_B_FULL_PWR_EN")
	)
	(segment
		(start 222.63608 -105.629456)
		(end 222.63608 -84.481924)
		(width 0.254)
		(layer "In2.Cu")
		(net "SCC_B_FULL_PWR_EN")
	)
	(segment
		(start 213.756748 -229.912164)
		(end 215.5317 -228.137212)
		(width 0.254)
		(layer "In2.Cu")
		(net "SCC_B_FULL_PWR_EN")
	)
	(segment
		(start 215.43645 -224.820988)
		(end 215.433656 -224.818194)
		(width 0.254)
		(layer "In2.Cu")
		(net "SCC_B_FULL_PWR_EN")
	)
	(segment
		(start 222.63608 -84.481924)
		(end 223.342708 -83.775296)
		(width 0.254)
		(layer "In2.Cu")
		(net "SCC_B_FULL_PWR_EN")
	)
	(segment
		(start 215.5317 -226.887786)
		(end 215.43645 -226.792536)
		(width 0.254)
		(layer "In2.Cu")
		(net "SCC_B_FULL_PWR_EN")
	)
	(segment
		(start 215.43645 -224.8154)
		(end 215.43645 -222.408496)
		(width 0.254)
		(layer "In2.Cu")
		(net "SCC_B_FULL_PWR_EN")
	)
	(segment
		(start 215.433656 -224.818194)
		(end 215.43645 -224.8154)
		(width 0.254)
		(layer "In2.Cu")
		(net "SCC_B_FULL_PWR_EN")
	)
	(segment
		(start 219.62618 -215.429846)
		(end 219.626434 -215.429846)
		(width 0.254)
		(layer "In2.Cu")
		(net "SCC_B_FULL_PWR_EN")
	)
	(segment
		(start 218.446096 -219.39885)
		(end 218.446096 -216.60993)
		(width 0.254)
		(layer "In2.Cu")
		(net "SCC_B_FULL_PWR_EN")
	)
	(segment
		(start 223.342708 -72.15759)
		(end 226.200208 -69.30009)
		(width 0.254)
		(layer "In2.Cu")
		(net "SCC_B_FULL_PWR_EN")
	)
	(segment
		(start 218.744292 -169.18178)
		(end 218.744292 -160.733994)
		(width 0.254)
		(layer "In2.Cu")
		(net "SCC_B_FULL_PWR_EN")
	)
	(segment
		(start 216.875106 -119.31777)
		(end 218.079574 -118.113302)
		(width 0.254)
		(layer "In2.Cu")
		(net "SCC_B_FULL_PWR_EN")
	)
	(segment
		(start 219.626434 -215.429846)
		(end 219.84208 -215.2142)
		(width 0.254)
		(layer "In2.Cu")
		(net "SCC_B_FULL_PWR_EN")
	)
	(segment
		(start 215.5317 -228.137212)
		(end 215.5317 -226.887786)
		(width 0.254)
		(layer "In2.Cu")
		(net "SCC_B_FULL_PWR_EN")
	)
	(segment
		(start 223.342708 -83.775296)
		(end 223.342708 -72.15759)
		(width 0.254)
		(layer "In2.Cu")
		(net "SCC_B_FULL_PWR_EN")
	)
	(segment
		(start 216.875106 -158.864808)
		(end 216.875106 -119.31777)
		(width 0.254)
		(layer "In2.Cu")
		(net "SCC_B_FULL_PWR_EN")
	)
	(segment
		(start 212.586062 -259.969)
		(end 246.126 -259.969)
		(width 0.254)
		(layer "In5.Cu")
		(net "SCC_B_FULL_PWR_EN")
	)
	(segment
		(start 258.445 -242.006374)
		(end 260.128766 -240.322608)
		(width 0.254)
		(layer "In5.Cu")
		(net "SCC_B_FULL_PWR_EN")
	)
	(segment
		(start 34.740596 -358.394)
		(end 34.740596 -329.586082)
		(width 0.254)
		(layer "In5.Cu")
		(net "SCC_B_FULL_PWR_EN")
	)
	(segment
		(start 258.445 -247.65)
		(end 258.445 -242.006374)
		(width 0.254)
		(layer "In5.Cu")
		(net "SCC_B_FULL_PWR_EN")
	)
	(segment
		(start 180.092096 -315.868304)
		(end 180.29174 -315.868304)
		(width 0.254)
		(layer "In5.Cu")
		(net "SCC_B_FULL_PWR_EN")
	)
	(segment
		(start 197.301358 -298.858686)
		(end 197.301358 -298.659042)
		(width 0.254)
		(layer "In5.Cu")
		(net "SCC_B_FULL_PWR_EN")
	)
	(segment
		(start 180.29174 -315.868304)
		(end 197.301358 -298.858686)
		(width 0.254)
		(layer "In5.Cu")
		(net "SCC_B_FULL_PWR_EN")
	)
	(segment
		(start 204.4954 -291.465)
		(end 211.5312 -291.465)
		(width 0.254)
		(layer "In5.Cu")
		(net "SCC_B_FULL_PWR_EN")
	)
	(segment
		(start 179.578 -316.3824)
		(end 180.092096 -315.868304)
		(width 0.254)
		(layer "In5.Cu")
		(net "SCC_B_FULL_PWR_EN")
	)
	(segment
		(start 197.301358 -298.659042)
		(end 204.4954 -291.465)
		(width 0.254)
		(layer "In5.Cu")
		(net "SCC_B_FULL_PWR_EN")
	)
	(segment
		(start 246.126 -259.969)
		(end 258.445 -247.65)
		(width 0.254)
		(layer "In5.Cu")
		(net "SCC_B_FULL_PWR_EN")
	)
	(segment
		(start 273.229324 -239.080294)
		(end 261.37108 -239.080294)
		(width 0.254)
		(layer "In5.Cu")
		(net "SCC_B_FULL_PWR_EN")
	)
	(segment
		(start 34.740596 -329.586082)
		(end 47.944278 -316.3824)
		(width 0.254)
		(layer "In5.Cu")
		(net "SCC_B_FULL_PWR_EN")
	)
	(segment
		(start 47.944278 -316.3824)
		(end 179.578 -316.3824)
		(width 0.254)
		(layer "In5.Cu")
		(net "SCC_B_FULL_PWR_EN")
	)
	(segment
		(start 261.37108 -239.080294)
		(end 260.128766 -240.322608)
		(width 0.254)
		(layer "In5.Cu")
		(net "SCC_B_FULL_PWR_EN")
	)
	(segment
		(start 240.692432 -96.826832)
		(end 248.9454 -105.0798)
		(width 0.254)
		(layer "F.Cu")
		(net "SCC_B_FULL_PGOOD")
	)
	(segment
		(start 259.067046 -112.181132)
		(end 259.470906 -111.777272)
		(width 0.254)
		(layer "F.Cu")
		(net "SCC_B_FULL_PGOOD")
	)
	(segment
		(start 226.200208 -70.39991)
		(end 225.23958 -71.360538)
		(width 0.254)
		(layer "F.Cu")
		(net "SCC_B_FULL_PGOOD")
	)
	(segment
		(start 256.046732 -112.181132)
		(end 259.067046 -112.181132)
		(width 0.254)
		(layer "F.Cu")
		(net "SCC_B_FULL_PGOOD")
	)
	(segment
		(start 259.56006 -111.777272)
		(end 259.56006 -111.688118)
		(width 0.254)
		(layer "F.Cu")
		(net "SCC_B_FULL_PGOOD")
	)
	(segment
		(start 225.23958 -80.071214)
		(end 240.692432 -95.524066)
		(width 0.254)
		(layer "F.Cu")
		(net "SCC_B_FULL_PGOOD")
	)
	(segment
		(start 240.692432 -95.524066)
		(end 240.692432 -96.826832)
		(width 0.254)
		(layer "F.Cu")
		(net "SCC_B_FULL_PGOOD")
	)
	(segment
		(start 248.9454 -105.0798)
		(end 256.046732 -112.181132)
		(width 0.254)
		(layer "F.Cu")
		(net "SCC_B_FULL_PGOOD")
	)
	(segment
		(start 259.470906 -111.777272)
		(end 259.56006 -111.777272)
		(width 0.254)
		(layer "F.Cu")
		(net "SCC_B_FULL_PGOOD")
	)
	(segment
		(start 225.23958 -71.360538)
		(end 225.23958 -80.071214)
		(width 0.254)
		(layer "F.Cu")
		(net "SCC_B_FULL_PGOOD")
	)
	(via
		(at 259.56006 -111.688118)
		(size 0.5588)
		(drill 0.3048)
		(layers "F.Cu" "B.Cu")
		(net "SCC_B_FULL_PGOOD")
	)
	(via
		(at 248.9454 -105.0798)
		(size 0.6604)
		(drill 0.3302)
		(layers "F.Cu" "B.Cu")
		(net "SCC_B_FULL_PGOOD")
	)
	(segment
		(start 267.00861 -111.680244)
		(end 259.56006 -111.680244)
		(width 0.254)
		(layer "In5.Cu")
		(net "SCC_B_FULL_PGOOD")
	)
	(segment
		(start 299.793406 -141.872462)
		(end 299.793406 -140.865098)
		(width 0.254)
		(layer "In5.Cu")
		(net "SCC_B_FULL_PGOOD")
	)
	(segment
		(start 276.724872 -121.396506)
		(end 267.00861 -111.680244)
		(width 0.254)
		(layer "In5.Cu")
		(net "SCC_B_FULL_PGOOD")
	)
	(segment
		(start 284.000956 -124.218954)
		(end 282.700222 -124.218954)
		(width 0.254)
		(layer "In5.Cu")
		(net "SCC_B_FULL_PGOOD")
	)
	(segment
		(start 299.793406 -140.865098)
		(end 299.793152 -140.864844)
		(width 0.254)
		(layer "In5.Cu")
		(net "SCC_B_FULL_PGOOD")
	)
	(segment
		(start 299.793152 -140.864844)
		(end 299.793152 -140.01115)
		(width 0.254)
		(layer "In5.Cu")
		(net "SCC_B_FULL_PGOOD")
	)
	(segment
		(start 279.877774 -121.396506)
		(end 276.724872 -121.396506)
		(width 0.254)
		(layer "In5.Cu")
		(net "SCC_B_FULL_PGOOD")
	)
	(segment
		(start 299.793152 -141.872716)
		(end 299.793406 -141.872462)
		(width 0.254)
		(layer "In5.Cu")
		(net "SCC_B_FULL_PGOOD")
	)
	(segment
		(start 299.793152 -149.039072)
		(end 299.793152 -141.872716)
		(width 0.254)
		(layer "In5.Cu")
		(net "SCC_B_FULL_PGOOD")
	)
	(segment
		(start 294.948356 -162.58286)
		(end 294.948356 -153.883868)
		(width 0.254)
		(layer "In5.Cu")
		(net "SCC_B_FULL_PGOOD")
	)
	(segment
		(start 281.836622 -175.694594)
		(end 294.948356 -162.58286)
		(width 0.254)
		(layer "In5.Cu")
		(net "SCC_B_FULL_PGOOD")
	)
	(segment
		(start 294.948356 -153.883868)
		(end 299.793152 -149.039072)
		(width 0.254)
		(layer "In5.Cu")
		(net "SCC_B_FULL_PGOOD")
	)
	(segment
		(start 282.700222 -124.218954)
		(end 279.877774 -121.396506)
		(width 0.254)
		(layer "In5.Cu")
		(net "SCC_B_FULL_PGOOD")
	)
	(segment
		(start 259.56006 -111.680244)
		(end 259.56006 -111.688118)
		(width 0.254)
		(layer "In5.Cu")
		(net "SCC_B_FULL_PGOOD")
	)
	(segment
		(start 299.793152 -140.01115)
		(end 284.000956 -124.218954)
		(width 0.254)
		(layer "In5.Cu")
		(net "SCC_B_FULL_PGOOD")
	)
	(segment
		(start 224.73158 -68.84162)
		(end 224.73158 -80.384904)
		(width 0.254)
		(layer "F.Cu")
		(net "SCC_A_FULL_PWR_EN")
	)
	(segment
		(start 222.251778 -152.728422)
		(end 222.140018 -152.728422)
		(width 0.254)
		(layer "F.Cu")
		(net "SCC_A_FULL_PWR_EN")
	)
	(segment
		(start 35.327336 -362.14304)
		(end 35.299396 -362.1151)
		(width 0.254)
		(layer "F.Cu")
		(net "SCC_A_FULL_PWR_EN")
	)
	(segment
		(start 34.956496 -362.1151)
		(end 35.299396 -362.1151)
		(width 0.254)
		(layer "F.Cu")
		(net "SCC_A_FULL_PWR_EN")
	)
	(segment
		(start 232.029 -142.9512)
		(end 222.251778 -152.728422)
		(width 0.254)
		(layer "F.Cu")
		(net "SCC_A_FULL_PWR_EN")
	)
	(segment
		(start 222.140018 -152.728422)
		(end 220.28404 -154.5844)
		(width 0.254)
		(layer "F.Cu")
		(net "SCC_A_FULL_PWR_EN")
	)
	(segment
		(start 225.373184 -68.200016)
		(end 224.73158 -68.84162)
		(width 0.254)
		(layer "F.Cu")
		(net "SCC_A_FULL_PWR_EN")
	)
	(segment
		(start 33.172654 -360.331258)
		(end 34.956496 -362.1151)
		(width 0.254)
		(layer "F.Cu")
		(net "SCC_A_FULL_PWR_EN")
	)
	(segment
		(start 235.204 -90.857324)
		(end 235.204 -92.4814)
		(width 0.254)
		(layer "F.Cu")
		(net "SCC_A_FULL_PWR_EN")
	)
	(segment
		(start 36.94303 -362.14304)
		(end 35.327336 -362.14304)
		(width 0.254)
		(layer "F.Cu")
		(net "SCC_A_FULL_PWR_EN")
	)
	(segment
		(start 224.73158 -80.384904)
		(end 235.204 -90.857324)
		(width 0.254)
		(layer "F.Cu")
		(net "SCC_A_FULL_PWR_EN")
	)
	(segment
		(start 232.029 -95.6564)
		(end 232.029 -142.9512)
		(width 0.254)
		(layer "F.Cu")
		(net "SCC_A_FULL_PWR_EN")
	)
	(segment
		(start 33.172654 -358.5718)
		(end 33.172654 -360.331258)
		(width 0.254)
		(layer "F.Cu")
		(net "SCC_A_FULL_PWR_EN")
	)
	(segment
		(start 235.204 -92.4814)
		(end 232.029 -95.6564)
		(width 0.254)
		(layer "F.Cu")
		(net "SCC_A_FULL_PWR_EN")
	)
	(segment
		(start 226.200208 -68.200016)
		(end 225.373184 -68.200016)
		(width 0.254)
		(layer "F.Cu")
		(net "SCC_A_FULL_PWR_EN")
	)
	(via
		(at 222.251778 -152.728422)
		(size 0.6604)
		(drill 0.3302)
		(layers "F.Cu" "B.Cu")
		(net "SCC_A_FULL_PWR_EN")
	)
	(via
		(at 201.04862 -156.1338)
		(size 0.5588)
		(drill 0.3048)
		(layers "F.Cu" "B.Cu")
		(net "SCC_A_FULL_PWR_EN")
	)
	(via
		(at 220.28404 -154.5844)
		(size 0.5588)
		(drill 0.3048)
		(layers "F.Cu" "B.Cu")
		(net "SCC_A_FULL_PWR_EN")
	)
	(via
		(at 33.172654 -358.5718)
		(size 0.5588)
		(drill 0.3048)
		(layers "F.Cu" "B.Cu")
		(net "SCC_A_FULL_PWR_EN")
	)
	(segment
		(start 180.241448 -212.73897)
		(end 180.241448 -212.143848)
		(width 0.254)
		(layer "In2.Cu")
		(net "SCC_A_FULL_PWR_EN")
	)
	(segment
		(start 33.172654 -358.5718)
		(end 33.292796 -358.451658)
		(width 0.254)
		(layer "In2.Cu")
		(net "SCC_A_FULL_PWR_EN")
	)
	(segment
		(start 198.621396 -189.617604)
		(end 198.621396 -158.561024)
		(width 0.254)
		(layer "In2.Cu")
		(net "SCC_A_FULL_PWR_EN")
	)
	(segment
		(start 180.241448 -212.143848)
		(end 180.241194 -212.143594)
		(width 0.254)
		(layer "In2.Cu")
		(net "SCC_A_FULL_PWR_EN")
	)
	(segment
		(start 192.5574 -260.858)
		(end 193.484246 -259.931154)
		(width 0.254)
		(layer "In2.Cu")
		(net "SCC_A_FULL_PWR_EN")
	)
	(segment
		(start 46.31563 -310.314848)
		(end 165.985952 -310.314848)
		(width 0.254)
		(layer "In2.Cu")
		(net "SCC_A_FULL_PWR_EN")
	)
	(segment
		(start 193.484246 -224.650046)
		(end 192.0748 -223.2406)
		(width 0.254)
		(layer "In2.Cu")
		(net "SCC_A_FULL_PWR_EN")
	)
	(segment
		(start 192.0748 -223.2406)
		(end 190.743078 -223.2406)
		(width 0.254)
		(layer "In2.Cu")
		(net "SCC_A_FULL_PWR_EN")
	)
	(segment
		(start 193.484246 -259.931154)
		(end 193.484246 -224.650046)
		(width 0.254)
		(layer "In2.Cu")
		(net "SCC_A_FULL_PWR_EN")
	)
	(segment
		(start 190.743078 -223.2406)
		(end 180.241448 -212.73897)
		(width 0.254)
		(layer "In2.Cu")
		(net "SCC_A_FULL_PWR_EN")
	)
	(segment
		(start 188.2902 -191.008)
		(end 197.231 -191.008)
		(width 0.254)
		(layer "In2.Cu")
		(net "SCC_A_FULL_PWR_EN")
	)
	(segment
		(start 192.5574 -283.7434)
		(end 192.5574 -260.858)
		(width 0.254)
		(layer "In2.Cu")
		(net "SCC_A_FULL_PWR_EN")
	)
	(segment
		(start 33.292796 -323.337682)
		(end 46.31563 -310.314848)
		(width 0.254)
		(layer "In2.Cu")
		(net "SCC_A_FULL_PWR_EN")
	)
	(segment
		(start 180.241194 -212.143594)
		(end 180.241194 -199.057006)
		(width 0.254)
		(layer "In2.Cu")
		(net "SCC_A_FULL_PWR_EN")
	)
	(segment
		(start 180.241194 -199.057006)
		(end 188.2902 -191.008)
		(width 0.254)
		(layer "In2.Cu")
		(net "SCC_A_FULL_PWR_EN")
	)
	(segment
		(start 198.621396 -158.561024)
		(end 201.04862 -156.1338)
		(width 0.254)
		(layer "In2.Cu")
		(net "SCC_A_FULL_PWR_EN")
	)
	(segment
		(start 165.985952 -310.314848)
		(end 192.5574 -283.7434)
		(width 0.254)
		(layer "In2.Cu")
		(net "SCC_A_FULL_PWR_EN")
	)
	(segment
		(start 33.292796 -358.451658)
		(end 33.292796 -323.337682)
		(width 0.254)
		(layer "In2.Cu")
		(net "SCC_A_FULL_PWR_EN")
	)
	(segment
		(start 197.231 -191.008)
		(end 198.621396 -189.617604)
		(width 0.254)
		(layer "In2.Cu")
		(net "SCC_A_FULL_PWR_EN")
	)
	(segment
		(start 203.58862 -153.67)
		(end 216.94521 -153.67)
		(width 0.254)
		(layer "In5.Cu")
		(net "SCC_A_FULL_PWR_EN")
	)
	(segment
		(start 201.04862 -156.1338)
		(end 201.04862 -156.21)
		(width 0.254)
		(layer "In5.Cu")
		(net "SCC_A_FULL_PWR_EN")
	)
	(segment
		(start 216.94521 -153.67)
		(end 217.83421 -154.559)
		(width 0.254)
		(layer "In5.Cu")
		(net "SCC_A_FULL_PWR_EN")
	)
	(segment
		(start 201.04862 -156.21)
		(end 203.58862 -153.67)
		(width 0.254)
		(layer "In5.Cu")
		(net "SCC_A_FULL_PWR_EN")
	)
	(segment
		(start 217.83421 -154.559)
		(end 220.25864 -154.559)
		(width 0.254)
		(layer "In5.Cu")
		(net "SCC_A_FULL_PWR_EN")
	)
	(segment
		(start 220.25864 -154.559)
		(end 220.28404 -154.5844)
		(width 0.254)
		(layer "In5.Cu")
		(net "SCC_A_FULL_PWR_EN")
	)
	(segment
		(start 267.589 -225.243136)
		(end 267.589 -225.6155)
		(width 0.17145)
		(layer "F.Cu")
		(net "I2C_CLIP_B_SDA")
	)
	(segment
		(start 273.122136 -219.71)
		(end 267.589 -225.243136)
		(width 0.17145)
		(layer "F.Cu")
		(net "I2C_CLIP_B_SDA")
	)
	(segment
		(start 182.8165 -370.459)
		(end 183.644032 -370.459)
		(width 0.17145)
		(layer "F.Cu")
		(net "I2C_CLIP_B_SDA")
	)
	(segment
		(start 214.14105 -112.172496)
		(end 216.636346 -114.667792)
		(width 0.17145)
		(layer "F.Cu")
		(net "I2C_CLIP_B_SDA")
	)
	(segment
		(start 214.14105 -99.314254)
		(end 214.14105 -112.172496)
		(width 0.17145)
		(layer "F.Cu")
		(net "I2C_CLIP_B_SDA")
	)
	(segment
		(start 267.50645 -237.064042)
		(end 275.298408 -244.856)
		(width 0.17145)
		(layer "F.Cu")
		(net "I2C_CLIP_B_SDA")
	)
	(segment
		(start 267.589 -225.6155)
		(end 268.097 -226.1235)
		(width 0.17145)
		(layer "F.Cu")
		(net "I2C_CLIP_B_SDA")
	)
	(segment
		(start 275.298408 -244.856)
		(end 279.6159 -244.856)
		(width 0.17145)
		(layer "F.Cu")
		(net "I2C_CLIP_B_SDA")
	)
	(segment
		(start 267.50645 -226.71405)
		(end 267.50645 -237.064042)
		(width 0.17145)
		(layer "F.Cu")
		(net "I2C_CLIP_B_SDA")
	)
	(segment
		(start 268.097 -226.1235)
		(end 267.50645 -226.71405)
		(width 0.17145)
		(layer "F.Cu")
		(net "I2C_CLIP_B_SDA")
	)
	(segment
		(start 216.636346 -124.5362)
		(end 220.293946 -128.1938)
		(width 0.17145)
		(layer "F.Cu")
		(net "I2C_CLIP_B_SDA")
	)
	(segment
		(start 281.836622 -218.894406)
		(end 281.021028 -219.71)
		(width 0.17145)
		(layer "F.Cu")
		(net "I2C_CLIP_B_SDA")
	)
	(segment
		(start 281.021028 -219.71)
		(end 273.122136 -219.71)
		(width 0.17145)
		(layer "F.Cu")
		(net "I2C_CLIP_B_SDA")
	)
	(segment
		(start 183.644032 -370.459)
		(end 183.96077 -370.142262)
		(width 0.17145)
		(layer "F.Cu")
		(net "I2C_CLIP_B_SDA")
	)
	(segment
		(start 216.636346 -114.667792)
		(end 216.636346 -124.5362)
		(width 0.17145)
		(layer "F.Cu")
		(net "I2C_CLIP_B_SDA")
	)
	(segment
		(start 213.852506 -99.02571)
		(end 214.14105 -99.314254)
		(width 0.17145)
		(layer "F.Cu")
		(net "I2C_CLIP_B_SDA")
	)
	(segment
		(start 279.6159 -244.856)
		(end 279.8953 -244.5766)
		(width 0.17145)
		(layer "F.Cu")
		(net "I2C_CLIP_B_SDA")
	)
	(via
		(at 297.815 -152.3238)
		(size 0.5588)
		(drill 0.3048)
		(layers "F.Cu" "B.Cu")
		(net "I2C_CLIP_B_SDA")
	)
	(via
		(at 246.120666 -137.7442)
		(size 0.6096)
		(drill 0.3048)
		(layers "F.Cu" "B.Cu")
		(net "I2C_CLIP_B_SDA")
	)
	(via
		(at 183.96077 -370.142262)
		(size 0.5588)
		(drill 0.3048)
		(layers "F.Cu" "B.Cu")
		(net "I2C_CLIP_B_SDA")
	)
	(via
		(at 279.8953 -244.5766)
		(size 0.5588)
		(drill 0.3048)
		(layers "F.Cu" "B.Cu")
		(net "I2C_CLIP_B_SDA")
	)
	(via
		(at 220.293946 -128.1938)
		(size 0.5588)
		(drill 0.3048)
		(layers "F.Cu" "B.Cu")
		(net "I2C_CLIP_B_SDA")
	)
	(segment
		(start 251.37618 -140.70711)
		(end 251.088398 -140.70711)
		(width 0.17145)
		(layer "B.Cu")
		(net "I2C_CLIP_B_SDA")
	)
	(segment
		(start 295.001188 -149.509988)
		(end 260.179058 -149.509988)
		(width 0.17145)
		(layer "B.Cu")
		(net "I2C_CLIP_B_SDA")
	)
	(segment
		(start 260.179058 -149.509988)
		(end 251.37618 -140.70711)
		(width 0.17145)
		(layer "B.Cu")
		(net "I2C_CLIP_B_SDA")
	)
	(segment
		(start 297.815 -152.3238)
		(end 295.001188 -149.509988)
		(width 0.17145)
		(layer "B.Cu")
		(net "I2C_CLIP_B_SDA")
	)
	(segment
		(start 243.887498 -136.094216)
		(end 240.622836 -136.094216)
		(width 0.17145)
		(layer "B.Cu")
		(net "I2C_CLIP_B_SDA")
	)
	(segment
		(start 246.120666 -137.7442)
		(end 245.537482 -137.7442)
		(width 0.17145)
		(layer "B.Cu")
		(net "I2C_CLIP_B_SDA")
	)
	(segment
		(start 223.75368 -130.776726)
		(end 221.170754 -128.1938)
		(width 0.17145)
		(layer "B.Cu")
		(net "I2C_CLIP_B_SDA")
	)
	(segment
		(start 235.382562 -136.391142)
		(end 229.768146 -130.776726)
		(width 0.17145)
		(layer "B.Cu")
		(net "I2C_CLIP_B_SDA")
	)
	(segment
		(start 251.088398 -140.70711)
		(end 248.125488 -137.7442)
		(width 0.17145)
		(layer "B.Cu")
		(net "I2C_CLIP_B_SDA")
	)
	(segment
		(start 240.32591 -136.391142)
		(end 235.382562 -136.391142)
		(width 0.17145)
		(layer "B.Cu")
		(net "I2C_CLIP_B_SDA")
	)
	(segment
		(start 221.170754 -128.1938)
		(end 220.293946 -128.1938)
		(width 0.17145)
		(layer "B.Cu")
		(net "I2C_CLIP_B_SDA")
	)
	(segment
		(start 248.125488 -137.7442)
		(end 246.120666 -137.7442)
		(width 0.17145)
		(layer "B.Cu")
		(net "I2C_CLIP_B_SDA")
	)
	(segment
		(start 240.622836 -136.094216)
		(end 240.32591 -136.391142)
		(width 0.17145)
		(layer "B.Cu")
		(net "I2C_CLIP_B_SDA")
	)
	(segment
		(start 229.768146 -130.776726)
		(end 223.75368 -130.776726)
		(width 0.17145)
		(layer "B.Cu")
		(net "I2C_CLIP_B_SDA")
	)
	(segment
		(start 245.537482 -137.7442)
		(end 243.887498 -136.094216)
		(width 0.17145)
		(layer "B.Cu")
		(net "I2C_CLIP_B_SDA")
	)
	(segment
		(start 282.664154 -219.721938)
		(end 288.856166 -219.721938)
		(width 0.14605)
		(layer "In2.Cu")
		(net "I2C_CLIP_B_SDA")
	)
	(segment
		(start 297.577764 -184.787032)
		(end 297.577764 -154.540712)
		(width 0.14605)
		(layer "In2.Cu")
		(net "I2C_CLIP_B_SDA")
	)
	(segment
		(start 281.836622 -218.894406)
		(end 282.664154 -219.721938)
		(width 0.14605)
		(layer "In2.Cu")
		(net "I2C_CLIP_B_SDA")
	)
	(segment
		(start 291.53612 -217.041984)
		(end 291.53612 -190.828676)
		(width 0.14605)
		(layer "In2.Cu")
		(net "I2C_CLIP_B_SDA")
	)
	(segment
		(start 288.856166 -219.721938)
		(end 291.53612 -217.041984)
		(width 0.14605)
		(layer "In2.Cu")
		(net "I2C_CLIP_B_SDA")
	)
	(segment
		(start 291.53612 -190.828676)
		(end 297.577764 -184.787032)
		(width 0.14605)
		(layer "In2.Cu")
		(net "I2C_CLIP_B_SDA")
	)
	(segment
		(start 297.577764 -154.540712)
		(end 298.266104 -153.852372)
		(width 0.14605)
		(layer "In2.Cu")
		(net "I2C_CLIP_B_SDA")
	)
	(segment
		(start 298.266104 -153.852372)
		(end 298.266104 -152.774904)
		(width 0.14605)
		(layer "In2.Cu")
		(net "I2C_CLIP_B_SDA")
	)
	(segment
		(start 298.266104 -152.774904)
		(end 297.815 -152.3238)
		(width 0.14605)
		(layer "In2.Cu")
		(net "I2C_CLIP_B_SDA")
	)
	(segment
		(start 253.50089 -375.665238)
		(end 256.00025 -378.164598)
		(width 0.14605)
		(layer "In5.Cu")
		(net "I2C_CLIP_B_SDA")
	)
	(segment
		(start 276.152102 -323.33057)
		(end 266.656312 -313.83478)
		(width 0.14605)
		(layer "In5.Cu")
		(net "I2C_CLIP_B_SDA")
	)
	(segment
		(start 269.261336 -358.043734)
		(end 276.152102 -351.152968)
		(width 0.14605)
		(layer "In5.Cu")
		(net "I2C_CLIP_B_SDA")
	)
	(segment
		(start 238.299244 -374.88749)
		(end 239.076992 -375.665238)
		(width 0.14605)
		(layer "In5.Cu")
		(net "I2C_CLIP_B_SDA")
	)
	(segment
		(start 269.261336 -372.217442)
		(end 269.261336 -358.043734)
		(width 0.14605)
		(layer "In5.Cu")
		(net "I2C_CLIP_B_SDA")
	)
	(segment
		(start 279.8953 -247.587516)
		(end 279.8953 -244.5766)
		(width 0.14605)
		(layer "In5.Cu")
		(net "I2C_CLIP_B_SDA")
	)
	(segment
		(start 183.96077 -370.142262)
		(end 187.133738 -370.142262)
		(width 0.14605)
		(layer "In5.Cu")
		(net "I2C_CLIP_B_SDA")
	)
	(segment
		(start 202.625198 -369.763802)
		(end 207.748886 -374.88749)
		(width 0.14605)
		(layer "In5.Cu")
		(net "I2C_CLIP_B_SDA")
	)
	(segment
		(start 256.00025 -378.164598)
		(end 263.31418 -378.164598)
		(width 0.14605)
		(layer "In5.Cu")
		(net "I2C_CLIP_B_SDA")
	)
	(segment
		(start 187.512198 -369.763802)
		(end 202.625198 -369.763802)
		(width 0.14605)
		(layer "In5.Cu")
		(net "I2C_CLIP_B_SDA")
	)
	(segment
		(start 263.31418 -378.164598)
		(end 269.261336 -372.217442)
		(width 0.14605)
		(layer "In5.Cu")
		(net "I2C_CLIP_B_SDA")
	)
	(segment
		(start 266.656312 -260.826504)
		(end 279.8953 -247.587516)
		(width 0.14605)
		(layer "In5.Cu")
		(net "I2C_CLIP_B_SDA")
	)
	(segment
		(start 187.133738 -370.142262)
		(end 187.512198 -369.763802)
		(width 0.14605)
		(layer "In5.Cu")
		(net "I2C_CLIP_B_SDA")
	)
	(segment
		(start 207.748886 -374.88749)
		(end 238.299244 -374.88749)
		(width 0.14605)
		(layer "In5.Cu")
		(net "I2C_CLIP_B_SDA")
	)
	(segment
		(start 276.152102 -351.152968)
		(end 276.152102 -323.33057)
		(width 0.14605)
		(layer "In5.Cu")
		(net "I2C_CLIP_B_SDA")
	)
	(segment
		(start 239.076992 -375.665238)
		(end 253.50089 -375.665238)
		(width 0.14605)
		(layer "In5.Cu")
		(net "I2C_CLIP_B_SDA")
	)
	(segment
		(start 266.656312 -313.83478)
		(end 266.656312 -260.826504)
		(width 0.14605)
		(layer "In5.Cu")
		(net "I2C_CLIP_B_SDA")
	)
	(segment
		(start 266.827 -237.345728)
		(end 266.827 -226.7585)
		(width 0.17145)
		(layer "F.Cu")
		(net "I2C_CLIP_B_SCL")
	)
	(segment
		(start 282.248864 -217.9066)
		(end 283.23667 -218.894406)
		(width 0.17145)
		(layer "F.Cu")
		(net "I2C_CLIP_B_SCL")
	)
	(segment
		(start 266.827 -225.4885)
		(end 266.827 -225.044)
		(width 0.17145)
		(layer "F.Cu")
		(net "I2C_CLIP_B_SCL")
	)
	(segment
		(start 217.315796 -124.254514)
		(end 217.315796 -114.386106)
		(width 0.17145)
		(layer "F.Cu")
		(net "I2C_CLIP_B_SCL")
	)
	(segment
		(start 280.5684 -245.8212)
		(end 280.4668 -245.7196)
		(width 0.17145)
		(layer "F.Cu")
		(net "I2C_CLIP_B_SCL")
	)
	(segment
		(start 266.192 -226.1235)
		(end 266.827 -225.4885)
		(width 0.17145)
		(layer "F.Cu")
		(net "I2C_CLIP_B_SCL")
	)
	(segment
		(start 220.97365 -127.912368)
		(end 217.315796 -124.254514)
		(width 0.17145)
		(layer "F.Cu")
		(net "I2C_CLIP_B_SCL")
	)
	(segment
		(start 273.9644 -217.9066)
		(end 282.248864 -217.9066)
		(width 0.17145)
		(layer "F.Cu")
		(net "I2C_CLIP_B_SCL")
	)
	(segment
		(start 214.821516 -99.3267)
		(end 215.122506 -99.02571)
		(width 0.17145)
		(layer "F.Cu")
		(net "I2C_CLIP_B_SCL")
	)
	(segment
		(start 275.200872 -245.7196)
		(end 266.827 -237.345728)
		(width 0.17145)
		(layer "F.Cu")
		(net "I2C_CLIP_B_SCL")
	)
	(segment
		(start 220.293946 -129.1844)
		(end 220.97365 -128.504696)
		(width 0.17145)
		(layer "F.Cu")
		(net "I2C_CLIP_B_SCL")
	)
	(segment
		(start 266.827 -226.7585)
		(end 266.192 -226.1235)
		(width 0.17145)
		(layer "F.Cu")
		(net "I2C_CLIP_B_SCL")
	)
	(segment
		(start 183.409336 -371.602)
		(end 183.912764 -371.098572)
		(width 0.17145)
		(layer "F.Cu")
		(net "I2C_CLIP_B_SCL")
	)
	(segment
		(start 182.8165 -371.602)
		(end 183.409336 -371.602)
		(width 0.17145)
		(layer "F.Cu")
		(net "I2C_CLIP_B_SCL")
	)
	(segment
		(start 217.315796 -114.386106)
		(end 214.821516 -111.891826)
		(width 0.17145)
		(layer "F.Cu")
		(net "I2C_CLIP_B_SCL")
	)
	(segment
		(start 280.4668 -245.7196)
		(end 275.200872 -245.7196)
		(width 0.17145)
		(layer "F.Cu")
		(net "I2C_CLIP_B_SCL")
	)
	(segment
		(start 220.97365 -128.504696)
		(end 220.97365 -127.912368)
		(width 0.17145)
		(layer "F.Cu")
		(net "I2C_CLIP_B_SCL")
	)
	(segment
		(start 266.827 -225.044)
		(end 273.9644 -217.9066)
		(width 0.17145)
		(layer "F.Cu")
		(net "I2C_CLIP_B_SCL")
	)
	(segment
		(start 214.821516 -111.891826)
		(end 214.821516 -99.3267)
		(width 0.17145)
		(layer "F.Cu")
		(net "I2C_CLIP_B_SCL")
	)
	(via
		(at 297.6118 -153.3398)
		(size 0.5588)
		(drill 0.3048)
		(layers "F.Cu" "B.Cu")
		(net "I2C_CLIP_B_SCL")
	)
	(via
		(at 248.51741 -139.097258)
		(size 0.6096)
		(drill 0.3048)
		(layers "F.Cu" "B.Cu")
		(net "I2C_CLIP_B_SCL")
	)
	(via
		(at 220.293946 -129.1844)
		(size 0.5588)
		(drill 0.3048)
		(layers "F.Cu" "B.Cu")
		(net "I2C_CLIP_B_SCL")
	)
	(via
		(at 280.5684 -245.8212)
		(size 0.5588)
		(drill 0.3048)
		(layers "F.Cu" "B.Cu")
		(net "I2C_CLIP_B_SCL")
	)
	(via
		(at 183.912764 -371.098572)
		(size 0.5588)
		(drill 0.3048)
		(layers "F.Cu" "B.Cu")
		(net "I2C_CLIP_B_SCL")
	)
	(segment
		(start 240.904522 -136.773666)
		(end 240.976658 -136.773666)
		(width 0.17145)
		(layer "B.Cu")
		(net "I2C_CLIP_B_SCL")
	)
	(segment
		(start 229.48646 -131.456176)
		(end 235.100876 -137.070592)
		(width 0.17145)
		(layer "B.Cu")
		(net "I2C_CLIP_B_SCL")
	)
	(segment
		(start 240.976658 -136.773666)
		(end 240.976912 -136.77392)
		(width 0.17145)
		(layer "B.Cu")
		(net "I2C_CLIP_B_SCL")
	)
	(segment
		(start 240.976912 -136.77392)
		(end 243.606066 -136.77392)
		(width 0.17145)
		(layer "B.Cu")
		(net "I2C_CLIP_B_SCL")
	)
	(segment
		(start 248.51741 -139.097258)
		(end 250.806966 -141.386814)
		(width 0.17145)
		(layer "B.Cu")
		(net "I2C_CLIP_B_SCL")
	)
	(segment
		(start 235.100876 -137.070592)
		(end 240.607596 -137.070592)
		(width 0.17145)
		(layer "B.Cu")
		(net "I2C_CLIP_B_SCL")
	)
	(segment
		(start 251.094748 -141.386814)
		(end 259.897372 -150.189438)
		(width 0.17145)
		(layer "B.Cu")
		(net "I2C_CLIP_B_SCL")
	)
	(segment
		(start 247.844056 -138.423904)
		(end 248.51741 -139.097258)
		(width 0.17145)
		(layer "B.Cu")
		(net "I2C_CLIP_B_SCL")
	)
	(segment
		(start 221.200218 -129.1844)
		(end 223.471994 -131.456176)
		(width 0.17145)
		(layer "B.Cu")
		(net "I2C_CLIP_B_SCL")
	)
	(segment
		(start 223.471994 -131.456176)
		(end 229.48646 -131.456176)
		(width 0.17145)
		(layer "B.Cu")
		(net "I2C_CLIP_B_SCL")
	)
	(segment
		(start 243.606066 -136.77392)
		(end 245.25605 -138.423904)
		(width 0.17145)
		(layer "B.Cu")
		(net "I2C_CLIP_B_SCL")
	)
	(segment
		(start 245.25605 -138.423904)
		(end 247.844056 -138.423904)
		(width 0.17145)
		(layer "B.Cu")
		(net "I2C_CLIP_B_SCL")
	)
	(segment
		(start 240.607596 -137.070592)
		(end 240.904522 -136.773666)
		(width 0.17145)
		(layer "B.Cu")
		(net "I2C_CLIP_B_SCL")
	)
	(segment
		(start 294.461438 -150.189438)
		(end 297.6118 -153.3398)
		(width 0.17145)
		(layer "B.Cu")
		(net "I2C_CLIP_B_SCL")
	)
	(segment
		(start 250.806966 -141.386814)
		(end 251.094748 -141.386814)
		(width 0.17145)
		(layer "B.Cu")
		(net "I2C_CLIP_B_SCL")
	)
	(segment
		(start 220.293946 -129.1844)
		(end 221.200218 -129.1844)
		(width 0.17145)
		(layer "B.Cu")
		(net "I2C_CLIP_B_SCL")
	)
	(segment
		(start 259.897372 -150.189438)
		(end 294.461438 -150.189438)
		(width 0.17145)
		(layer "B.Cu")
		(net "I2C_CLIP_B_SCL")
	)
	(segment
		(start 289.09264 -218.0336)
		(end 290.88207 -216.24417)
		(width 0.14605)
		(layer "In2.Cu")
		(net "I2C_CLIP_B_SCL")
	)
	(segment
		(start 296.923714 -154.027886)
		(end 297.6118 -153.3398)
		(width 0.14605)
		(layer "In2.Cu")
		(net "I2C_CLIP_B_SCL")
	)
	(segment
		(start 283.23667 -218.894406)
		(end 284.097476 -218.0336)
		(width 0.14605)
		(layer "In2.Cu")
		(net "I2C_CLIP_B_SCL")
	)
	(segment
		(start 296.923714 -184.516014)
		(end 296.923714 -154.027886)
		(width 0.14605)
		(layer "In2.Cu")
		(net "I2C_CLIP_B_SCL")
	)
	(segment
		(start 290.88207 -190.557658)
		(end 296.923714 -184.516014)
		(width 0.14605)
		(layer "In2.Cu")
		(net "I2C_CLIP_B_SCL")
	)
	(segment
		(start 290.88207 -216.24417)
		(end 290.88207 -190.557658)
		(width 0.14605)
		(layer "In2.Cu")
		(net "I2C_CLIP_B_SCL")
	)
	(segment
		(start 284.097476 -218.0336)
		(end 289.09264 -218.0336)
		(width 0.14605)
		(layer "In2.Cu")
		(net "I2C_CLIP_B_SCL")
	)
	(segment
		(start 253.229872 -376.319288)
		(end 255.729232 -378.818648)
		(width 0.14605)
		(layer "In5.Cu")
		(net "I2C_CLIP_B_SCL")
	)
	(segment
		(start 269.915386 -358.429814)
		(end 276.806152 -351.539048)
		(width 0.14605)
		(layer "In5.Cu")
		(net "I2C_CLIP_B_SCL")
	)
	(segment
		(start 267.36421 -313.61761)
		(end 267.36421 -261.043674)
		(width 0.14605)
		(layer "In5.Cu")
		(net "I2C_CLIP_B_SCL")
	)
	(segment
		(start 276.806152 -351.539048)
		(end 276.806152 -323.059552)
		(width 0.14605)
		(layer "In5.Cu")
		(net "I2C_CLIP_B_SCL")
	)
	(segment
		(start 183.912764 -371.098572)
		(end 187.193428 -371.098572)
		(width 0.14605)
		(layer "In5.Cu")
		(net "I2C_CLIP_B_SCL")
	)
	(segment
		(start 269.915386 -372.48846)
		(end 269.915386 -358.429814)
		(width 0.14605)
		(layer "In5.Cu")
		(net "I2C_CLIP_B_SCL")
	)
	(segment
		(start 187.193428 -371.098572)
		(end 187.874148 -370.417852)
		(width 0.14605)
		(layer "In5.Cu")
		(net "I2C_CLIP_B_SCL")
	)
	(segment
		(start 255.729232 -378.818648)
		(end 263.585198 -378.818648)
		(width 0.14605)
		(layer "In5.Cu")
		(net "I2C_CLIP_B_SCL")
	)
	(segment
		(start 187.874148 -370.417852)
		(end 202.35418 -370.417852)
		(width 0.14605)
		(layer "In5.Cu")
		(net "I2C_CLIP_B_SCL")
	)
	(segment
		(start 202.35418 -370.417852)
		(end 208.255616 -376.319288)
		(width 0.14605)
		(layer "In5.Cu")
		(net "I2C_CLIP_B_SCL")
	)
	(segment
		(start 280.5684 -247.839484)
		(end 280.5684 -245.8212)
		(width 0.14605)
		(layer "In5.Cu")
		(net "I2C_CLIP_B_SCL")
	)
	(segment
		(start 208.255616 -376.319288)
		(end 253.229872 -376.319288)
		(width 0.14605)
		(layer "In5.Cu")
		(net "I2C_CLIP_B_SCL")
	)
	(segment
		(start 267.36421 -261.043674)
		(end 280.5684 -247.839484)
		(width 0.14605)
		(layer "In5.Cu")
		(net "I2C_CLIP_B_SCL")
	)
	(segment
		(start 263.585198 -378.818648)
		(end 269.915386 -372.48846)
		(width 0.14605)
		(layer "In5.Cu")
		(net "I2C_CLIP_B_SCL")
	)
	(segment
		(start 276.806152 -323.059552)
		(end 267.36421 -313.61761)
		(width 0.14605)
		(layer "In5.Cu")
		(net "I2C_CLIP_B_SCL")
	)
	(segment
		(start 214.067644 -94.183708)
		(end 214.067644 -95.19793)
		(width 0.17145)
		(layer "F.Cu")
		(net "I2C_CLIP_A_SDA")
	)
	(segment
		(start 213.852506 -98.13671)
		(end 214.067644 -97.921572)
		(width 0.17145)
		(layer "F.Cu")
		(net "I2C_CLIP_A_SDA")
	)
	(segment
		(start 214.236046 -79.514954)
		(end 214.196422 -79.554578)
		(width 0.17145)
		(layer "F.Cu")
		(net "I2C_CLIP_A_SDA")
	)
	(segment
		(start 214.196422 -94.05493)
		(end 214.067644 -94.183708)
		(width 0.17145)
		(layer "F.Cu")
		(net "I2C_CLIP_A_SDA")
	)
	(segment
		(start 213.60003 -75.3999)
		(end 214.00262 -75.3999)
		(width 0.17145)
		(layer "F.Cu")
		(net "I2C_CLIP_A_SDA")
	)
	(segment
		(start 214.196422 -79.554578)
		(end 214.196422 -94.05493)
		(width 0.17145)
		(layer "F.Cu")
		(net "I2C_CLIP_A_SDA")
	)
	(segment
		(start 214.00262 -75.3999)
		(end 214.236046 -75.633326)
		(width 0.17145)
		(layer "F.Cu")
		(net "I2C_CLIP_A_SDA")
	)
	(segment
		(start 214.067644 -97.921572)
		(end 214.067644 -95.19793)
		(width 0.17145)
		(layer "F.Cu")
		(net "I2C_CLIP_A_SDA")
	)
	(segment
		(start 214.236046 -75.633326)
		(end 214.236046 -79.514954)
		(width 0.17145)
		(layer "F.Cu")
		(net "I2C_CLIP_A_SDA")
	)
	(via
		(at 214.067644 -95.19793)
		(size 0.6604)
		(drill 0.3302)
		(layers "F.Cu" "B.Cu")
		(net "I2C_CLIP_A_SDA")
	)
	(segment
		(start 214.763096 -75.162918)
		(end 214.763096 -79.459328)
		(width 0.17145)
		(layer "F.Cu")
		(net "I2C_CLIP_A_SCL")
	)
	(segment
		(start 214.875872 -97.890076)
		(end 214.875872 -96.525842)
		(width 0.17145)
		(layer "F.Cu")
		(net "I2C_CLIP_A_SCL")
	)
	(segment
		(start 215.122506 -98.13671)
		(end 214.875872 -97.890076)
		(width 0.17145)
		(layer "F.Cu")
		(net "I2C_CLIP_A_SCL")
	)
	(segment
		(start 214.763096 -79.459328)
		(end 214.875872 -79.572104)
		(width 0.17145)
		(layer "F.Cu")
		(net "I2C_CLIP_A_SCL")
	)
	(segment
		(start 214.875872 -79.572104)
		(end 214.875872 -96.525842)
		(width 0.17145)
		(layer "F.Cu")
		(net "I2C_CLIP_A_SCL")
	)
	(segment
		(start 213.60003 -73.999852)
		(end 214.763096 -75.162918)
		(width 0.17145)
		(layer "F.Cu")
		(net "I2C_CLIP_A_SCL")
	)
	(via
		(at 214.875872 -96.525842)
		(size 0.6604)
		(drill 0.3302)
		(layers "F.Cu" "B.Cu")
		(net "I2C_CLIP_A_SCL")
	)
	(via
		(at 430.435004 -359.156)
		(size 0.6604)
		(drill 0.3302)
		(layers "F.Cu" "B.Cu")
		(net "GATE_FAN3")
	)
	(via
		(at 331.597 -359.029)
		(size 0.6604)
		(drill 0.3302)
		(layers "F.Cu" "B.Cu")
		(net "GATE_FAN2")
	)
	(via
		(at 129.081784 -364.306104)
		(size 0.6096)
		(drill 0.3048)
		(layers "F.Cu" "B.Cu")
		(net "GATE_FAN1")
	)
	(via
		(at 42.843196 -359.2068)
		(size 0.6604)
		(drill 0.3302)
		(layers "F.Cu" "B.Cu")
		(net "GATE_FAN0")
	)
	(segment
		(start 38.59403 -360.84256)
		(end 38.59403 -359.0163)
		(width 0.254)
		(layer "F.Cu")
		(net "FAN_EN")
	)
	(segment
		(start 42.449496 -360.5149)
		(end 41.217596 -360.5149)
		(width 0.254)
		(layer "F.Cu")
		(net "FAN_EN")
	)
	(segment
		(start 432.435254 -363.0295)
		(end 432.435254 -364.236)
		(width 0.254)
		(layer "F.Cu")
		(net "FAN_EN")
	)
	(segment
		(start 44.513246 -362.52785)
		(end 44.189396 -362.204)
		(width 0.254)
		(layer "F.Cu")
		(net "FAN_EN")
	)
	(segment
		(start 42.766996 -361.8738)
		(end 42.766996 -360.8324)
		(width 0.254)
		(layer "F.Cu")
		(net "FAN_EN")
	)
	(segment
		(start 44.513246 -363.0295)
		(end 44.513246 -362.52785)
		(width 0.254)
		(layer "F.Cu")
		(net "FAN_EN")
	)
	(segment
		(start 44.513246 -364.25505)
		(end 44.513246 -363.0295)
		(width 0.254)
		(layer "F.Cu")
		(net "FAN_EN")
	)
	(segment
		(start 39.19093 -358.4194)
		(end 40.658796 -358.4194)
		(width 0.254)
		(layer "F.Cu")
		(net "FAN_EN")
	)
	(segment
		(start 42.766996 -360.8324)
		(end 42.449496 -360.5149)
		(width 0.254)
		(layer "F.Cu")
		(net "FAN_EN")
	)
	(segment
		(start 38.59403 -359.0163)
		(end 39.19093 -358.4194)
		(width 0.254)
		(layer "F.Cu")
		(net "FAN_EN")
	)
	(segment
		(start 44.189396 -362.204)
		(end 43.097196 -362.204)
		(width 0.254)
		(layer "F.Cu")
		(net "FAN_EN")
	)
	(segment
		(start 40.658796 -358.4194)
		(end 41.217596 -358.9782)
		(width 0.254)
		(layer "F.Cu")
		(net "FAN_EN")
	)
	(segment
		(start 43.097196 -362.204)
		(end 42.766996 -361.8738)
		(width 0.254)
		(layer "F.Cu")
		(net "FAN_EN")
	)
	(segment
		(start 41.217596 -358.9782)
		(end 41.217596 -360.5149)
		(width 0.254)
		(layer "F.Cu")
		(net "FAN_EN")
	)
	(segment
		(start 333.85125 -363.0295)
		(end 333.85125 -361.79125)
		(width 0.254)
		(layer "F.Cu")
		(net "FAN_EN")
	)
	(via
		(at 71.0438 -362.712)
		(size 0.6096)
		(drill 0.3048)
		(layers "F.Cu" "B.Cu")
		(net "FAN_EN")
	)
	(via
		(at 333.85125 -361.79125)
		(size 0.5588)
		(drill 0.3048)
		(layers "F.Cu" "B.Cu")
		(net "FAN_EN")
	)
	(via
		(at 432.435254 -364.236)
		(size 0.5588)
		(drill 0.3048)
		(layers "F.Cu" "B.Cu")
		(net "FAN_EN")
	)
	(via
		(at 44.513246 -364.25505)
		(size 0.5588)
		(drill 0.3048)
		(layers "F.Cu" "B.Cu")
		(net "FAN_EN")
	)
	(via
		(at 132.95757 -359.807256)
		(size 0.5588)
		(drill 0.3048)
		(layers "F.Cu" "B.Cu")
		(net "FAN_EN")
	)
	(segment
		(start 62.0776 -359.537)
		(end 65.2526 -362.712)
		(width 0.254)
		(layer "B.Cu")
		(net "FAN_EN")
	)
	(segment
		(start 44.513246 -364.25505)
		(end 50.73015 -364.25505)
		(width 0.254)
		(layer "B.Cu")
		(net "FAN_EN")
	)
	(segment
		(start 416.061144 -358.32034)
		(end 337.32216 -358.32034)
		(width 0.254)
		(layer "B.Cu")
		(net "FAN_EN")
	)
	(segment
		(start 55.4482 -359.537)
		(end 62.0776 -359.537)
		(width 0.254)
		(layer "B.Cu")
		(net "FAN_EN")
	)
	(segment
		(start 91.313 -367.665)
		(end 86.36 -362.712)
		(width 0.254)
		(layer "B.Cu")
		(net "FAN_EN")
	)
	(segment
		(start 118.618 -367.665)
		(end 91.313 -367.665)
		(width 0.254)
		(layer "B.Cu")
		(net "FAN_EN")
	)
	(segment
		(start 126.475744 -359.807256)
		(end 118.618 -367.665)
		(width 0.254)
		(layer "B.Cu")
		(net "FAN_EN")
	)
	(segment
		(start 431.876454 -364.7948)
		(end 422.535604 -364.7948)
		(width 0.254)
		(layer "B.Cu")
		(net "FAN_EN")
	)
	(segment
		(start 50.73015 -364.25505)
		(end 55.4482 -359.537)
		(width 0.254)
		(layer "B.Cu")
		(net "FAN_EN")
	)
	(segment
		(start 132.95757 -359.807256)
		(end 126.475744 -359.807256)
		(width 0.254)
		(layer "B.Cu")
		(net "FAN_EN")
	)
	(segment
		(start 422.535604 -364.7948)
		(end 416.061144 -358.32034)
		(width 0.254)
		(layer "B.Cu")
		(net "FAN_EN")
	)
	(segment
		(start 65.2526 -362.712)
		(end 71.0438 -362.712)
		(width 0.254)
		(layer "B.Cu")
		(net "FAN_EN")
	)
	(segment
		(start 432.435254 -364.236)
		(end 431.876454 -364.7948)
		(width 0.254)
		(layer "B.Cu")
		(net "FAN_EN")
	)
	(segment
		(start 131.235196 -361.08767)
		(end 131.677156 -361.08767)
		(width 0.254)
		(layer "B.Cu")
		(net "FAN_EN")
	)
	(segment
		(start 337.32216 -358.32034)
		(end 333.85125 -361.79125)
		(width 0.254)
		(layer "B.Cu")
		(net "FAN_EN")
	)
	(segment
		(start 131.677156 -361.08767)
		(end 132.95757 -359.807256)
		(width 0.254)
		(layer "B.Cu")
		(net "FAN_EN")
	)
	(segment
		(start 86.36 -362.712)
		(end 71.0438 -362.712)
		(width 0.254)
		(layer "B.Cu")
		(net "FAN_EN")
	)
	(segment
		(start 154.905456 -359.807256)
		(end 132.95757 -359.807256)
		(width 0.254)
		(layer "In2.Cu")
		(net "FAN_EN")
	)
	(segment
		(start 326.79005 -361.79125)
		(end 325.628 -360.6292)
		(width 0.254)
		(layer "In2.Cu")
		(net "FAN_EN")
	)
	(segment
		(start 283.2354 -360.6292)
		(end 278.9936 -356.3874)
		(width 0.254)
		(layer "In2.Cu")
		(net "FAN_EN")
	)
	(segment
		(start 242.698016 -355.902514)
		(end 239.771682 -355.902514)
		(width 0.254)
		(layer "In2.Cu")
		(net "FAN_EN")
	)
	(segment
		(start 164.465 -379.5522)
		(end 160.4772 -375.5644)
		(width 0.254)
		(layer "In2.Cu")
		(net "FAN_EN")
	)
	(segment
		(start 183.642 -378.3838)
		(end 182.4736 -379.5522)
		(width 0.254)
		(layer "In2.Cu")
		(net "FAN_EN")
	)
	(segment
		(start 239.771682 -355.902514)
		(end 239.455198 -355.58603)
		(width 0.254)
		(layer "In2.Cu")
		(net "FAN_EN")
	)
	(segment
		(start 233.655108 -359.537)
		(end 220.447616 -359.537)
		(width 0.254)
		(layer "In2.Cu")
		(net "FAN_EN")
	)
	(segment
		(start 278.9936 -356.3874)
		(end 243.182902 -356.3874)
		(width 0.254)
		(layer "In2.Cu")
		(net "FAN_EN")
	)
	(segment
		(start 201.5998 -372.4148)
		(end 195.6308 -378.3838)
		(width 0.254)
		(layer "In2.Cu")
		(net "FAN_EN")
	)
	(segment
		(start 325.628 -360.6292)
		(end 283.2354 -360.6292)
		(width 0.254)
		(layer "In2.Cu")
		(net "FAN_EN")
	)
	(segment
		(start 243.182902 -356.3874)
		(end 242.698016 -355.902514)
		(width 0.254)
		(layer "In2.Cu")
		(net "FAN_EN")
	)
	(segment
		(start 160.4772 -365.379)
		(end 154.905456 -359.807256)
		(width 0.254)
		(layer "In2.Cu")
		(net "FAN_EN")
	)
	(segment
		(start 239.455198 -355.58603)
		(end 237.606078 -355.58603)
		(width 0.254)
		(layer "In2.Cu")
		(net "FAN_EN")
	)
	(segment
		(start 237.606078 -355.58603)
		(end 233.655108 -359.537)
		(width 0.254)
		(layer "In2.Cu")
		(net "FAN_EN")
	)
	(segment
		(start 207.569816 -372.4148)
		(end 201.5998 -372.4148)
		(width 0.254)
		(layer "In2.Cu")
		(net "FAN_EN")
	)
	(segment
		(start 182.4736 -379.5522)
		(end 164.465 -379.5522)
		(width 0.254)
		(layer "In2.Cu")
		(net "FAN_EN")
	)
	(segment
		(start 220.447616 -359.537)
		(end 207.569816 -372.4148)
		(width 0.254)
		(layer "In2.Cu")
		(net "FAN_EN")
	)
	(segment
		(start 160.4772 -375.5644)
		(end 160.4772 -365.379)
		(width 0.254)
		(layer "In2.Cu")
		(net "FAN_EN")
	)
	(segment
		(start 195.6308 -378.3838)
		(end 183.642 -378.3838)
		(width 0.254)
		(layer "In2.Cu")
		(net "FAN_EN")
	)
	(segment
		(start 333.85125 -361.79125)
		(end 326.79005 -361.79125)
		(width 0.254)
		(layer "In2.Cu")
		(net "FAN_EN")
	)
	(segment
		(start 257.99796 -216.481152)
		(end 259.095494 -215.383618)
		(width 0.17145)
		(layer "F.Cu")
		(net "VOL_SEN_INT_N")
	)
	(segment
		(start 259.1435 -215.335612)
		(end 259.1435 -213.995)
		(width 0.17145)
		(layer "F.Cu")
		(net "VOL_SEN_INT_N")
	)
	(segment
		(start 257.99796 -217.45702)
		(end 257.99796 -216.481152)
		(width 0.17145)
		(layer "F.Cu")
		(net "VOL_SEN_INT_N")
	)
	(segment
		(start 259.095494 -215.383618)
		(end 259.1435 -215.335612)
		(width 0.17145)
		(layer "F.Cu")
		(net "VOL_SEN_INT_N")
	)
	(segment
		(start 261.597648 -215.700356)
		(end 261.940294 -215.35771)
		(width 0.17145)
		(layer "F.Cu")
		(net "VOL_SEN_ADDR1")
	)
	(segment
		(start 262.670036 -216.33307)
		(end 262.670036 -215.440768)
		(width 0.17145)
		(layer "F.Cu")
		(net "VOL_SEN_ADDR1")
	)
	(segment
		(start 262.670036 -215.440768)
		(end 262.586978 -215.35771)
		(width 0.17145)
		(layer "F.Cu")
		(net "VOL_SEN_ADDR1")
	)
	(segment
		(start 261.940294 -215.35771)
		(end 262.586978 -215.35771)
		(width 0.17145)
		(layer "F.Cu")
		(net "VOL_SEN_ADDR1")
	)
	(via
		(at 262.586978 -215.35771)
		(size 0.6604)
		(drill 0.3302)
		(layers "F.Cu" "B.Cu")
		(net "VOL_SEN_ADDR1")
	)
	(segment
		(start 259.29844 -218.67876)
		(end 259.29844 -217.45702)
		(width 0.17145)
		(layer "F.Cu")
		(net "VOL_SEN_ADDR0")
	)
	(segment
		(start 259.29844 -217.45702)
		(end 259.820156 -217.45702)
		(width 0.17145)
		(layer "F.Cu")
		(net "VOL_SEN_ADDR0")
	)
	(segment
		(start 260.731 -218.948)
		(end 261.239 -218.948)
		(width 0.17145)
		(layer "F.Cu")
		(net "VOL_SEN_ADDR0")
	)
	(segment
		(start 258.6482 -217.45702)
		(end 258.6482 -218.67495)
		(width 0.17145)
		(layer "F.Cu")
		(net "VOL_SEN_ADDR0")
	)
	(segment
		(start 259.1308 -218.8464)
		(end 259.29844 -218.67876)
		(width 0.17145)
		(layer "F.Cu")
		(net "VOL_SEN_ADDR0")
	)
	(segment
		(start 258.81965 -218.8464)
		(end 259.1308 -218.8464)
		(width 0.17145)
		(layer "F.Cu")
		(net "VOL_SEN_ADDR0")
	)
	(segment
		(start 259.820156 -217.45702)
		(end 260.2357 -217.872564)
		(width 0.17145)
		(layer "F.Cu")
		(net "VOL_SEN_ADDR0")
	)
	(segment
		(start 262.669274 -217.419936)
		(end 262.39851 -217.6907)
		(width 0.17145)
		(layer "F.Cu")
		(net "VOL_SEN_ADDR0")
	)
	(segment
		(start 258.6482 -218.67495)
		(end 258.81965 -218.8464)
		(width 0.17145)
		(layer "F.Cu")
		(net "VOL_SEN_ADDR0")
	)
	(segment
		(start 262.39851 -217.6907)
		(end 261.5184 -217.6907)
		(width 0.17145)
		(layer "F.Cu")
		(net "VOL_SEN_ADDR0")
	)
	(segment
		(start 261.5184 -217.6907)
		(end 261.5184 -218.6686)
		(width 0.17145)
		(layer "F.Cu")
		(net "VOL_SEN_ADDR0")
	)
	(segment
		(start 261.5184 -218.6686)
		(end 261.239 -218.948)
		(width 0.17145)
		(layer "F.Cu")
		(net "VOL_SEN_ADDR0")
	)
	(segment
		(start 260.2357 -218.4527)
		(end 260.731 -218.948)
		(width 0.17145)
		(layer "F.Cu")
		(net "VOL_SEN_ADDR0")
	)
	(segment
		(start 260.2357 -217.872564)
		(end 260.2357 -218.4527)
		(width 0.17145)
		(layer "F.Cu")
		(net "VOL_SEN_ADDR0")
	)
	(via
		(at 261.239 -218.948)
		(size 0.6604)
		(drill 0.3302)
		(layers "F.Cu" "B.Cu")
		(net "VOL_SEN_ADDR0")
	)
	(segment
		(start 312.5724 -339.595206)
		(end 312.9534 -339.976206)
		(width 0.17145)
		(layer "F.Cu")
		(net "THERMHOT#_D")
	)
	(segment
		(start 312.9534 -339.976206)
		(end 312.9534 -340.368382)
		(width 0.17145)
		(layer "F.Cu")
		(net "THERMHOT#_D")
	)
	(segment
		(start 312.9534 -340.368382)
		(end 311.6834 -340.368382)
		(width 0.17145)
		(layer "F.Cu")
		(net "THERMHOT#_D")
	)
	(segment
		(start 312.5724 -339.128354)
		(end 312.5724 -339.595206)
		(width 0.17145)
		(layer "F.Cu")
		(net "THERMHOT#_D")
	)
	(segment
		(start 312.5724 -337.015582)
		(end 312.5724 -339.128354)
		(width 0.17145)
		(layer "F.Cu")
		(net "THERMHOT#_D")
	)
	(via
		(at 312.5724 -339.128354)
		(size 0.6604)
		(drill 0.3302)
		(layers "F.Cu" "B.Cu")
		(net "THERMHOT#_D")
	)
	(segment
		(start 304.138076 -339.595206)
		(end 304.138076 -339.128354)
		(width 0.17145)
		(layer "F.Cu")
		(net "THERMHOT#_C")
	)
	(segment
		(start 304.519076 -340.368382)
		(end 304.519076 -339.976206)
		(width 0.17145)
		(layer "F.Cu")
		(net "THERMHOT#_C")
	)
	(segment
		(start 303.249076 -340.368382)
		(end 304.519076 -340.368382)
		(width 0.17145)
		(layer "F.Cu")
		(net "THERMHOT#_C")
	)
	(segment
		(start 304.519076 -339.976206)
		(end 304.138076 -339.595206)
		(width 0.17145)
		(layer "F.Cu")
		(net "THERMHOT#_C")
	)
	(segment
		(start 304.138076 -339.128354)
		(end 304.138076 -337.015582)
		(width 0.17145)
		(layer "F.Cu")
		(net "THERMHOT#_C")
	)
	(via
		(at 304.138076 -339.128354)
		(size 0.6604)
		(drill 0.3302)
		(layers "F.Cu" "B.Cu")
		(net "THERMHOT#_C")
	)
	(segment
		(start 310.0324 -339.479382)
		(end 310.0324 -339.128354)
		(width 0.254)
		(layer "F.Cu")
		(net "PWM_SCC_B_ZONE_D")
	)
	(segment
		(start 280.8732 -243.0018)
		(end 279.439116 -243.0018)
		(width 0.254)
		(layer "F.Cu")
		(net "PWM_SCC_B_ZONE_D")
	)
	(segment
		(start 281.559 -243.9924)
		(end 281.559 -243.6876)
		(width 0.254)
		(layer "F.Cu")
		(net "PWM_SCC_B_ZONE_D")
	)
	(segment
		(start 308.31028 -340.368382)
		(end 309.1434 -340.368382)
		(width 0.254)
		(layer "F.Cu")
		(net "PWM_SCC_B_ZONE_D")
	)
	(segment
		(start 281.559 -243.6876)
		(end 280.8732 -243.0018)
		(width 0.254)
		(layer "F.Cu")
		(net "PWM_SCC_B_ZONE_D")
	)
	(segment
		(start 309.1434 -340.368382)
		(end 310.0324 -339.479382)
		(width 0.254)
		(layer "F.Cu")
		(net "PWM_SCC_B_ZONE_D")
	)
	(segment
		(start 272.704052 -228.875082)
		(end 274.588224 -226.99091)
		(width 0.254)
		(layer "F.Cu")
		(net "PWM_SCC_B_ZONE_D")
	)
	(segment
		(start 274.588224 -226.99091)
		(end 280.940256 -226.99091)
		(width 0.254)
		(layer "F.Cu")
		(net "PWM_SCC_B_ZONE_D")
	)
	(segment
		(start 272.704052 -236.266736)
		(end 272.704052 -228.875082)
		(width 0.254)
		(layer "F.Cu")
		(net "PWM_SCC_B_ZONE_D")
	)
	(segment
		(start 279.439116 -243.0018)
		(end 272.704052 -236.266736)
		(width 0.254)
		(layer "F.Cu")
		(net "PWM_SCC_B_ZONE_D")
	)
	(segment
		(start 280.940256 -226.99091)
		(end 281.836622 -226.094544)
		(width 0.254)
		(layer "F.Cu")
		(net "PWM_SCC_B_ZONE_D")
	)
	(segment
		(start 310.0324 -339.128354)
		(end 310.0324 -337.015582)
		(width 0.254)
		(layer "F.Cu")
		(net "PWM_SCC_B_ZONE_D")
	)
	(via
		(at 308.31028 -340.368382)
		(size 0.5588)
		(drill 0.3048)
		(layers "F.Cu" "B.Cu")
		(net "PWM_SCC_B_ZONE_D")
	)
	(via
		(at 281.559 -243.9924)
		(size 0.5588)
		(drill 0.3048)
		(layers "F.Cu" "B.Cu")
		(net "PWM_SCC_B_ZONE_D")
	)
	(via
		(at 310.0324 -339.128354)
		(size 0.6604)
		(drill 0.3302)
		(layers "F.Cu" "B.Cu")
		(net "PWM_SCC_B_ZONE_D")
	)
	(segment
		(start 281.3558 -244.1956)
		(end 281.3558 -248.154952)
		(width 0.254)
		(layer "In5.Cu")
		(net "PWM_SCC_B_ZONE_D")
	)
	(segment
		(start 281.7368 -326.9488)
		(end 281.7368 -339.344)
		(width 0.254)
		(layer "In5.Cu")
		(net "PWM_SCC_B_ZONE_D")
	)
	(segment
		(start 308.31028 -342.75395)
		(end 308.31028 -340.368382)
		(width 0.254)
		(layer "In5.Cu")
		(net "PWM_SCC_B_ZONE_D")
	)
	(segment
		(start 293.0398 -343.3064)
		(end 307.75783 -343.3064)
		(width 0.254)
		(layer "In5.Cu")
		(net "PWM_SCC_B_ZONE_D")
	)
	(segment
		(start 307.75783 -343.3064)
		(end 308.31028 -342.75395)
		(width 0.254)
		(layer "In5.Cu")
		(net "PWM_SCC_B_ZONE_D")
	)
	(segment
		(start 281.7368 -339.344)
		(end 282.575 -340.1822)
		(width 0.254)
		(layer "In5.Cu")
		(net "PWM_SCC_B_ZONE_D")
	)
	(segment
		(start 268.072362 -313.284362)
		(end 281.7368 -326.9488)
		(width 0.254)
		(layer "In5.Cu")
		(net "PWM_SCC_B_ZONE_D")
	)
	(segment
		(start 282.575 -340.1822)
		(end 289.9156 -340.1822)
		(width 0.254)
		(layer "In5.Cu")
		(net "PWM_SCC_B_ZONE_D")
	)
	(segment
		(start 281.3558 -248.154952)
		(end 268.072362 -261.43839)
		(width 0.254)
		(layer "In5.Cu")
		(net "PWM_SCC_B_ZONE_D")
	)
	(segment
		(start 281.559 -243.9924)
		(end 281.3558 -244.1956)
		(width 0.254)
		(layer "In5.Cu")
		(net "PWM_SCC_B_ZONE_D")
	)
	(segment
		(start 268.072362 -261.43839)
		(end 268.072362 -313.284362)
		(width 0.254)
		(layer "In5.Cu")
		(net "PWM_SCC_B_ZONE_D")
	)
	(segment
		(start 289.9156 -340.1822)
		(end 293.0398 -343.3064)
		(width 0.254)
		(layer "In5.Cu")
		(net "PWM_SCC_B_ZONE_D")
	)
	(segment
		(start 300.709076 -340.368382)
		(end 301.598076 -339.479382)
		(width 0.254)
		(layer "F.Cu")
		(net "PWM_SCC_B_ZONE_C")
	)
	(segment
		(start 281.453844 -244.9068)
		(end 280.310844 -243.7638)
		(width 0.254)
		(layer "F.Cu")
		(net "PWM_SCC_B_ZONE_C")
	)
	(segment
		(start 282.414726 -225.2726)
		(end 283.23667 -226.094544)
		(width 0.254)
		(layer "F.Cu")
		(net "PWM_SCC_B_ZONE_C")
	)
	(segment
		(start 275.228812 -225.2726)
		(end 282.414726 -225.2726)
		(width 0.254)
		(layer "F.Cu")
		(net "PWM_SCC_B_ZONE_C")
	)
	(segment
		(start 301.598076 -339.128354)
		(end 301.598076 -337.015582)
		(width 0.254)
		(layer "F.Cu")
		(net "PWM_SCC_B_ZONE_C")
	)
	(segment
		(start 271.942052 -228.55936)
		(end 275.228812 -225.2726)
		(width 0.254)
		(layer "F.Cu")
		(net "PWM_SCC_B_ZONE_C")
	)
	(segment
		(start 301.598076 -339.479382)
		(end 301.598076 -339.128354)
		(width 0.254)
		(layer "F.Cu")
		(net "PWM_SCC_B_ZONE_C")
	)
	(segment
		(start 280.310844 -243.7638)
		(end 279.123394 -243.7638)
		(width 0.254)
		(layer "F.Cu")
		(net "PWM_SCC_B_ZONE_C")
	)
	(segment
		(start 279.123394 -243.7638)
		(end 271.942052 -236.582458)
		(width 0.254)
		(layer "F.Cu")
		(net "PWM_SCC_B_ZONE_C")
	)
	(segment
		(start 271.942052 -236.582458)
		(end 271.942052 -228.55936)
		(width 0.254)
		(layer "F.Cu")
		(net "PWM_SCC_B_ZONE_C")
	)
	(segment
		(start 299.875956 -340.368382)
		(end 300.709076 -340.368382)
		(width 0.254)
		(layer "F.Cu")
		(net "PWM_SCC_B_ZONE_C")
	)
	(segment
		(start 282.0924 -244.9068)
		(end 281.453844 -244.9068)
		(width 0.254)
		(layer "F.Cu")
		(net "PWM_SCC_B_ZONE_C")
	)
	(via
		(at 299.875956 -340.368382)
		(size 0.5588)
		(drill 0.3048)
		(layers "F.Cu" "B.Cu")
		(net "PWM_SCC_B_ZONE_C")
	)
	(via
		(at 282.0924 -244.9068)
		(size 0.5588)
		(drill 0.3048)
		(layers "F.Cu" "B.Cu")
		(net "PWM_SCC_B_ZONE_C")
	)
	(via
		(at 301.598076 -339.128354)
		(size 0.6604)
		(drill 0.3302)
		(layers "F.Cu" "B.Cu")
		(net "PWM_SCC_B_ZONE_C")
	)
	(segment
		(start 268.834362 -312.801762)
		(end 268.834362 -261.757922)
		(width 0.254)
		(layer "In5.Cu")
		(net "PWM_SCC_B_ZONE_C")
	)
	(segment
		(start 283.0322 -339.3694)
		(end 282.4988 -338.836)
		(width 0.254)
		(layer "In5.Cu")
		(net "PWM_SCC_B_ZONE_C")
	)
	(segment
		(start 282.2194 -245.0338)
		(end 282.0924 -244.9068)
		(width 0.254)
		(layer "In5.Cu")
		(net "PWM_SCC_B_ZONE_C")
	)
	(segment
		(start 268.834362 -261.757922)
		(end 282.2194 -248.372884)
		(width 0.254)
		(layer "In5.Cu")
		(net "PWM_SCC_B_ZONE_C")
	)
	(segment
		(start 282.4988 -326.4662)
		(end 268.834362 -312.801762)
		(width 0.254)
		(layer "In5.Cu")
		(net "PWM_SCC_B_ZONE_C")
	)
	(segment
		(start 292.763956 -340.368382)
		(end 291.764974 -339.3694)
		(width 0.254)
		(layer "In5.Cu")
		(net "PWM_SCC_B_ZONE_C")
	)
	(segment
		(start 299.875956 -340.368382)
		(end 292.763956 -340.368382)
		(width 0.254)
		(layer "In5.Cu")
		(net "PWM_SCC_B_ZONE_C")
	)
	(segment
		(start 282.2194 -248.372884)
		(end 282.2194 -245.0338)
		(width 0.254)
		(layer "In5.Cu")
		(net "PWM_SCC_B_ZONE_C")
	)
	(segment
		(start 291.764974 -339.3694)
		(end 283.0322 -339.3694)
		(width 0.254)
		(layer "In5.Cu")
		(net "PWM_SCC_B_ZONE_C")
	)
	(segment
		(start 282.4988 -338.836)
		(end 282.4988 -326.4662)
		(width 0.254)
		(layer "In5.Cu")
		(net "PWM_SCC_B_ZONE_C")
	)
	(segment
		(start 311.2516 -329.74661)
		(end 311.2516 -328.727562)
		(width 0.254)
		(layer "F.Cu")
		(net "PWM_SCC_A_ZONE_D")
	)
	(segment
		(start 221.964504 -74.835512)
		(end 222.600012 -74.200004)
		(width 0.17145)
		(layer "F.Cu")
		(net "PWM_SCC_A_ZONE_D")
	)
	(segment
		(start 221.964504 -79.405734)
		(end 221.964504 -74.835512)
		(width 0.17145)
		(layer "F.Cu")
		(net "PWM_SCC_A_ZONE_D")
	)
	(segment
		(start 311.3024 -329.79741)
		(end 311.2516 -329.74661)
		(width 0.254)
		(layer "F.Cu")
		(net "PWM_SCC_A_ZONE_D")
	)
	(segment
		(start 222.071184 -79.512414)
		(end 221.964504 -79.405734)
		(width 0.17145)
		(layer "F.Cu")
		(net "PWM_SCC_A_ZONE_D")
	)
	(segment
		(start 310.82742 -328.303382)
		(end 309.9943 -328.303382)
		(width 0.254)
		(layer "F.Cu")
		(net "PWM_SCC_A_ZONE_D")
	)
	(segment
		(start 311.2516 -328.727562)
		(end 310.82742 -328.303382)
		(width 0.254)
		(layer "F.Cu")
		(net "PWM_SCC_A_ZONE_D")
	)
	(segment
		(start 311.3024 -331.910182)
		(end 311.3024 -329.79741)
		(width 0.254)
		(layer "F.Cu")
		(net "PWM_SCC_A_ZONE_D")
	)
	(segment
		(start 222.138748 -81.70672)
		(end 222.071184 -81.639156)
		(width 0.17145)
		(layer "F.Cu")
		(net "PWM_SCC_A_ZONE_D")
	)
	(segment
		(start 222.138748 -91.176602)
		(end 222.138748 -81.70672)
		(width 0.254)
		(layer "F.Cu")
		(net "PWM_SCC_A_ZONE_D")
	)
	(segment
		(start 226.489768 -95.527622)
		(end 222.138748 -91.176602)
		(width 0.254)
		(layer "F.Cu")
		(net "PWM_SCC_A_ZONE_D")
	)
	(segment
		(start 222.071184 -81.639156)
		(end 222.071184 -79.512414)
		(width 0.17145)
		(layer "F.Cu")
		(net "PWM_SCC_A_ZONE_D")
	)
	(segment
		(start 226.489768 -139.155424)
		(end 226.489768 -95.527622)
		(width 0.254)
		(layer "F.Cu")
		(net "PWM_SCC_A_ZONE_D")
	)
	(segment
		(start 210.2485 -155.396692)
		(end 226.489768 -139.155424)
		(width 0.254)
		(layer "F.Cu")
		(net "PWM_SCC_A_ZONE_D")
	)
	(via
		(at 210.2485 -155.396692)
		(size 0.5588)
		(drill 0.3048)
		(layers "F.Cu" "B.Cu")
		(net "PWM_SCC_A_ZONE_D")
	)
	(via
		(at 309.9943 -328.303382)
		(size 0.5588)
		(drill 0.3048)
		(layers "F.Cu" "B.Cu")
		(net "PWM_SCC_A_ZONE_D")
	)
	(via
		(at 197.383654 -310.771794)
		(size 0.5588)
		(drill 0.3048)
		(layers "F.Cu" "B.Cu")
		(net "PWM_SCC_A_ZONE_D")
	)
	(via
		(at 311.3024 -329.79741)
		(size 0.6604)
		(drill 0.3302)
		(layers "F.Cu" "B.Cu")
		(net "PWM_SCC_A_ZONE_D")
	)
	(segment
		(start 234.30357 -322.20535)
		(end 232.466642 -320.368422)
		(width 0.254)
		(layer "B.Cu")
		(net "PWM_SCC_A_ZONE_D")
	)
	(segment
		(start 232.466642 -320.368422)
		(end 205.199996 -320.368422)
		(width 0.254)
		(layer "B.Cu")
		(net "PWM_SCC_A_ZONE_D")
	)
	(segment
		(start 197.383654 -312.55208)
		(end 197.383654 -310.771794)
		(width 0.254)
		(layer "B.Cu")
		(net "PWM_SCC_A_ZONE_D")
	)
	(segment
		(start 309.9943 -328.303382)
		(end 303.896268 -322.20535)
		(width 0.254)
		(layer "B.Cu")
		(net "PWM_SCC_A_ZONE_D")
	)
	(segment
		(start 303.896268 -322.20535)
		(end 234.30357 -322.20535)
		(width 0.254)
		(layer "B.Cu")
		(net "PWM_SCC_A_ZONE_D")
	)
	(segment
		(start 205.199996 -320.368422)
		(end 197.383654 -312.55208)
		(width 0.254)
		(layer "B.Cu")
		(net "PWM_SCC_A_ZONE_D")
	)
	(segment
		(start 205.017624 -294.985186)
		(end 197.383654 -302.619156)
		(width 0.254)
		(layer "In2.Cu")
		(net "PWM_SCC_A_ZONE_D")
	)
	(segment
		(start 205.017878 -294.985186)
		(end 205.017624 -294.985186)
		(width 0.254)
		(layer "In2.Cu")
		(net "PWM_SCC_A_ZONE_D")
	)
	(segment
		(start 206.356712 -293.646098)
		(end 206.356712 -293.646352)
		(width 0.254)
		(layer "In2.Cu")
		(net "PWM_SCC_A_ZONE_D")
	)
	(segment
		(start 211.242148 -157.113986)
		(end 211.242148 -165.71087)
		(width 0.254)
		(layer "In2.Cu")
		(net "PWM_SCC_A_ZONE_D")
	)
	(segment
		(start 207.175608 -245.824756)
		(end 206.356712 -246.643652)
		(width 0.254)
		(layer "In2.Cu")
		(net "PWM_SCC_A_ZONE_D")
	)
	(segment
		(start 210.81619 -234.470956)
		(end 210.815936 -234.47121)
		(width 0.254)
		(layer "In2.Cu")
		(net "PWM_SCC_A_ZONE_D")
	)
	(segment
		(start 212.344508 -211.47913)
		(end 212.344508 -216.475818)
		(width 0.254)
		(layer "In2.Cu")
		(net "PWM_SCC_A_ZONE_D")
	)
	(segment
		(start 210.815936 -234.47121)
		(end 207.175608 -238.111792)
		(width 0.254)
		(layer "In2.Cu")
		(net "PWM_SCC_A_ZONE_D")
	)
	(segment
		(start 210.2485 -156.120338)
		(end 211.242148 -157.113986)
		(width 0.254)
		(layer "In2.Cu")
		(net "PWM_SCC_A_ZONE_D")
	)
	(segment
		(start 210.81619 -220.866462)
		(end 210.81619 -234.470956)
		(width 0.254)
		(layer "In2.Cu")
		(net "PWM_SCC_A_ZONE_D")
	)
	(segment
		(start 212.344508 -216.475818)
		(end 212.979 -217.11031)
		(width 0.254)
		(layer "In2.Cu")
		(net "PWM_SCC_A_ZONE_D")
	)
	(segment
		(start 212.479382 -175.575722)
		(end 212.479382 -211.344256)
		(width 0.254)
		(layer "In2.Cu")
		(net "PWM_SCC_A_ZONE_D")
	)
	(segment
		(start 211.90204 -166.370762)
		(end 211.90204 -174.99838)
		(width 0.254)
		(layer "In2.Cu")
		(net "PWM_SCC_A_ZONE_D")
	)
	(segment
		(start 210.2485 -155.396692)
		(end 210.2485 -156.120338)
		(width 0.254)
		(layer "In2.Cu")
		(net "PWM_SCC_A_ZONE_D")
	)
	(segment
		(start 206.356966 -293.645844)
		(end 206.356712 -293.646098)
		(width 0.254)
		(layer "In2.Cu")
		(net "PWM_SCC_A_ZONE_D")
	)
	(segment
		(start 206.356712 -293.646352)
		(end 205.017878 -294.985186)
		(width 0.254)
		(layer "In2.Cu")
		(net "PWM_SCC_A_ZONE_D")
	)
	(segment
		(start 211.90204 -174.99838)
		(end 212.479382 -175.575722)
		(width 0.254)
		(layer "In2.Cu")
		(net "PWM_SCC_A_ZONE_D")
	)
	(segment
		(start 211.242148 -165.71087)
		(end 211.90204 -166.370762)
		(width 0.254)
		(layer "In2.Cu")
		(net "PWM_SCC_A_ZONE_D")
	)
	(segment
		(start 212.979 -218.703652)
		(end 210.81619 -220.866462)
		(width 0.254)
		(layer "In2.Cu")
		(net "PWM_SCC_A_ZONE_D")
	)
	(segment
		(start 206.356712 -293.014654)
		(end 206.356966 -293.014908)
		(width 0.254)
		(layer "In2.Cu")
		(net "PWM_SCC_A_ZONE_D")
	)
	(segment
		(start 212.979 -217.11031)
		(end 212.979 -218.703652)
		(width 0.254)
		(layer "In2.Cu")
		(net "PWM_SCC_A_ZONE_D")
	)
	(segment
		(start 207.175608 -238.111792)
		(end 207.175608 -245.824756)
		(width 0.254)
		(layer "In2.Cu")
		(net "PWM_SCC_A_ZONE_D")
	)
	(segment
		(start 206.356966 -293.014908)
		(end 206.356966 -293.645844)
		(width 0.254)
		(layer "In2.Cu")
		(net "PWM_SCC_A_ZONE_D")
	)
	(segment
		(start 197.383654 -302.619156)
		(end 197.383654 -310.771794)
		(width 0.254)
		(layer "In2.Cu")
		(net "PWM_SCC_A_ZONE_D")
	)
	(segment
		(start 212.479382 -211.344256)
		(end 212.344508 -211.47913)
		(width 0.254)
		(layer "In2.Cu")
		(net "PWM_SCC_A_ZONE_D")
	)
	(segment
		(start 206.356712 -246.643652)
		(end 206.356712 -293.014654)
		(width 0.254)
		(layer "In2.Cu")
		(net "PWM_SCC_A_ZONE_D")
	)
	(segment
		(start 302.7934 -328.703686)
		(end 302.393096 -328.303382)
		(width 0.254)
		(layer "F.Cu")
		(net "PWM_SCC_A_ZONE_C")
	)
	(segment
		(start 221.282768 -81.915)
		(end 221.391734 -81.806034)
		(width 0.17145)
		(layer "F.Cu")
		(net "PWM_SCC_A_ZONE_C")
	)
	(segment
		(start 221.391734 -80.195674)
		(end 221.39402 -80.193388)
		(width 0.17145)
		(layer "F.Cu")
		(net "PWM_SCC_A_ZONE_C")
	)
	(segment
		(start 221.391734 -81.806034)
		(end 221.391734 -80.195674)
		(width 0.17145)
		(layer "F.Cu")
		(net "PWM_SCC_A_ZONE_C")
	)
	(segment
		(start 302.868076 -329.79741)
		(end 302.7934 -329.722734)
		(width 0.254)
		(layer "F.Cu")
		(net "PWM_SCC_A_ZONE_C")
	)
	(segment
		(start 225.519234 -138.982958)
		(end 225.519234 -95.63481)
		(width 0.254)
		(layer "F.Cu")
		(net "PWM_SCC_A_ZONE_C")
	)
	(segment
		(start 225.519234 -95.63481)
		(end 221.282768 -91.398344)
		(width 0.254)
		(layer "F.Cu")
		(net "PWM_SCC_A_ZONE_C")
	)
	(segment
		(start 209.452972 -155.04922)
		(end 225.519234 -138.982958)
		(width 0.254)
		(layer "F.Cu")
		(net "PWM_SCC_A_ZONE_C")
	)
	(segment
		(start 221.39402 -80.193388)
		(end 221.39402 -79.4258)
		(width 0.17145)
		(layer "F.Cu")
		(net "PWM_SCC_A_ZONE_C")
	)
	(segment
		(start 302.868076 -331.910182)
		(end 302.868076 -329.79741)
		(width 0.254)
		(layer "F.Cu")
		(net "PWM_SCC_A_ZONE_C")
	)
	(segment
		(start 301.072296 -326.787002)
		(end 301.072296 -327.437496)
		(width 0.254)
		(layer "F.Cu")
		(net "PWM_SCC_A_ZONE_C")
	)
	(segment
		(start 221.282768 -91.398344)
		(end 221.282768 -81.915)
		(width 0.254)
		(layer "F.Cu")
		(net "PWM_SCC_A_ZONE_C")
	)
	(segment
		(start 221.437454 -79.382366)
		(end 221.437454 -73.962514)
		(width 0.17145)
		(layer "F.Cu")
		(net "PWM_SCC_A_ZONE_C")
	)
	(segment
		(start 301.938182 -328.303382)
		(end 302.393096 -328.303382)
		(width 0.254)
		(layer "F.Cu")
		(net "PWM_SCC_A_ZONE_C")
	)
	(segment
		(start 301.072296 -327.437496)
		(end 301.938182 -328.303382)
		(width 0.254)
		(layer "F.Cu")
		(net "PWM_SCC_A_ZONE_C")
	)
	(segment
		(start 209.452972 -156.112718)
		(end 209.452972 -155.04922)
		(width 0.254)
		(layer "F.Cu")
		(net "PWM_SCC_A_ZONE_C")
	)
	(segment
		(start 302.7934 -329.722734)
		(end 302.7934 -328.703686)
		(width 0.254)
		(layer "F.Cu")
		(net "PWM_SCC_A_ZONE_C")
	)
	(segment
		(start 221.437454 -73.962514)
		(end 222.600012 -72.799956)
		(width 0.17145)
		(layer "F.Cu")
		(net "PWM_SCC_A_ZONE_C")
	)
	(segment
		(start 221.39402 -79.4258)
		(end 221.437454 -79.382366)
		(width 0.17145)
		(layer "F.Cu")
		(net "PWM_SCC_A_ZONE_C")
	)
	(via
		(at 196.240654 -308.485794)
		(size 0.5588)
		(drill 0.3048)
		(layers "F.Cu" "B.Cu")
		(net "PWM_SCC_A_ZONE_C")
	)
	(via
		(at 209.452972 -156.112718)
		(size 0.5588)
		(drill 0.3048)
		(layers "F.Cu" "B.Cu")
		(net "PWM_SCC_A_ZONE_C")
	)
	(via
		(at 302.868076 -329.79741)
		(size 0.6604)
		(drill 0.3302)
		(layers "F.Cu" "B.Cu")
		(net "PWM_SCC_A_ZONE_C")
	)
	(via
		(at 301.072296 -326.787002)
		(size 0.5588)
		(drill 0.3048)
		(layers "F.Cu" "B.Cu")
		(net "PWM_SCC_A_ZONE_C")
	)
	(segment
		(start 204.51318 -321.837304)
		(end 195.440554 -312.764678)
		(width 0.254)
		(layer "B.Cu")
		(net "PWM_SCC_A_ZONE_C")
	)
	(segment
		(start 231.835198 -321.892422)
		(end 204.568552 -321.892422)
		(width 0.254)
		(layer "B.Cu")
		(net "PWM_SCC_A_ZONE_C")
	)
	(segment
		(start 204.513434 -321.837304)
		(end 204.51318 -321.837304)
		(width 0.254)
		(layer "B.Cu")
		(net "PWM_SCC_A_ZONE_C")
	)
	(segment
		(start 301.072296 -326.787002)
		(end 294.153336 -326.787002)
		(width 0.254)
		(layer "B.Cu")
		(net "PWM_SCC_A_ZONE_C")
	)
	(segment
		(start 204.568552 -321.892422)
		(end 204.513434 -321.837304)
		(width 0.254)
		(layer "B.Cu")
		(net "PWM_SCC_A_ZONE_C")
	)
	(segment
		(start 195.440554 -312.764678)
		(end 195.440554 -309.285894)
		(width 0.254)
		(layer "B.Cu")
		(net "PWM_SCC_A_ZONE_C")
	)
	(segment
		(start 233.672126 -323.72935)
		(end 231.835198 -321.892422)
		(width 0.254)
		(layer "B.Cu")
		(net "PWM_SCC_A_ZONE_C")
	)
	(segment
		(start 195.440554 -309.285894)
		(end 196.240654 -308.485794)
		(width 0.254)
		(layer "B.Cu")
		(net "PWM_SCC_A_ZONE_C")
	)
	(segment
		(start 294.153336 -326.787002)
		(end 291.095684 -323.72935)
		(width 0.254)
		(layer "B.Cu")
		(net "PWM_SCC_A_ZONE_C")
	)
	(segment
		(start 291.095684 -323.72935)
		(end 233.672126 -323.72935)
		(width 0.254)
		(layer "B.Cu")
		(net "PWM_SCC_A_ZONE_C")
	)
	(segment
		(start 206.413608 -237.716568)
		(end 206.413608 -245.509034)
		(width 0.254)
		(layer "In2.Cu")
		(net "PWM_SCC_A_ZONE_C")
	)
	(segment
		(start 210.904836 -218.216226)
		(end 211.0994 -218.41079)
		(width 0.254)
		(layer "In2.Cu")
		(net "PWM_SCC_A_ZONE_C")
	)
	(segment
		(start 210.480148 -157.471872)
		(end 210.480148 -166.026592)
		(width 0.254)
		(layer "In2.Cu")
		(net "PWM_SCC_A_ZONE_C")
	)
	(segment
		(start 210.05419 -220.550486)
		(end 210.05419 -230.189024)
		(width 0.254)
		(layer "In2.Cu")
		(net "PWM_SCC_A_ZONE_C")
	)
	(segment
		(start 204.701902 -294.223186)
		(end 196.240654 -302.684434)
		(width 0.254)
		(layer "In2.Cu")
		(net "PWM_SCC_A_ZONE_C")
	)
	(segment
		(start 207.070706 -233.172508)
		(end 207.070706 -237.05947)
		(width 0.254)
		(layer "In2.Cu")
		(net "PWM_SCC_A_ZONE_C")
	)
	(segment
		(start 210.904836 -211.841334)
		(end 210.904836 -218.216226)
		(width 0.254)
		(layer "In2.Cu")
		(net "PWM_SCC_A_ZONE_C")
	)
	(segment
		(start 209.452972 -156.444696)
		(end 210.480148 -157.471872)
		(width 0.254)
		(layer "In2.Cu")
		(net "PWM_SCC_A_ZONE_C")
	)
	(segment
		(start 204.702156 -294.223186)
		(end 204.701902 -294.223186)
		(width 0.254)
		(layer "In2.Cu")
		(net "PWM_SCC_A_ZONE_C")
	)
	(segment
		(start 205.594712 -246.32793)
		(end 205.594712 -293.330376)
		(width 0.254)
		(layer "In2.Cu")
		(net "PWM_SCC_A_ZONE_C")
	)
	(segment
		(start 209.452972 -156.112718)
		(end 209.452972 -156.444696)
		(width 0.254)
		(layer "In2.Cu")
		(net "PWM_SCC_A_ZONE_C")
	)
	(segment
		(start 211.0994 -218.41079)
		(end 211.0994 -219.505276)
		(width 0.254)
		(layer "In2.Cu")
		(net "PWM_SCC_A_ZONE_C")
	)
	(segment
		(start 211.717382 -202.86091)
		(end 211.717382 -211.028788)
		(width 0.254)
		(layer "In2.Cu")
		(net "PWM_SCC_A_ZONE_C")
	)
	(segment
		(start 206.413608 -245.509034)
		(end 205.594712 -246.32793)
		(width 0.254)
		(layer "In2.Cu")
		(net "PWM_SCC_A_ZONE_C")
	)
	(segment
		(start 205.594458 -293.33063)
		(end 205.594458 -293.330884)
		(width 0.254)
		(layer "In2.Cu")
		(net "PWM_SCC_A_ZONE_C")
	)
	(segment
		(start 211.14004 -166.686484)
		(end 211.14004 -202.283568)
		(width 0.254)
		(layer "In2.Cu")
		(net "PWM_SCC_A_ZONE_C")
	)
	(segment
		(start 210.480148 -166.026592)
		(end 211.14004 -166.686484)
		(width 0.254)
		(layer "In2.Cu")
		(net "PWM_SCC_A_ZONE_C")
	)
	(segment
		(start 205.594712 -293.330376)
		(end 205.594458 -293.33063)
		(width 0.254)
		(layer "In2.Cu")
		(net "PWM_SCC_A_ZONE_C")
	)
	(segment
		(start 205.594458 -293.330884)
		(end 204.702156 -294.223186)
		(width 0.254)
		(layer "In2.Cu")
		(net "PWM_SCC_A_ZONE_C")
	)
	(segment
		(start 196.240654 -302.684434)
		(end 196.240654 -308.485794)
		(width 0.254)
		(layer "In2.Cu")
		(net "PWM_SCC_A_ZONE_C")
	)
	(segment
		(start 210.05419 -230.189024)
		(end 207.070706 -233.172508)
		(width 0.254)
		(layer "In2.Cu")
		(net "PWM_SCC_A_ZONE_C")
	)
	(segment
		(start 207.070706 -237.05947)
		(end 206.413608 -237.716568)
		(width 0.254)
		(layer "In2.Cu")
		(net "PWM_SCC_A_ZONE_C")
	)
	(segment
		(start 211.717382 -211.028788)
		(end 210.904836 -211.841334)
		(width 0.254)
		(layer "In2.Cu")
		(net "PWM_SCC_A_ZONE_C")
	)
	(segment
		(start 211.0994 -219.505276)
		(end 210.05419 -220.550486)
		(width 0.254)
		(layer "In2.Cu")
		(net "PWM_SCC_A_ZONE_C")
	)
	(segment
		(start 211.14004 -202.283568)
		(end 211.717382 -202.86091)
		(width 0.254)
		(layer "In2.Cu")
		(net "PWM_SCC_A_ZONE_C")
	)
	(segment
		(start 310.4134 -340.368382)
		(end 311.3024 -339.479382)
		(width 0.254)
		(layer "F.Cu")
		(net "PWM_OUT_D_R")
	)
	(segment
		(start 311.3024 -337.015582)
		(end 311.3024 -339.128354)
		(width 0.254)
		(layer "F.Cu")
		(net "PWM_OUT_D_R")
	)
	(segment
		(start 311.3024 -339.479382)
		(end 311.3024 -339.128354)
		(width 0.254)
		(layer "F.Cu")
		(net "PWM_OUT_D_R")
	)
	(via
		(at 311.3024 -339.128354)
		(size 0.6604)
		(drill 0.3302)
		(layers "F.Cu" "B.Cu")
		(net "PWM_OUT_D_R")
	)
	(segment
		(start 285.7881 -328.9554)
		(end 286.1945 -329.3618)
		(width 0.254)
		(layer "F.Cu")
		(net "PWM_OUT_D")
	)
	(segment
		(start 285.9659 -329.5904)
		(end 286.1945 -329.3618)
		(width 0.254)
		(layer "F.Cu")
		(net "PWM_OUT_D")
	)
	(segment
		(start 282.35148 -328.82332)
		(end 283.4894 -328.82332)
		(width 0.254)
		(layer "F.Cu")
		(net "PWM_OUT_D")
	)
	(segment
		(start 284.4038 -328.9554)
		(end 285.7881 -328.9554)
		(width 0.254)
		(layer "F.Cu")
		(net "PWM_OUT_D")
	)
	(segment
		(start 281.70124 -329.47356)
		(end 282.35148 -328.82332)
		(width 0.254)
		(layer "F.Cu")
		(net "PWM_OUT_D")
	)
	(segment
		(start 285.242 -329.5904)
		(end 285.9659 -329.5904)
		(width 0.254)
		(layer "F.Cu")
		(net "PWM_OUT_D")
	)
	(segment
		(start 310.4134 -342.0364)
		(end 310.388 -342.0618)
		(width 0.254)
		(layer "F.Cu")
		(net "PWM_OUT_D")
	)
	(segment
		(start 284.27172 -328.82332)
		(end 284.4038 -328.9554)
		(width 0.254)
		(layer "F.Cu")
		(net "PWM_OUT_D")
	)
	(segment
		(start 277.8506 -329.47356)
		(end 281.70124 -329.47356)
		(width 0.254)
		(layer "F.Cu")
		(net "PWM_OUT_D")
	)
	(segment
		(start 283.4894 -328.82332)
		(end 284.27172 -328.82332)
		(width 0.254)
		(layer "F.Cu")
		(net "PWM_OUT_D")
	)
	(segment
		(start 310.4134 -341.257382)
		(end 310.4134 -342.0364)
		(width 0.254)
		(layer "F.Cu")
		(net "PWM_OUT_D")
	)
	(via
		(at 285.242 -329.5904)
		(size 0.5588)
		(drill 0.3048)
		(layers "F.Cu" "B.Cu")
		(net "PWM_OUT_D")
	)
	(via
		(at 310.388 -342.0618)
		(size 0.5588)
		(drill 0.3048)
		(layers "F.Cu" "B.Cu")
		(net "PWM_OUT_D")
	)
	(via
		(at 301.172372 -338.790534)
		(size 0.6096)
		(drill 0.3048)
		(layers "F.Cu" "B.Cu")
		(net "PWM_OUT_D")
	)
	(segment
		(start 294.442134 -338.790534)
		(end 301.172372 -338.790534)
		(width 0.254)
		(layer "B.Cu")
		(net "PWM_OUT_D")
	)
	(segment
		(start 307.822346 -338.790534)
		(end 301.172372 -338.790534)
		(width 0.254)
		(layer "B.Cu")
		(net "PWM_OUT_D")
	)
	(segment
		(start 285.242 -329.5904)
		(end 294.442134 -338.790534)
		(width 0.254)
		(layer "B.Cu")
		(net "PWM_OUT_D")
	)
	(segment
		(start 310.388 -341.356188)
		(end 307.822346 -338.790534)
		(width 0.254)
		(layer "B.Cu")
		(net "PWM_OUT_D")
	)
	(segment
		(start 310.388 -342.0618)
		(end 310.388 -341.356188)
		(width 0.254)
		(layer "B.Cu")
		(net "PWM_OUT_D")
	)
	(segment
		(start 301.979076 -340.368382)
		(end 302.868076 -339.479382)
		(width 0.254)
		(layer "F.Cu")
		(net "PWM_OUT_C_R")
	)
	(segment
		(start 302.868076 -339.479382)
		(end 302.868076 -339.128354)
		(width 0.254)
		(layer "F.Cu")
		(net "PWM_OUT_C_R")
	)
	(segment
		(start 302.868076 -339.128354)
		(end 302.868076 -337.015582)
		(width 0.254)
		(layer "F.Cu")
		(net "PWM_OUT_C_R")
	)
	(via
		(at 302.868076 -339.128354)
		(size 0.6604)
		(drill 0.3302)
		(layers "F.Cu" "B.Cu")
		(net "PWM_OUT_C_R")
	)
	(segment
		(start 277.8506 -330.77404)
		(end 278.90724 -330.77404)
		(width 0.254)
		(layer "F.Cu")
		(net "PWM_OUT_C")
	)
	(segment
		(start 279.1968 -331.724)
		(end 278.84755 -332.07325)
		(width 0.254)
		(layer "F.Cu")
		(net "PWM_OUT_C")
	)
	(segment
		(start 277.04415 -332.07325)
		(end 276.50567 -332.61173)
		(width 0.254)
		(layer "F.Cu")
		(net "PWM_OUT_C")
	)
	(segment
		(start 277.8506 -332.07325)
		(end 277.04415 -332.07325)
		(width 0.254)
		(layer "F.Cu")
		(net "PWM_OUT_C")
	)
	(segment
		(start 276.50567 -332.61173)
		(end 275.834348 -332.61173)
		(width 0.254)
		(layer "F.Cu")
		(net "PWM_OUT_C")
	)
	(segment
		(start 278.84755 -332.07325)
		(end 277.8506 -332.07325)
		(width 0.254)
		(layer "F.Cu")
		(net "PWM_OUT_C")
	)
	(segment
		(start 301.979076 -341.257382)
		(end 301.979076 -342.077802)
		(width 0.254)
		(layer "F.Cu")
		(net "PWM_OUT_C")
	)
	(segment
		(start 279.1968 -331.0636)
		(end 279.1968 -331.724)
		(width 0.254)
		(layer "F.Cu")
		(net "PWM_OUT_C")
	)
	(segment
		(start 278.90724 -330.77404)
		(end 279.1968 -331.0636)
		(width 0.254)
		(layer "F.Cu")
		(net "PWM_OUT_C")
	)
	(segment
		(start 274.84832 -332.61173)
		(end 274.0279 -332.61173)
		(width 0.254)
		(layer "F.Cu")
		(net "PWM_OUT_C")
	)
	(segment
		(start 274.84832 -332.61173)
		(end 275.834348 -332.61173)
		(width 0.254)
		(layer "F.Cu")
		(net "PWM_OUT_C")
	)
	(via
		(at 275.834348 -332.61173)
		(size 0.6604)
		(drill 0.3302)
		(layers "F.Cu" "B.Cu")
		(net "PWM_OUT_C")
	)
	(via
		(at 301.979076 -342.077802)
		(size 0.5588)
		(drill 0.3048)
		(layers "F.Cu" "B.Cu")
		(net "PWM_OUT_C")
	)
	(via
		(at 274.84832 -332.61173)
		(size 0.5588)
		(drill 0.3048)
		(layers "F.Cu" "B.Cu")
		(net "PWM_OUT_C")
	)
	(segment
		(start 295.40581 -341.22741)
		(end 285.3944 -331.216)
		(width 0.254)
		(layer "B.Cu")
		(net "PWM_OUT_C")
	)
	(segment
		(start 301.979076 -342.077802)
		(end 301.128684 -341.22741)
		(width 0.254)
		(layer "B.Cu")
		(net "PWM_OUT_C")
	)
	(segment
		(start 285.3944 -331.216)
		(end 277.495 -331.216)
		(width 0.254)
		(layer "B.Cu")
		(net "PWM_OUT_C")
	)
	(segment
		(start 276.09927 -332.61173)
		(end 274.84832 -332.61173)
		(width 0.254)
		(layer "B.Cu")
		(net "PWM_OUT_C")
	)
	(segment
		(start 301.128684 -341.22741)
		(end 295.40581 -341.22741)
		(width 0.254)
		(layer "B.Cu")
		(net "PWM_OUT_C")
	)
	(segment
		(start 277.495 -331.216)
		(end 276.09927 -332.61173)
		(width 0.254)
		(layer "B.Cu")
		(net "PWM_OUT_C")
	)
	(segment
		(start 313.8424 -337.015582)
		(end 313.8424 -339.128354)
		(width 0.17145)
		(layer "F.Cu")
		(net "PWM_CAMP_SEL2")
	)
	(segment
		(start 314.0964 -340.368382)
		(end 315.3664 -340.368382)
		(width 0.17145)
		(layer "F.Cu")
		(net "PWM_CAMP_SEL2")
	)
	(segment
		(start 313.8424 -339.128354)
		(end 313.8424 -340.114382)
		(width 0.17145)
		(layer "F.Cu")
		(net "PWM_CAMP_SEL2")
	)
	(segment
		(start 313.8424 -340.114382)
		(end 314.0964 -340.368382)
		(width 0.17145)
		(layer "F.Cu")
		(net "PWM_CAMP_SEL2")
	)
	(via
		(at 313.8424 -339.128354)
		(size 0.6604)
		(drill 0.3302)
		(layers "F.Cu" "B.Cu")
		(net "PWM_CAMP_SEL2")
	)
	(segment
		(start 313.8424 -331.910182)
		(end 313.8424 -329.79741)
		(width 0.254)
		(layer "F.Cu")
		(net "PWM_BMC_B_ZONE_D")
	)
	(segment
		(start 313.8424 -328.303382)
		(end 313.8424 -329.79741)
		(width 0.254)
		(layer "F.Cu")
		(net "PWM_BMC_B_ZONE_D")
	)
	(segment
		(start 314.66282 -328.303382)
		(end 313.8424 -328.303382)
		(width 0.254)
		(layer "F.Cu")
		(net "PWM_BMC_B_ZONE_D")
	)
	(via
		(at 313.8424 -329.79741)
		(size 0.6604)
		(drill 0.3302)
		(layers "F.Cu" "B.Cu")
		(net "PWM_BMC_B_ZONE_D")
	)
	(via
		(at 196.240654 -309.628794)
		(size 0.5588)
		(drill 0.3048)
		(layers "F.Cu" "B.Cu")
		(net "PWM_BMC_B_ZONE_D")
	)
	(via
		(at 314.66282 -328.303382)
		(size 0.5588)
		(drill 0.3048)
		(layers "F.Cu" "B.Cu")
		(net "PWM_BMC_B_ZONE_D")
	)
	(segment
		(start 232.782364 -319.606422)
		(end 207.230726 -319.606422)
		(width 0.254)
		(layer "B.Cu")
		(net "PWM_BMC_B_ZONE_D")
	)
	(segment
		(start 234.619292 -321.44335)
		(end 232.782364 -319.606422)
		(width 0.254)
		(layer "B.Cu")
		(net "PWM_BMC_B_ZONE_D")
	)
	(segment
		(start 197.69963 -310.009794)
		(end 197.634098 -310.009794)
		(width 0.254)
		(layer "B.Cu")
		(net "PWM_BMC_B_ZONE_D")
	)
	(segment
		(start 207.230726 -319.606422)
		(end 198.145654 -310.52135)
		(width 0.254)
		(layer "B.Cu")
		(net "PWM_BMC_B_ZONE_D")
	)
	(segment
		(start 198.145654 -310.52135)
		(end 198.145654 -310.455818)
		(width 0.254)
		(layer "B.Cu")
		(net "PWM_BMC_B_ZONE_D")
	)
	(segment
		(start 314.66282 -325.496682)
		(end 310.609488 -321.44335)
		(width 0.254)
		(layer "B.Cu")
		(net "PWM_BMC_B_ZONE_D")
	)
	(segment
		(start 197.634098 -310.009794)
		(end 197.253098 -309.628794)
		(width 0.254)
		(layer "B.Cu")
		(net "PWM_BMC_B_ZONE_D")
	)
	(segment
		(start 314.66282 -328.303382)
		(end 314.66282 -325.496682)
		(width 0.254)
		(layer "B.Cu")
		(net "PWM_BMC_B_ZONE_D")
	)
	(segment
		(start 197.253098 -309.628794)
		(end 196.240654 -309.628794)
		(width 0.254)
		(layer "B.Cu")
		(net "PWM_BMC_B_ZONE_D")
	)
	(segment
		(start 198.145654 -310.455818)
		(end 197.69963 -310.009794)
		(width 0.254)
		(layer "B.Cu")
		(net "PWM_BMC_B_ZONE_D")
	)
	(segment
		(start 310.609488 -321.44335)
		(end 234.619292 -321.44335)
		(width 0.254)
		(layer "B.Cu")
		(net "PWM_BMC_B_ZONE_D")
	)
	(segment
		(start 195.478654 -302.368712)
		(end 204.38618 -293.461186)
		(width 0.254)
		(layer "In2.Cu")
		(net "PWM_BMC_B_ZONE_D")
	)
	(segment
		(start 210.393534 -152.798526)
		(end 210.393534 -137.127996)
		(width 0.254)
		(layer "In2.Cu")
		(net "PWM_BMC_B_ZONE_D")
	)
	(segment
		(start 204.832458 -293.015162)
		(end 204.832458 -252.803406)
		(width 0.254)
		(layer "In2.Cu")
		(net "PWM_BMC_B_ZONE_D")
	)
	(segment
		(start 209.220054 -217.573098)
		(end 210.142836 -216.650316)
		(width 0.254)
		(layer "In2.Cu")
		(net "PWM_BMC_B_ZONE_D")
	)
	(segment
		(start 204.38618 -293.461186)
		(end 204.386434 -293.461186)
		(width 0.254)
		(layer "In2.Cu")
		(net "PWM_BMC_B_ZONE_D")
	)
	(segment
		(start 208.575656 -135.310372)
		(end 208.575656 -134.089902)
		(width 0.254)
		(layer "In2.Cu")
		(net "PWM_BMC_B_ZONE_D")
	)
	(segment
		(start 204.832712 -246.081296)
		(end 204.832458 -246.081042)
		(width 0.254)
		(layer "In2.Cu")
		(net "PWM_BMC_B_ZONE_D")
	)
	(segment
		(start 205.651608 -237.400592)
		(end 206.308706 -236.743494)
		(width 0.254)
		(layer "In2.Cu")
		(net "PWM_BMC_B_ZONE_D")
	)
	(segment
		(start 209.2198 -218.726512)
		(end 209.220054 -218.726258)
		(width 0.254)
		(layer "In2.Cu")
		(net "PWM_BMC_B_ZONE_D")
	)
	(segment
		(start 204.832458 -246.012462)
		(end 205.651608 -245.193312)
		(width 0.254)
		(layer "In2.Cu")
		(net "PWM_BMC_B_ZONE_D")
	)
	(segment
		(start 206.656178 -71.543926)
		(end 210.000088 -68.200016)
		(width 0.254)
		(layer "In2.Cu")
		(net "PWM_BMC_B_ZONE_D")
	)
	(segment
		(start 210.955382 -203.176632)
		(end 210.37804 -202.59929)
		(width 0.254)
		(layer "In2.Cu")
		(net "PWM_BMC_B_ZONE_D")
	)
	(segment
		(start 208.575402 -134.089648)
		(end 208.575402 -112.058196)
		(width 0.254)
		(layer "In2.Cu")
		(net "PWM_BMC_B_ZONE_D")
	)
	(segment
		(start 210.142836 -216.650316)
		(end 210.142836 -211.525612)
		(width 0.254)
		(layer "In2.Cu")
		(net "PWM_BMC_B_ZONE_D")
	)
	(segment
		(start 209.220054 -218.726258)
		(end 209.220054 -217.573098)
		(width 0.254)
		(layer "In2.Cu")
		(net "PWM_BMC_B_ZONE_D")
	)
	(segment
		(start 204.832458 -246.081042)
		(end 204.832458 -246.012462)
		(width 0.254)
		(layer "In2.Cu")
		(net "PWM_BMC_B_ZONE_D")
	)
	(segment
		(start 206.308706 -232.856786)
		(end 209.2198 -229.945692)
		(width 0.254)
		(layer "In2.Cu")
		(net "PWM_BMC_B_ZONE_D")
	)
	(segment
		(start 204.386434 -293.461186)
		(end 204.832458 -293.015162)
		(width 0.254)
		(layer "In2.Cu")
		(net "PWM_BMC_B_ZONE_D")
	)
	(segment
		(start 206.308706 -236.743494)
		(end 206.308706 -232.856786)
		(width 0.254)
		(layer "In2.Cu")
		(net "PWM_BMC_B_ZONE_D")
	)
	(segment
		(start 209.718148 -157.787594)
		(end 208.576164 -156.64561)
		(width 0.254)
		(layer "In2.Cu")
		(net "PWM_BMC_B_ZONE_D")
	)
	(segment
		(start 208.575656 -134.089902)
		(end 208.575402 -134.089648)
		(width 0.254)
		(layer "In2.Cu")
		(net "PWM_BMC_B_ZONE_D")
	)
	(segment
		(start 210.142836 -211.525612)
		(end 210.955382 -210.713066)
		(width 0.254)
		(layer "In2.Cu")
		(net "PWM_BMC_B_ZONE_D")
	)
	(segment
		(start 209.94751 -136.681972)
		(end 209.947256 -136.681972)
		(width 0.254)
		(layer "In2.Cu")
		(net "PWM_BMC_B_ZONE_D")
	)
	(segment
		(start 195.478654 -308.866794)
		(end 195.478654 -302.368712)
		(width 0.254)
		(layer "In2.Cu")
		(net "PWM_BMC_B_ZONE_D")
	)
	(segment
		(start 205.651608 -245.193312)
		(end 205.651608 -237.400592)
		(width 0.254)
		(layer "In2.Cu")
		(net "PWM_BMC_B_ZONE_D")
	)
	(segment
		(start 204.832712 -252.803152)
		(end 204.832712 -246.081296)
		(width 0.254)
		(layer "In2.Cu")
		(net "PWM_BMC_B_ZONE_D")
	)
	(segment
		(start 210.37804 -202.59929)
		(end 210.37804 -167.002206)
		(width 0.254)
		(layer "In2.Cu")
		(net "PWM_BMC_B_ZONE_D")
	)
	(segment
		(start 208.576164 -154.615896)
		(end 210.393534 -152.798526)
		(width 0.254)
		(layer "In2.Cu")
		(net "PWM_BMC_B_ZONE_D")
	)
	(segment
		(start 210.37804 -167.002206)
		(end 209.718148 -166.342314)
		(width 0.254)
		(layer "In2.Cu")
		(net "PWM_BMC_B_ZONE_D")
	)
	(segment
		(start 209.718148 -166.342314)
		(end 209.718148 -157.787594)
		(width 0.254)
		(layer "In2.Cu")
		(net "PWM_BMC_B_ZONE_D")
	)
	(segment
		(start 210.393534 -137.127996)
		(end 209.94751 -136.681972)
		(width 0.254)
		(layer "In2.Cu")
		(net "PWM_BMC_B_ZONE_D")
	)
	(segment
		(start 196.240654 -309.628794)
		(end 195.478654 -308.866794)
		(width 0.254)
		(layer "In2.Cu")
		(net "PWM_BMC_B_ZONE_D")
	)
	(segment
		(start 208.576164 -156.64561)
		(end 208.576164 -154.615896)
		(width 0.254)
		(layer "In2.Cu")
		(net "PWM_BMC_B_ZONE_D")
	)
	(segment
		(start 204.832458 -252.803406)
		(end 204.832712 -252.803152)
		(width 0.254)
		(layer "In2.Cu")
		(net "PWM_BMC_B_ZONE_D")
	)
	(segment
		(start 210.955382 -210.713066)
		(end 210.955382 -203.176632)
		(width 0.254)
		(layer "In2.Cu")
		(net "PWM_BMC_B_ZONE_D")
	)
	(segment
		(start 209.2198 -229.945692)
		(end 209.2198 -218.726512)
		(width 0.254)
		(layer "In2.Cu")
		(net "PWM_BMC_B_ZONE_D")
	)
	(segment
		(start 209.947256 -136.681972)
		(end 208.575656 -135.310372)
		(width 0.254)
		(layer "In2.Cu")
		(net "PWM_BMC_B_ZONE_D")
	)
	(segment
		(start 206.656178 -110.138972)
		(end 206.656178 -71.543926)
		(width 0.254)
		(layer "In2.Cu")
		(net "PWM_BMC_B_ZONE_D")
	)
	(segment
		(start 208.575402 -112.058196)
		(end 206.656178 -110.138972)
		(width 0.254)
		(layer "In2.Cu")
		(net "PWM_BMC_B_ZONE_D")
	)
	(segment
		(start 306.228496 -328.303382)
		(end 305.408076 -328.303382)
		(width 0.254)
		(layer "F.Cu")
		(net "PWM_BMC_B_ZONE_C")
	)
	(segment
		(start 305.408076 -328.303382)
		(end 305.408076 -329.79741)
		(width 0.254)
		(layer "F.Cu")
		(net "PWM_BMC_B_ZONE_C")
	)
	(segment
		(start 305.408076 -329.79741)
		(end 305.408076 -331.910182)
		(width 0.254)
		(layer "F.Cu")
		(net "PWM_BMC_B_ZONE_C")
	)
	(via
		(at 305.408076 -329.79741)
		(size 0.6604)
		(drill 0.3302)
		(layers "F.Cu" "B.Cu")
		(net "PWM_BMC_B_ZONE_C")
	)
	(via
		(at 196.240654 -310.771794)
		(size 0.5588)
		(drill 0.3048)
		(layers "F.Cu" "B.Cu")
		(net "PWM_BMC_B_ZONE_C")
	)
	(via
		(at 306.228496 -328.303382)
		(size 0.5588)
		(drill 0.3048)
		(layers "F.Cu" "B.Cu")
		(net "PWM_BMC_B_ZONE_C")
	)
	(segment
		(start 306.228496 -328.303382)
		(end 306.228496 -325.718932)
		(width 0.254)
		(layer "B.Cu")
		(net "PWM_BMC_B_ZONE_C")
	)
	(segment
		(start 232.15092 -321.130422)
		(end 204.884274 -321.130422)
		(width 0.254)
		(layer "B.Cu")
		(net "PWM_BMC_B_ZONE_C")
	)
	(segment
		(start 303.476914 -322.96735)
		(end 233.987848 -322.96735)
		(width 0.254)
		(layer "B.Cu")
		(net "PWM_BMC_B_ZONE_C")
	)
	(segment
		(start 306.228496 -325.718932)
		(end 303.476914 -322.96735)
		(width 0.254)
		(layer "B.Cu")
		(net "PWM_BMC_B_ZONE_C")
	)
	(segment
		(start 196.240654 -312.486802)
		(end 196.240654 -310.771794)
		(width 0.254)
		(layer "B.Cu")
		(net "PWM_BMC_B_ZONE_C")
	)
	(segment
		(start 233.987848 -322.96735)
		(end 232.15092 -321.130422)
		(width 0.254)
		(layer "B.Cu")
		(net "PWM_BMC_B_ZONE_C")
	)
	(segment
		(start 204.884274 -321.130422)
		(end 196.240654 -312.486802)
		(width 0.254)
		(layer "B.Cu")
		(net "PWM_BMC_B_ZONE_C")
	)
	(segment
		(start 208.4578 -222.557848)
		(end 208.4578 -217.985086)
		(width 0.254)
		(layer "In2.Cu")
		(net "PWM_BMC_B_ZONE_C")
	)
	(segment
		(start 204.070458 -245.69674)
		(end 204.889608 -244.87759)
		(width 0.254)
		(layer "In2.Cu")
		(net "PWM_BMC_B_ZONE_C")
	)
	(segment
		(start 208.956148 -166.658036)
		(end 208.956148 -158.103316)
		(width 0.254)
		(layer "In2.Cu")
		(net "PWM_BMC_B_ZONE_C")
	)
	(segment
		(start 204.070712 -252.48743)
		(end 204.070712 -246.397018)
		(width 0.254)
		(layer "In2.Cu")
		(net "PWM_BMC_B_ZONE_C")
	)
	(segment
		(start 208.458054 -217.257376)
		(end 209.27568 -216.43975)
		(width 0.254)
		(layer "In2.Cu")
		(net "PWM_BMC_B_ZONE_C")
	)
	(segment
		(start 209.61604 -167.317928)
		(end 208.956148 -166.658036)
		(width 0.254)
		(layer "In2.Cu")
		(net "PWM_BMC_B_ZONE_C")
	)
	(segment
		(start 207.814164 -154.300174)
		(end 209.631534 -152.482804)
		(width 0.254)
		(layer "In2.Cu")
		(net "PWM_BMC_B_ZONE_C")
	)
	(segment
		(start 209.27568 -216.43975)
		(end 209.27568 -210.20405)
		(width 0.254)
		(layer "In2.Cu")
		(net "PWM_BMC_B_ZONE_C")
	)
	(segment
		(start 205.546706 -225.468942)
		(end 208.4578 -222.557848)
		(width 0.254)
		(layer "In2.Cu")
		(net "PWM_BMC_B_ZONE_C")
	)
	(segment
		(start 196.240654 -310.771794)
		(end 194.716654 -309.247794)
		(width 0.254)
		(layer "In2.Cu")
		(net "PWM_BMC_B_ZONE_C")
	)
	(segment
		(start 209.27568 -210.20405)
		(end 210.193382 -209.286348)
		(width 0.254)
		(layer "In2.Cu")
		(net "PWM_BMC_B_ZONE_C")
	)
	(segment
		(start 205.894178 -110.454694)
		(end 205.894178 -70.905878)
		(width 0.254)
		(layer "In2.Cu")
		(net "PWM_BMC_B_ZONE_C")
	)
	(segment
		(start 207.814164 -156.961332)
		(end 207.814164 -154.300174)
		(width 0.254)
		(layer "In2.Cu")
		(net "PWM_BMC_B_ZONE_C")
	)
	(segment
		(start 204.889608 -237.028482)
		(end 205.546706 -236.371384)
		(width 0.254)
		(layer "In2.Cu")
		(net "PWM_BMC_B_ZONE_C")
	)
	(segment
		(start 208.458054 -217.984832)
		(end 208.458054 -217.257376)
		(width 0.254)
		(layer "In2.Cu")
		(net "PWM_BMC_B_ZONE_C")
	)
	(segment
		(start 207.813656 -134.405624)
		(end 207.813402 -134.40537)
		(width 0.254)
		(layer "In2.Cu")
		(net "PWM_BMC_B_ZONE_C")
	)
	(segment
		(start 194.716654 -302.05299)
		(end 204.070458 -292.699186)
		(width 0.254)
		(layer "In2.Cu")
		(net "PWM_BMC_B_ZONE_C")
	)
	(segment
		(start 208.956148 -158.103316)
		(end 207.814164 -156.961332)
		(width 0.254)
		(layer "In2.Cu")
		(net "PWM_BMC_B_ZONE_C")
	)
	(segment
		(start 205.894178 -70.905878)
		(end 210.000088 -66.799968)
		(width 0.254)
		(layer "In2.Cu")
		(net "PWM_BMC_B_ZONE_C")
	)
	(segment
		(start 204.070712 -246.397018)
		(end 204.070458 -246.396764)
		(width 0.254)
		(layer "In2.Cu")
		(net "PWM_BMC_B_ZONE_C")
	)
	(segment
		(start 204.070458 -246.396764)
		(end 204.070458 -245.69674)
		(width 0.254)
		(layer "In2.Cu")
		(net "PWM_BMC_B_ZONE_C")
	)
	(segment
		(start 210.193382 -209.286348)
		(end 210.193382 -203.492354)
		(width 0.254)
		(layer "In2.Cu")
		(net "PWM_BMC_B_ZONE_C")
	)
	(segment
		(start 207.813656 -135.626094)
		(end 207.813656 -134.405624)
		(width 0.254)
		(layer "In2.Cu")
		(net "PWM_BMC_B_ZONE_C")
	)
	(segment
		(start 207.813402 -112.373918)
		(end 205.894178 -110.454694)
		(width 0.254)
		(layer "In2.Cu")
		(net "PWM_BMC_B_ZONE_C")
	)
	(segment
		(start 209.631534 -137.443972)
		(end 207.813656 -135.626094)
		(width 0.254)
		(layer "In2.Cu")
		(net "PWM_BMC_B_ZONE_C")
	)
	(segment
		(start 205.546706 -236.371384)
		(end 205.546706 -225.468942)
		(width 0.254)
		(layer "In2.Cu")
		(net "PWM_BMC_B_ZONE_C")
	)
	(segment
		(start 204.070458 -292.699186)
		(end 204.070458 -252.487684)
		(width 0.254)
		(layer "In2.Cu")
		(net "PWM_BMC_B_ZONE_C")
	)
	(segment
		(start 207.813402 -134.40537)
		(end 207.813402 -112.373918)
		(width 0.254)
		(layer "In2.Cu")
		(net "PWM_BMC_B_ZONE_C")
	)
	(segment
		(start 210.193382 -203.492354)
		(end 209.61604 -202.915012)
		(width 0.254)
		(layer "In2.Cu")
		(net "PWM_BMC_B_ZONE_C")
	)
	(segment
		(start 194.716654 -309.247794)
		(end 194.716654 -302.05299)
		(width 0.254)
		(layer "In2.Cu")
		(net "PWM_BMC_B_ZONE_C")
	)
	(segment
		(start 204.070458 -252.487684)
		(end 204.070712 -252.48743)
		(width 0.254)
		(layer "In2.Cu")
		(net "PWM_BMC_B_ZONE_C")
	)
	(segment
		(start 209.61604 -202.915012)
		(end 209.61604 -167.317928)
		(width 0.254)
		(layer "In2.Cu")
		(net "PWM_BMC_B_ZONE_C")
	)
	(segment
		(start 208.4578 -217.985086)
		(end 208.458054 -217.984832)
		(width 0.254)
		(layer "In2.Cu")
		(net "PWM_BMC_B_ZONE_C")
	)
	(segment
		(start 204.889608 -244.87759)
		(end 204.889608 -237.028482)
		(width 0.254)
		(layer "In2.Cu")
		(net "PWM_BMC_B_ZONE_C")
	)
	(segment
		(start 209.631534 -152.482804)
		(end 209.631534 -137.443972)
		(width 0.254)
		(layer "In2.Cu")
		(net "PWM_BMC_B_ZONE_C")
	)
	(segment
		(start 311.6834 -328.303382)
		(end 312.5724 -328.303382)
		(width 0.254)
		(layer "F.Cu")
		(net "PWM_BMC_A_ZONE_D")
	)
	(segment
		(start 312.5724 -331.910182)
		(end 312.5724 -329.79741)
		(width 0.254)
		(layer "F.Cu")
		(net "PWM_BMC_A_ZONE_D")
	)
	(segment
		(start 312.5724 -328.303382)
		(end 312.5724 -329.79741)
		(width 0.254)
		(layer "F.Cu")
		(net "PWM_BMC_A_ZONE_D")
	)
	(via
		(at 198.808848 -306.553616)
		(size 0.5588)
		(drill 0.3048)
		(layers "F.Cu" "B.Cu")
		(net "PWM_BMC_A_ZONE_D")
	)
	(via
		(at 311.6834 -328.303382)
		(size 0.5588)
		(drill 0.3048)
		(layers "F.Cu" "B.Cu")
		(net "PWM_BMC_A_ZONE_D")
	)
	(via
		(at 312.5724 -329.79741)
		(size 0.6604)
		(drill 0.3302)
		(layers "F.Cu" "B.Cu")
		(net "PWM_BMC_A_ZONE_D")
	)
	(segment
		(start 195.97751 -306.553616)
		(end 193.916554 -308.614572)
		(width 0.254)
		(layer "B.Cu")
		(net "PWM_BMC_A_ZONE_D")
	)
	(segment
		(start 193.916554 -308.614572)
		(end 193.916554 -313.396376)
		(width 0.254)
		(layer "B.Cu")
		(net "PWM_BMC_A_ZONE_D")
	)
	(segment
		(start 292.50259 -329.065382)
		(end 310.9214 -329.065382)
		(width 0.254)
		(layer "B.Cu")
		(net "PWM_BMC_A_ZONE_D")
	)
	(segment
		(start 204.158342 -323.638164)
		(end 231.425496 -323.638164)
		(width 0.254)
		(layer "B.Cu")
		(net "PWM_BMC_A_ZONE_D")
	)
	(segment
		(start 233.040682 -325.25335)
		(end 288.690558 -325.25335)
		(width 0.254)
		(layer "B.Cu")
		(net "PWM_BMC_A_ZONE_D")
	)
	(segment
		(start 231.425496 -323.638164)
		(end 233.040682 -325.25335)
		(width 0.254)
		(layer "B.Cu")
		(net "PWM_BMC_A_ZONE_D")
	)
	(segment
		(start 310.9214 -329.065382)
		(end 311.6834 -328.303382)
		(width 0.254)
		(layer "B.Cu")
		(net "PWM_BMC_A_ZONE_D")
	)
	(segment
		(start 193.916554 -313.396376)
		(end 204.158342 -323.638164)
		(width 0.254)
		(layer "B.Cu")
		(net "PWM_BMC_A_ZONE_D")
	)
	(segment
		(start 198.808848 -306.553616)
		(end 195.97751 -306.553616)
		(width 0.254)
		(layer "B.Cu")
		(net "PWM_BMC_A_ZONE_D")
	)
	(segment
		(start 288.690558 -325.25335)
		(end 292.50259 -329.065382)
		(width 0.254)
		(layer "B.Cu")
		(net "PWM_BMC_A_ZONE_D")
	)
	(segment
		(start 210.726528 -135.923528)
		(end 212.004148 -137.201148)
		(width 0.254)
		(layer "In2.Cu")
		(net "PWM_BMC_A_ZONE_D")
	)
	(segment
		(start 213.65845 -174.751746)
		(end 214.495126 -175.588422)
		(width 0.254)
		(layer "In2.Cu")
		(net "PWM_BMC_A_ZONE_D")
	)
	(segment
		(start 215.400128 -70.600062)
		(end 214.250524 -71.749666)
		(width 0.14605)
		(layer "In2.Cu")
		(net "PWM_BMC_A_ZONE_D")
	)
	(segment
		(start 214.395304 -219.290392)
		(end 212.232494 -221.453202)
		(width 0.254)
		(layer "In2.Cu")
		(net "PWM_BMC_A_ZONE_D")
	)
	(segment
		(start 207.773016 -247.598184)
		(end 207.773016 -292.427914)
		(width 0.254)
		(layer "In2.Cu")
		(net "PWM_BMC_A_ZONE_D")
	)
	(segment
		(start 210.725766 -112.108234)
		(end 210.725766 -116.883942)
		(width 0.254)
		(layer "In2.Cu")
		(net "PWM_BMC_A_ZONE_D")
	)
	(segment
		(start 209.273648 -238.016796)
		(end 208.998566 -238.291878)
		(width 0.254)
		(layer "In2.Cu")
		(net "PWM_BMC_A_ZONE_D")
	)
	(segment
		(start 207.773016 -294.233092)
		(end 205.604364 -296.401744)
		(width 0.254)
		(layer "In2.Cu")
		(net "PWM_BMC_A_ZONE_D")
	)
	(segment
		(start 214.495126 -175.588422)
		(end 214.495126 -211.33181)
		(width 0.254)
		(layer "In2.Cu")
		(net "PWM_BMC_A_ZONE_D")
	)
	(segment
		(start 207.773016 -294.232838)
		(end 207.773016 -294.233092)
		(width 0.254)
		(layer "In2.Cu")
		(net "PWM_BMC_A_ZONE_D")
	)
	(segment
		(start 208.998566 -238.291878)
		(end 208.998566 -246.372634)
		(width 0.254)
		(layer "In2.Cu")
		(net "PWM_BMC_A_ZONE_D")
	)
	(segment
		(start 205.604364 -296.401744)
		(end 205.60411 -296.401744)
		(width 0.254)
		(layer "In2.Cu")
		(net "PWM_BMC_A_ZONE_D")
	)
	(segment
		(start 205.60411 -296.401744)
		(end 198.808848 -303.197006)
		(width 0.254)
		(layer "In2.Cu")
		(net "PWM_BMC_A_ZONE_D")
	)
	(segment
		(start 208.998566 -246.372634)
		(end 207.773016 -247.598184)
		(width 0.254)
		(layer "In2.Cu")
		(net "PWM_BMC_A_ZONE_D")
	)
	(segment
		(start 211.362544 -83.926934)
		(end 211.362544 -111.471456)
		(width 0.254)
		(layer "In2.Cu")
		(net "PWM_BMC_A_ZONE_D")
	)
	(segment
		(start 214.395304 -216.52357)
		(end 214.395304 -219.290392)
		(width 0.254)
		(layer "In2.Cu")
		(net "PWM_BMC_A_ZONE_D")
	)
	(segment
		(start 211.362544 -111.471456)
		(end 210.725766 -112.108234)
		(width 0.254)
		(layer "In2.Cu")
		(net "PWM_BMC_A_ZONE_D")
	)
	(segment
		(start 212.004148 -137.201148)
		(end 212.004148 -165.395148)
		(width 0.254)
		(layer "In2.Cu")
		(net "PWM_BMC_A_ZONE_D")
	)
	(segment
		(start 210.725766 -116.883942)
		(end 210.726528 -116.884704)
		(width 0.254)
		(layer "In2.Cu")
		(net "PWM_BMC_A_ZONE_D")
	)
	(segment
		(start 207.77327 -294.232584)
		(end 207.773016 -294.232838)
		(width 0.254)
		(layer "In2.Cu")
		(net "PWM_BMC_A_ZONE_D")
	)
	(segment
		(start 212.232494 -235.057696)
		(end 209.273648 -238.016796)
		(width 0.254)
		(layer "In2.Cu")
		(net "PWM_BMC_A_ZONE_D")
	)
	(segment
		(start 212.004148 -165.395148)
		(end 213.65845 -167.04945)
		(width 0.254)
		(layer "In2.Cu")
		(net "PWM_BMC_A_ZONE_D")
	)
	(segment
		(start 213.760812 -215.889078)
		(end 214.395304 -216.52357)
		(width 0.254)
		(layer "In2.Cu")
		(net "PWM_BMC_A_ZONE_D")
	)
	(segment
		(start 213.760812 -212.066124)
		(end 213.760812 -215.889078)
		(width 0.254)
		(layer "In2.Cu")
		(net "PWM_BMC_A_ZONE_D")
	)
	(segment
		(start 207.77327 -292.428168)
		(end 207.77327 -294.232584)
		(width 0.254)
		(layer "In2.Cu")
		(net "PWM_BMC_A_ZONE_D")
	)
	(segment
		(start 214.495126 -211.33181)
		(end 213.760812 -212.066124)
		(width 0.254)
		(layer "In2.Cu")
		(net "PWM_BMC_A_ZONE_D")
	)
	(segment
		(start 207.773016 -292.427914)
		(end 207.77327 -292.428168)
		(width 0.254)
		(layer "In2.Cu")
		(net "PWM_BMC_A_ZONE_D")
	)
	(segment
		(start 214.048848 -81.24063)
		(end 211.362544 -83.926934)
		(width 0.254)
		(layer "In2.Cu")
		(net "PWM_BMC_A_ZONE_D")
	)
	(segment
		(start 214.250524 -71.749666)
		(end 214.250524 -81.038954)
		(width 0.14605)
		(layer "In2.Cu")
		(net "PWM_BMC_A_ZONE_D")
	)
	(segment
		(start 212.232494 -221.453202)
		(end 212.232494 -235.057696)
		(width 0.254)
		(layer "In2.Cu")
		(net "PWM_BMC_A_ZONE_D")
	)
	(segment
		(start 198.808848 -303.197006)
		(end 198.808848 -306.553616)
		(width 0.254)
		(layer "In2.Cu")
		(net "PWM_BMC_A_ZONE_D")
	)
	(segment
		(start 214.250524 -81.038954)
		(end 214.048848 -81.24063)
		(width 0.14605)
		(layer "In2.Cu")
		(net "PWM_BMC_A_ZONE_D")
	)
	(segment
		(start 210.726528 -116.884704)
		(end 210.726528 -135.923528)
		(width 0.254)
		(layer "In2.Cu")
		(net "PWM_BMC_A_ZONE_D")
	)
	(segment
		(start 213.65845 -167.04945)
		(end 213.65845 -174.751746)
		(width 0.254)
		(layer "In2.Cu")
		(net "PWM_BMC_A_ZONE_D")
	)
	(segment
		(start 304.138076 -328.303382)
		(end 304.138076 -329.79741)
		(width 0.254)
		(layer "F.Cu")
		(net "PWM_BMC_A_ZONE_C")
	)
	(segment
		(start 304.138076 -329.79741)
		(end 304.138076 -331.910182)
		(width 0.254)
		(layer "F.Cu")
		(net "PWM_BMC_A_ZONE_C")
	)
	(segment
		(start 303.249076 -328.303382)
		(end 304.138076 -328.303382)
		(width 0.254)
		(layer "F.Cu")
		(net "PWM_BMC_A_ZONE_C")
	)
	(via
		(at 304.138076 -329.79741)
		(size 0.6604)
		(drill 0.3302)
		(layers "F.Cu" "B.Cu")
		(net "PWM_BMC_A_ZONE_C")
	)
	(via
		(at 198.808848 -307.696616)
		(size 0.5588)
		(drill 0.3048)
		(layers "F.Cu" "B.Cu")
		(net "PWM_BMC_A_ZONE_C")
	)
	(via
		(at 303.249076 -328.303382)
		(size 0.5588)
		(drill 0.3048)
		(layers "F.Cu" "B.Cu")
		(net "PWM_BMC_A_ZONE_C")
	)
	(segment
		(start 195.912232 -307.696616)
		(end 198.808848 -307.696616)
		(width 0.254)
		(layer "B.Cu")
		(net "PWM_BMC_A_ZONE_C")
	)
	(segment
		(start 231.519476 -322.654422)
		(end 204.25283 -322.654422)
		(width 0.254)
		(layer "B.Cu")
		(net "PWM_BMC_A_ZONE_C")
	)
	(segment
		(start 194.678554 -313.080654)
		(end 194.678554 -308.930294)
		(width 0.254)
		(layer "B.Cu")
		(net "PWM_BMC_A_ZONE_C")
	)
	(segment
		(start 194.678554 -308.930294)
		(end 195.912232 -307.696616)
		(width 0.254)
		(layer "B.Cu")
		(net "PWM_BMC_A_ZONE_C")
	)
	(segment
		(start 204.25283 -322.654422)
		(end 204.197712 -322.599304)
		(width 0.254)
		(layer "B.Cu")
		(net "PWM_BMC_A_ZONE_C")
	)
	(segment
		(start 303.249076 -328.303382)
		(end 294.216582 -328.303382)
		(width 0.254)
		(layer "B.Cu")
		(net "PWM_BMC_A_ZONE_C")
	)
	(segment
		(start 233.356404 -324.49135)
		(end 231.519476 -322.654422)
		(width 0.254)
		(layer "B.Cu")
		(net "PWM_BMC_A_ZONE_C")
	)
	(segment
		(start 294.216582 -328.303382)
		(end 290.40455 -324.49135)
		(width 0.254)
		(layer "B.Cu")
		(net "PWM_BMC_A_ZONE_C")
	)
	(segment
		(start 290.40455 -324.49135)
		(end 233.356404 -324.49135)
		(width 0.254)
		(layer "B.Cu")
		(net "PWM_BMC_A_ZONE_C")
	)
	(segment
		(start 204.078586 -322.480432)
		(end 204.078332 -322.480432)
		(width 0.254)
		(layer "B.Cu")
		(net "PWM_BMC_A_ZONE_C")
	)
	(segment
		(start 204.197458 -322.599304)
		(end 204.078586 -322.480432)
		(width 0.254)
		(layer "B.Cu")
		(net "PWM_BMC_A_ZONE_C")
	)
	(segment
		(start 204.078332 -322.480432)
		(end 194.678554 -313.080654)
		(width 0.254)
		(layer "B.Cu")
		(net "PWM_BMC_A_ZONE_C")
	)
	(segment
		(start 204.197712 -322.599304)
		(end 204.197458 -322.599304)
		(width 0.254)
		(layer "B.Cu")
		(net "PWM_BMC_A_ZONE_C")
	)
	(segment
		(start 215.400128 -69.200014)
		(end 216.561162 -70.361048)
		(width 0.14605)
		(layer "In2.Cu")
		(net "PWM_BMC_A_ZONE_C")
	)
	(segment
		(start 214.522812 -215.573102)
		(end 215.157304 -216.207594)
		(width 0.254)
		(layer "In2.Cu")
		(net "PWM_BMC_A_ZONE_C")
	)
	(segment
		(start 212.994494 -235.373418)
		(end 210.035902 -238.332264)
		(width 0.254)
		(layer "In2.Cu")
		(net "PWM_BMC_A_ZONE_C")
	)
	(segment
		(start 215.157304 -219.606114)
		(end 212.994494 -221.768924)
		(width 0.254)
		(layer "In2.Cu")
		(net "PWM_BMC_A_ZONE_C")
	)
	(segment
		(start 211.3788 -290.539678)
		(end 210.768946 -291.149532)
		(width 0.254)
		(layer "In2.Cu")
		(net "PWM_BMC_A_ZONE_C")
	)
	(segment
		(start 210.035902 -248.339102)
		(end 211.3788 -249.682)
		(width 0.254)
		(layer "In2.Cu")
		(net "PWM_BMC_A_ZONE_C")
	)
	(segment
		(start 213.210648 -161.097214)
		(end 213.210648 -164.24783)
		(width 0.254)
		(layer "In2.Cu")
		(net "PWM_BMC_A_ZONE_C")
	)
	(segment
		(start 213.210394 -164.248084)
		(end 213.210394 -164.834316)
		(width 0.254)
		(layer "In2.Cu")
		(net "PWM_BMC_A_ZONE_C")
	)
	(segment
		(start 210.768946 -291.149532)
		(end 210.768946 -292.328854)
		(width 0.254)
		(layer "In2.Cu")
		(net "PWM_BMC_A_ZONE_C")
	)
	(segment
		(start 217.005916 -83.683094)
		(end 213.560152 -87.128858)
		(width 0.254)
		(layer "In2.Cu")
		(net "PWM_BMC_A_ZONE_C")
	)
	(segment
		(start 217.005916 -80.861916)
		(end 217.005916 -81.103978)
		(width 0.14605)
		(layer "In2.Cu")
		(net "PWM_BMC_A_ZONE_C")
	)
	(segment
		(start 213.210394 -164.834316)
		(end 213.210648 -164.83457)
		(width 0.254)
		(layer "In2.Cu")
		(net "PWM_BMC_A_ZONE_C")
	)
	(segment
		(start 213.210648 -164.83457)
		(end 213.210648 -164.925248)
		(width 0.254)
		(layer "In2.Cu")
		(net "PWM_BMC_A_ZONE_C")
	)
	(segment
		(start 214.522812 -212.381846)
		(end 214.522812 -215.573102)
		(width 0.254)
		(layer "In2.Cu")
		(net "PWM_BMC_A_ZONE_C")
	)
	(segment
		(start 213.560152 -112.775746)
		(end 212.842602 -113.493296)
		(width 0.254)
		(layer "In2.Cu")
		(net "PWM_BMC_A_ZONE_C")
	)
	(segment
		(start 212.842602 -160.729168)
		(end 213.210648 -161.097214)
		(width 0.254)
		(layer "In2.Cu")
		(net "PWM_BMC_A_ZONE_C")
	)
	(segment
		(start 212.842602 -113.493296)
		(end 212.842602 -160.729168)
		(width 0.254)
		(layer "In2.Cu")
		(net "PWM_BMC_A_ZONE_C")
	)
	(segment
		(start 213.560152 -87.128858)
		(end 213.560152 -112.775746)
		(width 0.254)
		(layer "In2.Cu")
		(net "PWM_BMC_A_ZONE_C")
	)
	(segment
		(start 216.561162 -70.361048)
		(end 216.561162 -80.417162)
		(width 0.14605)
		(layer "In2.Cu")
		(net "PWM_BMC_A_ZONE_C")
	)
	(segment
		(start 215.157304 -216.207594)
		(end 215.157304 -219.606114)
		(width 0.254)
		(layer "In2.Cu")
		(net "PWM_BMC_A_ZONE_C")
	)
	(segment
		(start 211.3788 -249.682)
		(end 211.3788 -290.539678)
		(width 0.254)
		(layer "In2.Cu")
		(net "PWM_BMC_A_ZONE_C")
	)
	(segment
		(start 216.561162 -80.417162)
		(end 217.005916 -80.861916)
		(width 0.14605)
		(layer "In2.Cu")
		(net "PWM_BMC_A_ZONE_C")
	)
	(segment
		(start 215.257126 -175.2727)
		(end 215.257126 -211.647532)
		(width 0.254)
		(layer "In2.Cu")
		(net "PWM_BMC_A_ZONE_C")
	)
	(segment
		(start 210.768946 -292.328854)
		(end 199.783192 -303.314608)
		(width 0.254)
		(layer "In2.Cu")
		(net "PWM_BMC_A_ZONE_C")
	)
	(segment
		(start 213.210648 -164.24783)
		(end 213.210394 -164.248084)
		(width 0.254)
		(layer "In2.Cu")
		(net "PWM_BMC_A_ZONE_C")
	)
	(segment
		(start 212.994494 -221.768924)
		(end 212.994494 -235.373418)
		(width 0.254)
		(layer "In2.Cu")
		(net "PWM_BMC_A_ZONE_C")
	)
	(segment
		(start 215.257126 -211.647532)
		(end 214.522812 -212.381846)
		(width 0.254)
		(layer "In2.Cu")
		(net "PWM_BMC_A_ZONE_C")
	)
	(segment
		(start 213.210648 -164.925248)
		(end 214.42045 -166.13505)
		(width 0.254)
		(layer "In2.Cu")
		(net "PWM_BMC_A_ZONE_C")
	)
	(segment
		(start 214.42045 -174.436024)
		(end 215.257126 -175.2727)
		(width 0.254)
		(layer "In2.Cu")
		(net "PWM_BMC_A_ZONE_C")
	)
	(segment
		(start 199.783192 -303.314608)
		(end 199.783192 -306.722272)
		(width 0.254)
		(layer "In2.Cu")
		(net "PWM_BMC_A_ZONE_C")
	)
	(segment
		(start 199.783192 -306.722272)
		(end 198.808848 -307.696616)
		(width 0.254)
		(layer "In2.Cu")
		(net "PWM_BMC_A_ZONE_C")
	)
	(segment
		(start 210.035902 -238.332264)
		(end 210.035902 -248.339102)
		(width 0.254)
		(layer "In2.Cu")
		(net "PWM_BMC_A_ZONE_C")
	)
	(segment
		(start 214.42045 -166.13505)
		(end 214.42045 -174.436024)
		(width 0.254)
		(layer "In2.Cu")
		(net "PWM_BMC_A_ZONE_C")
	)
	(segment
		(start 217.005916 -81.103978)
		(end 217.005916 -83.683094)
		(width 0.254)
		(layer "In2.Cu")
		(net "PWM_BMC_A_ZONE_C")
	)
	(segment
		(start 258.7498 -224.409)
		(end 259.461 -225.1202)
		(width 0.254)
		(layer "F.Cu")
		(net "P5V_B_4_SENSE")
	)
	(segment
		(start 262.46201 -226.271074)
		(end 262.382 -226.191064)
		(width 0.254)
		(layer "F.Cu")
		(net "P5V_B_4_SENSE")
	)
	(segment
		(start 257.683 -224.409)
		(end 258.7498 -224.409)
		(width 0.254)
		(layer "F.Cu")
		(net "P5V_B_4_SENSE")
	)
	(segment
		(start 257.34772 -224.07372)
		(end 257.683 -224.409)
		(width 0.254)
		(layer "F.Cu")
		(net "P5V_B_4_SENSE")
	)
	(segment
		(start 262.382 -226.191064)
		(end 262.382 -225.4504)
		(width 0.254)
		(layer "F.Cu")
		(net "P5V_B_4_SENSE")
	)
	(segment
		(start 259.461 -225.1202)
		(end 259.461 -225.171)
		(width 0.254)
		(layer "F.Cu")
		(net "P5V_B_4_SENSE")
	)
	(segment
		(start 262.161274 -225.229674)
		(end 261.75081 -225.229674)
		(width 0.254)
		(layer "F.Cu")
		(net "P5V_B_4_SENSE")
	)
	(segment
		(start 262.382 -225.4504)
		(end 262.161274 -225.229674)
		(width 0.254)
		(layer "F.Cu")
		(net "P5V_B_4_SENSE")
	)
	(segment
		(start 259.519674 -225.229674)
		(end 259.461 -225.171)
		(width 0.254)
		(layer "F.Cu")
		(net "P5V_B_4_SENSE")
	)
	(segment
		(start 257.34772 -223.09582)
		(end 257.34772 -224.07372)
		(width 0.254)
		(layer "F.Cu")
		(net "P5V_B_4_SENSE")
	)
	(segment
		(start 260.73481 -225.229674)
		(end 259.519674 -225.229674)
		(width 0.254)
		(layer "F.Cu")
		(net "P5V_B_4_SENSE")
	)
	(segment
		(start 261.75081 -225.229674)
		(end 260.73481 -225.229674)
		(width 0.254)
		(layer "F.Cu")
		(net "P5V_B_4_SENSE")
	)
	(via
		(at 259.461 -225.171)
		(size 0.6604)
		(drill 0.3302)
		(layers "F.Cu" "B.Cu")
		(net "P5V_B_4_SENSE")
	)
	(segment
		(start 256.69748 -223.09582)
		(end 256.69748 -224.18548)
		(width 0.254)
		(layer "F.Cu")
		(net "P5V_B_3_SENSE")
	)
	(segment
		(start 257.683 -225.171)
		(end 258.1656 -225.171)
		(width 0.254)
		(layer "F.Cu")
		(net "P5V_B_3_SENSE")
	)
	(segment
		(start 258.645406 -228.84511)
		(end 258.645406 -227.82911)
		(width 0.254)
		(layer "F.Cu")
		(net "P5V_B_3_SENSE")
	)
	(segment
		(start 256.69748 -224.18548)
		(end 257.683 -225.171)
		(width 0.254)
		(layer "F.Cu")
		(net "P5V_B_3_SENSE")
	)
	(segment
		(start 258.1656 -225.171)
		(end 258.669282 -225.674682)
		(width 0.254)
		(layer "F.Cu")
		(net "P5V_B_3_SENSE")
	)
	(segment
		(start 258.669282 -227.805234)
		(end 258.669282 -226.81311)
		(width 0.254)
		(layer "F.Cu")
		(net "P5V_B_3_SENSE")
	)
	(segment
		(start 258.669282 -225.674682)
		(end 258.669282 -226.81311)
		(width 0.254)
		(layer "F.Cu")
		(net "P5V_B_3_SENSE")
	)
	(segment
		(start 258.645406 -227.82911)
		(end 258.669282 -227.805234)
		(width 0.254)
		(layer "F.Cu")
		(net "P5V_B_3_SENSE")
	)
	(via
		(at 258.1656 -225.171)
		(size 0.6604)
		(drill 0.3302)
		(layers "F.Cu" "B.Cu")
		(net "P5V_B_3_SENSE")
	)
	(segment
		(start 256.039874 -228.36505)
		(end 256.039874 -227.35667)
		(width 0.254)
		(layer "F.Cu")
		(net "P5V_B_2_SENSE")
	)
	(segment
		(start 256.4892 -224.8408)
		(end 256.4892 -225.3234)
		(width 0.254)
		(layer "F.Cu")
		(net "P5V_B_2_SENSE")
	)
	(segment
		(start 256.04724 -223.09582)
		(end 256.04724 -224.39884)
		(width 0.254)
		(layer "F.Cu")
		(net "P5V_B_2_SENSE")
	)
	(segment
		(start 256.4892 -225.3234)
		(end 256.4892 -225.9076)
		(width 0.254)
		(layer "F.Cu")
		(net "P5V_B_2_SENSE")
	)
	(segment
		(start 256.055114 -226.341686)
		(end 256.055114 -227.34143)
		(width 0.254)
		(layer "F.Cu")
		(net "P5V_B_2_SENSE")
	)
	(segment
		(start 256.039874 -229.38105)
		(end 256.039874 -228.36505)
		(width 0.254)
		(layer "F.Cu")
		(net "P5V_B_2_SENSE")
	)
	(segment
		(start 256.04724 -224.39884)
		(end 256.4892 -224.8408)
		(width 0.254)
		(layer "F.Cu")
		(net "P5V_B_2_SENSE")
	)
	(segment
		(start 256.039874 -227.35667)
		(end 256.055114 -227.34143)
		(width 0.254)
		(layer "F.Cu")
		(net "P5V_B_2_SENSE")
	)
	(segment
		(start 256.4892 -225.9076)
		(end 256.055114 -226.341686)
		(width 0.254)
		(layer "F.Cu")
		(net "P5V_B_2_SENSE")
	)
	(via
		(at 256.4892 -225.3234)
		(size 0.6604)
		(drill 0.3302)
		(layers "F.Cu" "B.Cu")
		(net "P5V_B_2_SENSE")
	)
	(segment
		(start 255.030478 -227.34905)
		(end 255.030478 -225.937572)
		(width 0.254)
		(layer "F.Cu")
		(net "P5V_B_1_SENSE")
	)
	(segment
		(start 255.030478 -229.38105)
		(end 255.030478 -228.36505)
		(width 0.254)
		(layer "F.Cu")
		(net "P5V_B_1_SENSE")
	)
	(segment
		(start 255.397 -223.09582)
		(end 255.397 -225.57105)
		(width 0.254)
		(layer "F.Cu")
		(net "P5V_B_1_SENSE")
	)
	(segment
		(start 255.030478 -228.36505)
		(end 255.030478 -227.34905)
		(width 0.254)
		(layer "F.Cu")
		(net "P5V_B_1_SENSE")
	)
	(segment
		(start 255.030478 -225.937572)
		(end 255.0922 -225.87585)
		(width 0.254)
		(layer "F.Cu")
		(net "P5V_B_1_SENSE")
	)
	(segment
		(start 255.397 -225.57105)
		(end 255.0922 -225.87585)
		(width 0.254)
		(layer "F.Cu")
		(net "P5V_B_1_SENSE")
	)
	(via
		(at 255.0922 -225.87585)
		(size 0.6604)
		(drill 0.3302)
		(layers "F.Cu" "B.Cu")
		(net "P5V_B_1_SENSE")
	)
	(segment
		(start 260.018022 -368.655346)
		(end 259.899658 -368.655346)
		(width 0.17145)
		(layer "F.Cu")
		(net "MB3_SDA_R")
	)
	(segment
		(start 259.899658 -368.655346)
		(end 258.609592 -367.36528)
		(width 0.17145)
		(layer "F.Cu")
		(net "MB3_SDA_R")
	)
	(segment
		(start 258.303522 -367.36528)
		(end 255.827022 -367.36528)
		(width 0.17145)
		(layer "F.Cu")
		(net "MB3_SDA_R")
	)
	(segment
		(start 258.609592 -367.36528)
		(end 258.303522 -367.36528)
		(width 0.17145)
		(layer "F.Cu")
		(net "MB3_SDA_R")
	)
	(via
		(at 258.303522 -367.36528)
		(size 0.6604)
		(drill 0.3302)
		(layers "F.Cu" "B.Cu")
		(net "MB3_SDA_R")
	)
	(segment
		(start 256.116582 -367.865406)
		(end 257.160522 -368.909346)
		(width 0.17145)
		(layer "F.Cu")
		(net "MB3_SCL_R")
	)
	(segment
		(start 259.129022 -368.909346)
		(end 257.922522 -368.909346)
		(width 0.17145)
		(layer "F.Cu")
		(net "MB3_SCL_R")
	)
	(segment
		(start 260.018022 -369.798346)
		(end 259.129022 -368.909346)
		(width 0.17145)
		(layer "F.Cu")
		(net "MB3_SCL_R")
	)
	(segment
		(start 257.160522 -368.909346)
		(end 257.922522 -368.909346)
		(width 0.17145)
		(layer "F.Cu")
		(net "MB3_SCL_R")
	)
	(segment
		(start 255.903222 -367.865406)
		(end 256.116582 -367.865406)
		(width 0.17145)
		(layer "F.Cu")
		(net "MB3_SCL_R")
	)
	(via
		(at 257.922522 -368.909346)
		(size 0.6604)
		(drill 0.3302)
		(layers "F.Cu" "B.Cu")
		(net "MB3_SCL_R")
	)
	(segment
		(start 180.666136 -370.438934)
		(end 180.686202 -370.459)
		(width 0.17145)
		(layer "F.Cu")
		(net "MB0_SDA_R")
	)
	(segment
		(start 177.7365 -370.438934)
		(end 180.666136 -370.438934)
		(width 0.17145)
		(layer "F.Cu")
		(net "MB0_SDA_R")
	)
	(segment
		(start 181.9275 -370.459)
		(end 180.686202 -370.459)
		(width 0.17145)
		(layer "F.Cu")
		(net "MB0_SDA_R")
	)
	(via
		(at 180.686202 -370.459)
		(size 0.6604)
		(drill 0.3302)
		(layers "F.Cu" "B.Cu")
		(net "MB0_SDA_R")
	)
	(segment
		(start 177.8127 -371.166644)
		(end 178.248056 -371.602)
		(width 0.17145)
		(layer "F.Cu")
		(net "MB0_SCL_R")
	)
	(segment
		(start 178.248056 -371.602)
		(end 179.197 -371.602)
		(width 0.17145)
		(layer "F.Cu")
		(net "MB0_SCL_R")
	)
	(segment
		(start 177.8127 -370.93906)
		(end 177.8127 -371.166644)
		(width 0.17145)
		(layer "F.Cu")
		(net "MB0_SCL_R")
	)
	(segment
		(start 179.197 -371.602)
		(end 181.9275 -371.602)
		(width 0.17145)
		(layer "F.Cu")
		(net "MB0_SCL_R")
	)
	(via
		(at 179.197 -371.602)
		(size 0.6604)
		(drill 0.3302)
		(layers "F.Cu" "B.Cu")
		(net "MB0_SCL_R")
	)
	(segment
		(start 260.470396 -277.869396)
		(end 261.874 -279.273)
		(width 0.254)
		(layer "B.Cu")
		(net "PWRGD_P3V3_STBY")
	)
	(segment
		(start 262.69315 -280.09215)
		(end 262.69315 -281.14625)
		(width 0.254)
		(layer "B.Cu")
		(net "PWRGD_P3V3_STBY")
	)
	(segment
		(start 262.69315 -281.14625)
		(end 261.950454 -281.888946)
		(width 0.254)
		(layer "B.Cu")
		(net "PWRGD_P3V3_STBY")
	)
	(segment
		(start 257.729228 -278.922734)
		(end 258.782566 -277.869396)
		(width 0.254)
		(layer "B.Cu")
		(net "PWRGD_P3V3_STBY")
	)
	(segment
		(start 257.360674 -278.922734)
		(end 257.729228 -278.922734)
		(width 0.254)
		(layer "B.Cu")
		(net "PWRGD_P3V3_STBY")
	)
	(segment
		(start 256.890266 -278.922734)
		(end 257.360674 -278.922734)
		(width 0.254)
		(layer "B.Cu")
		(net "PWRGD_P3V3_STBY")
	)
	(segment
		(start 261.950454 -281.888946)
		(end 261.045198 -281.888946)
		(width 0.254)
		(layer "B.Cu")
		(net "PWRGD_P3V3_STBY")
	)
	(segment
		(start 255.17856 -280.63444)
		(end 256.890266 -278.922734)
		(width 0.254)
		(layer "B.Cu")
		(net "PWRGD_P3V3_STBY")
	)
	(segment
		(start 261.874 -279.273)
		(end 262.69315 -280.09215)
		(width 0.254)
		(layer "B.Cu")
		(net "PWRGD_P3V3_STBY")
	)
	(segment
		(start 258.782566 -277.869396)
		(end 260.470396 -277.869396)
		(width 0.254)
		(layer "B.Cu")
		(net "PWRGD_P3V3_STBY")
	)
	(segment
		(start 255.17856 -280.769822)
		(end 255.17856 -280.63444)
		(width 0.254)
		(layer "B.Cu")
		(net "PWRGD_P3V3_STBY")
	)
	(via
		(at 54.25186 -120.469406)
		(size 0.6096)
		(drill 0.3048)
		(layers "F.Cu" "B.Cu")
		(net "P5V_B_2_VFB")
	)
	(segment
		(start 47.439072 -117.91442)
		(end 48.270922 -117.91442)
		(width 0.254)
		(layer "B.Cu")
		(net "P5V_B_2_VFB")
	)
	(segment
		(start 48.270922 -117.91442)
		(end 48.863758 -118.507256)
		(width 0.254)
		(layer "B.Cu")
		(net "P5V_B_2_VFB")
	)
	(segment
		(start 48.863758 -119.444008)
		(end 48.85436 -119.453406)
		(width 0.254)
		(layer "B.Cu")
		(net "P5V_B_2_VFB")
	)
	(segment
		(start 55.710582 -119.72671)
		(end 54.967886 -120.469406)
		(width 0.254)
		(layer "B.Cu")
		(net "P5V_B_2_VFB")
	)
	(segment
		(start 48.88738 -118.483634)
		(end 48.863758 -118.507256)
		(width 0.254)
		(layer "B.Cu")
		(net "P5V_B_2_VFB")
	)
	(segment
		(start 54.25186 -120.469406)
		(end 49.67986 -120.469406)
		(width 0.254)
		(layer "B.Cu")
		(net "P5V_B_2_VFB")
	)
	(segment
		(start 48.863758 -118.507256)
		(end 48.863758 -119.444008)
		(width 0.254)
		(layer "B.Cu")
		(net "P5V_B_2_VFB")
	)
	(segment
		(start 49.67986 -120.469406)
		(end 48.85436 -119.643906)
		(width 0.254)
		(layer "B.Cu")
		(net "P5V_B_2_VFB")
	)
	(segment
		(start 48.88738 -116.232178)
		(end 48.88738 -118.483634)
		(width 0.254)
		(layer "B.Cu")
		(net "P5V_B_2_VFB")
	)
	(segment
		(start 54.967886 -120.469406)
		(end 54.25186 -120.469406)
		(width 0.254)
		(layer "B.Cu")
		(net "P5V_B_2_VFB")
	)
	(segment
		(start 48.85436 -119.643906)
		(end 48.85436 -119.453406)
		(width 0.254)
		(layer "B.Cu")
		(net "P5V_B_2_VFB")
	)
	(via
		(at 28.641802 -231.65435)
		(size 0.6096)
		(drill 0.3048)
		(layers "F.Cu" "B.Cu")
		(net "P5V_B_1_VFB")
	)
	(segment
		(start 23.422864 -229.099364)
		(end 24.0157 -229.6922)
		(width 0.254)
		(layer "B.Cu")
		(net "P5V_B_1_VFB")
	)
	(segment
		(start 30.119828 -231.65435)
		(end 28.641802 -231.65435)
		(width 0.254)
		(layer "B.Cu")
		(net "P5V_B_1_VFB")
	)
	(segment
		(start 24.039322 -227.417122)
		(end 24.039322 -229.668578)
		(width 0.254)
		(layer "B.Cu")
		(net "P5V_B_1_VFB")
	)
	(segment
		(start 24.039322 -229.668578)
		(end 24.0157 -229.6922)
		(width 0.254)
		(layer "B.Cu")
		(net "P5V_B_1_VFB")
	)
	(segment
		(start 24.831802 -231.65435)
		(end 24.006302 -230.82885)
		(width 0.254)
		(layer "B.Cu")
		(net "P5V_B_1_VFB")
	)
	(segment
		(start 28.641802 -231.65435)
		(end 24.831802 -231.65435)
		(width 0.254)
		(layer "B.Cu")
		(net "P5V_B_1_VFB")
	)
	(segment
		(start 24.0157 -229.6922)
		(end 24.0157 -230.628952)
		(width 0.254)
		(layer "B.Cu")
		(net "P5V_B_1_VFB")
	)
	(segment
		(start 30.862524 -230.911654)
		(end 30.119828 -231.65435)
		(width 0.254)
		(layer "B.Cu")
		(net "P5V_B_1_VFB")
	)
	(segment
		(start 22.591014 -229.099364)
		(end 23.422864 -229.099364)
		(width 0.254)
		(layer "B.Cu")
		(net "P5V_B_1_VFB")
	)
	(segment
		(start 24.0157 -230.628952)
		(end 24.006302 -230.63835)
		(width 0.254)
		(layer "B.Cu")
		(net "P5V_B_1_VFB")
	)
	(segment
		(start 24.006302 -230.82885)
		(end 24.006302 -230.63835)
		(width 0.254)
		(layer "B.Cu")
		(net "P5V_B_1_VFB")
	)
	(via
		(at 258.1402 -282.829)
		(size 0.6096)
		(drill 0.3048)
		(layers "F.Cu" "B.Cu")
		(net "P3V3_STBY_VRG5")
	)
	(segment
		(start 259.477002 -282.568142)
		(end 259.477002 -283.006546)
		(width 0.254)
		(layer "B.Cu")
		(net "P3V3_STBY_VRG5")
	)
	(segment
		(start 256.7178 -282.570682)
		(end 256.976118 -282.829)
		(width 0.254)
		(layer "B.Cu")
		(net "P3V3_STBY_VRG5")
	)
	(segment
		(start 259.477002 -283.006546)
		(end 258.317746 -283.006546)
		(width 0.254)
		(layer "B.Cu")
		(net "P3V3_STBY_VRG5")
	)
	(segment
		(start 258.317746 -283.006546)
		(end 258.1402 -282.829)
		(width 0.254)
		(layer "B.Cu")
		(net "P3V3_STBY_VRG5")
	)
	(segment
		(start 255.966722 -282.570682)
		(end 256.7178 -282.570682)
		(width 0.254)
		(layer "B.Cu")
		(net "P3V3_STBY_VRG5")
	)
	(segment
		(start 256.976118 -282.829)
		(end 258.1402 -282.829)
		(width 0.254)
		(layer "B.Cu")
		(net "P3V3_STBY_VRG5")
	)
	(segment
		(start 260.156198 -281.888946)
		(end 259.477002 -282.568142)
		(width 0.254)
		(layer "B.Cu")
		(net "P3V3_STBY_VRG5")
	)
	(segment
		(start 255.951736 -283.861764)
		(end 255.951736 -285.152338)
		(width 0.254)
		(layer "F.Cu")
		(net "P3V3_STBY_VO")
	)
	(segment
		(start 255.951736 -285.152338)
		(end 255.887474 -285.2166)
		(width 0.254)
		(layer "F.Cu")
		(net "P3V3_STBY_VO")
	)
	(segment
		(start 255.9685 -283.845)
		(end 255.951736 -283.861764)
		(width 0.254)
		(layer "F.Cu")
		(net "P3V3_STBY_VO")
	)
	(via
		(at 255.887474 -285.2166)
		(size 0.6604)
		(drill 0.3048)
		(layers "F.Cu" "B.Cu")
		(net "P3V3_STBY_VO")
	)
	(segment
		(start 255.17856 -284.26156)
		(end 255.887474 -284.970474)
		(width 0.254)
		(layer "B.Cu")
		(net "P3V3_STBY_VO")
	)
	(segment
		(start 255.17856 -283.87167)
		(end 255.17856 -284.26156)
		(width 0.254)
		(layer "B.Cu")
		(net "P3V3_STBY_VO")
	)
	(segment
		(start 255.887474 -284.970474)
		(end 255.887474 -285.2166)
		(width 0.254)
		(layer "B.Cu")
		(net "P3V3_STBY_VO")
	)
	(via
		(at 253.2126 -285.623)
		(size 0.6096)
		(drill 0.3048)
		(layers "F.Cu" "B.Cu")
		(net "P3V3_STBY_VIN")
	)
	(via
		(at 248.321322 -287.65246)
		(size 0.6604)
		(drill 0.3048)
		(layers "F.Cu" "B.Cu")
		(net "P3V3_STBY_VFB_R")
	)
	(via
		(at 261.366 -285.0896)
		(size 0.5588)
		(drill 0.3048)
		(layers "F.Cu" "B.Cu")
		(net "P3V3_STBY_VFB_R")
	)
	(segment
		(start 247.4468 -287.0327)
		(end 248.06656 -287.65246)
		(width 0.254)
		(layer "B.Cu")
		(net "P3V3_STBY_VFB_R")
	)
	(segment
		(start 261.366 -285.0896)
		(end 260.4643 -285.0896)
		(width 0.254)
		(layer "B.Cu")
		(net "P3V3_STBY_VFB_R")
	)
	(segment
		(start 248.06656 -287.65246)
		(end 248.321322 -287.65246)
		(width 0.254)
		(layer "B.Cu")
		(net "P3V3_STBY_VFB_R")
	)
	(segment
		(start 246.3546 -287.7312)
		(end 246.7102 -287.7312)
		(width 0.254)
		(layer "B.Cu")
		(net "P3V3_STBY_VFB_R")
	)
	(segment
		(start 246.7102 -287.7312)
		(end 247.4087 -287.0327)
		(width 0.254)
		(layer "B.Cu")
		(net "P3V3_STBY_VFB_R")
	)
	(segment
		(start 247.4087 -287.0327)
		(end 247.4468 -287.0327)
		(width 0.254)
		(layer "B.Cu")
		(net "P3V3_STBY_VFB_R")
	)
	(segment
		(start 250.4694 -288.4424)
		(end 249.67946 -287.65246)
		(width 0.254)
		(layer "In5.Cu")
		(net "P3V3_STBY_VFB_R")
	)
	(segment
		(start 258.0132 -288.4424)
		(end 250.4694 -288.4424)
		(width 0.254)
		(layer "In5.Cu")
		(net "P3V3_STBY_VFB_R")
	)
	(segment
		(start 261.366 -285.0896)
		(end 258.0132 -288.4424)
		(width 0.254)
		(layer "In5.Cu")
		(net "P3V3_STBY_VFB_R")
	)
	(segment
		(start 249.67946 -287.65246)
		(end 248.321322 -287.65246)
		(width 0.254)
		(layer "In5.Cu")
		(net "P3V3_STBY_VFB_R")
	)
	(via
		(at 258.4958 -284.049216)
		(size 0.6096)
		(drill 0.3048)
		(layers "F.Cu" "B.Cu")
		(net "P3V3_STBY_VFB")
	)
	(segment
		(start 259.5753 -285.0896)
		(end 259.5753 -285.3309)
		(width 0.254)
		(layer "B.Cu")
		(net "P3V3_STBY_VFB")
	)
	(segment
		(start 259.82549 -285.58109)
		(end 259.82549 -286.138112)
		(width 0.254)
		(layer "B.Cu")
		(net "P3V3_STBY_VFB")
	)
	(segment
		(start 260.7818 -287.0581)
		(end 260.7818 -286.786828)
		(width 0.254)
		(layer "B.Cu")
		(net "P3V3_STBY_VFB")
	)
	(segment
		(start 260.133084 -286.138112)
		(end 259.82549 -286.138112)
		(width 0.254)
		(layer "B.Cu")
		(net "P3V3_STBY_VFB")
	)
	(segment
		(start 259.345684 -284.049216)
		(end 258.4958 -284.049216)
		(width 0.254)
		(layer "B.Cu")
		(net "P3V3_STBY_VFB")
	)
	(segment
		(start 259.5753 -285.3309)
		(end 259.82549 -285.58109)
		(width 0.254)
		(layer "B.Cu")
		(net "P3V3_STBY_VFB")
	)
	(segment
		(start 259.5753 -285.0896)
		(end 259.5753 -284.278832)
		(width 0.254)
		(layer "B.Cu")
		(net "P3V3_STBY_VFB")
	)
	(segment
		(start 255.979422 -283.070808)
		(end 256.375408 -283.070808)
		(width 0.254)
		(layer "B.Cu")
		(net "P3V3_STBY_VFB")
	)
	(segment
		(start 259.421122 -284.124654)
		(end 259.345684 -284.049216)
		(width 0.254)
		(layer "B.Cu")
		(net "P3V3_STBY_VFB")
	)
	(segment
		(start 260.7818 -286.786828)
		(end 260.133084 -286.138112)
		(width 0.254)
		(layer "B.Cu")
		(net "P3V3_STBY_VFB")
	)
	(segment
		(start 259.5753 -284.278832)
		(end 259.421122 -284.124654)
		(width 0.254)
		(layer "B.Cu")
		(net "P3V3_STBY_VFB")
	)
	(segment
		(start 257.353816 -284.049216)
		(end 258.4958 -284.049216)
		(width 0.254)
		(layer "B.Cu")
		(net "P3V3_STBY_VFB")
	)
	(segment
		(start 256.375408 -283.070808)
		(end 257.353816 -284.049216)
		(width 0.254)
		(layer "B.Cu")
		(net "P3V3_STBY_VFB")
	)
	(segment
		(start 253.492 -284.487366)
		(end 254.678434 -285.6738)
		(width 0.508)
		(layer "F.Cu")
		(net "P3V3_STBY_VCC")
	)
	(segment
		(start 253.492 -284.48)
		(end 253.492 -284.487366)
		(width 0.508)
		(layer "F.Cu")
		(net "P3V3_STBY_VCC")
	)
	(segment
		(start 255.1176 -286.112966)
		(end 254.678434 -285.6738)
		(width 0.508)
		(layer "F.Cu")
		(net "P3V3_STBY_VCC")
	)
	(segment
		(start 255.1176 -286.8422)
		(end 255.1176 -286.112966)
		(width 0.508)
		(layer "F.Cu")
		(net "P3V3_STBY_VCC")
	)
	(via
		(at 254.678434 -285.6738)
		(size 0.6604)
		(drill 0.3048)
		(layers "F.Cu" "B.Cu")
		(net "P3V3_STBY_VCC")
	)
	(segment
		(start 254.678434 -283.85897)
		(end 254.678434 -285.6738)
		(width 0.3048)
		(layer "B.Cu")
		(net "P3V3_STBY_VCC")
	)
	(via
		(at 251.1552 -286.2072)
		(size 0.6096)
		(drill 0.3048)
		(layers "F.Cu" "B.Cu")
		(net "P3V3_STBY_VBST_RR")
	)
	(via
		(at 251.5108 -284.0482)
		(size 0.6096)
		(drill 0.3048)
		(layers "F.Cu" "B.Cu")
		(net "P3V3_STBY_VBST")
	)
	(via
		(at 248.539 -284.988)
		(size 0.6096)
		(drill 0.3048)
		(layers "F.Cu" "B.Cu")
		(net "P3V3_STBY_SW")
	)
	(segment
		(start 248.539 -284.988)
		(end 248.539 -286.2072)
		(width 0.508)
		(layer "B.Cu")
		(net "P3V3_STBY_SW")
	)
	(segment
		(start 248.4755 -276.7965)
		(end 248.4755 -275.463)
		(width 0.508)
		(layer "B.Cu")
		(net "P3V3_STBY_SW")
	)
	(segment
		(start 248.539 -286.2072)
		(end 248.083324 -286.2072)
		(width 0.508)
		(layer "B.Cu")
		(net "P3V3_STBY_SW")
	)
	(segment
		(start 248.019824 -286.1437)
		(end 247.4468 -286.1437)
		(width 0.508)
		(layer "B.Cu")
		(net "P3V3_STBY_SW")
	)
	(segment
		(start 248.539 -282.829)
		(end 248.539 -284.988)
		(width 0.508)
		(layer "B.Cu")
		(net "P3V3_STBY_SW")
	)
	(segment
		(start 248.92 -282.448)
		(end 248.539 -282.829)
		(width 0.508)
		(layer "B.Cu")
		(net "P3V3_STBY_SW")
	)
	(segment
		(start 249.047 -277.368)
		(end 248.4755 -276.7965)
		(width 0.508)
		(layer "B.Cu")
		(net "P3V3_STBY_SW")
	)
	(segment
		(start 248.083324 -286.2072)
		(end 248.019824 -286.1437)
		(width 0.508)
		(layer "B.Cu")
		(net "P3V3_STBY_SW")
	)
	(via
		(at 257.302 -281.559)
		(size 0.6096)
		(drill 0.3048)
		(layers "F.Cu" "B.Cu")
		(net "P3V3_STBY_SS")
	)
	(segment
		(start 256.79019 -282.07081)
		(end 257.302 -281.559)
		(width 0.254)
		(layer "B.Cu")
		(net "P3V3_STBY_SS")
	)
	(segment
		(start 257.735832 -281.125168)
		(end 257.302 -281.559)
		(width 0.254)
		(layer "B.Cu")
		(net "P3V3_STBY_SS")
	)
	(segment
		(start 255.966722 -282.07081)
		(end 256.79019 -282.07081)
		(width 0.254)
		(layer "B.Cu")
		(net "P3V3_STBY_SS")
	)
	(segment
		(start 258.22783 -281.125168)
		(end 257.735832 -281.125168)
		(width 0.254)
		(layer "B.Cu")
		(net "P3V3_STBY_SS")
	)
	(via
		(at 247.269 -274.447)
		(size 0.6096)
		(drill 0.3048)
		(layers "F.Cu" "B.Cu")
		(net "P3V3_STBY_SNB")
	)
	(via
		(at 254 -278.003)
		(size 0.6096)
		(drill 0.3048)
		(layers "F.Cu" "B.Cu")
		(net "P3V3_STBY_EN_R")
	)
	(segment
		(start 255.330706 -277.451312)
		(end 254.170688 -277.451312)
		(width 0.254)
		(layer "B.Cu")
		(net "P3V3_STBY_EN_R")
	)
	(segment
		(start 254.678434 -279.189434)
		(end 254.635 -279.146)
		(width 0.254)
		(layer "B.Cu")
		(net "P3V3_STBY_EN_R")
	)
	(segment
		(start 254.170688 -277.451312)
		(end 254 -277.622)
		(width 0.254)
		(layer "B.Cu")
		(net "P3V3_STBY_EN_R")
	)
	(segment
		(start 254 -278.511)
		(end 254.635 -279.146)
		(width 0.254)
		(layer "B.Cu")
		(net "P3V3_STBY_EN_R")
	)
	(segment
		(start 254 -278.003)
		(end 254 -278.511)
		(width 0.254)
		(layer "B.Cu")
		(net "P3V3_STBY_EN_R")
	)
	(segment
		(start 254 -277.622)
		(end 254 -278.003)
		(width 0.254)
		(layer "B.Cu")
		(net "P3V3_STBY_EN_R")
	)
	(segment
		(start 254.678434 -280.782522)
		(end 254.678434 -279.189434)
		(width 0.254)
		(layer "B.Cu")
		(net "P3V3_STBY_EN_R")
	)
	(segment
		(start 256.8575 -283.845)
		(end 256.8575 -284.6197)
		(width 0.254)
		(layer "F.Cu")
		(net "P3V3_STBY_CC_R")
	)
	(segment
		(start 256.8575 -284.6197)
		(end 257.2512 -285.0134)
		(width 0.254)
		(layer "F.Cu")
		(net "P3V3_STBY_CC_R")
	)
	(via
		(at 257.2512 -285.0134)
		(size 0.6604)
		(drill 0.3048)
		(layers "F.Cu" "B.Cu")
		(net "P3V3_STBY_CC_R")
	)
	(segment
		(start 259.82549 -287.36036)
		(end 259.82549 -287.027112)
		(width 0.254)
		(layer "B.Cu")
		(net "P3V3_STBY_CC_R")
	)
	(segment
		(start 258.1402 -284.988)
		(end 257.2766 -284.988)
		(width 0.254)
		(layer "B.Cu")
		(net "P3V3_STBY_CC_R")
	)
	(segment
		(start 259.388864 -288.879534)
		(end 259.849366 -288.879534)
		(width 0.254)
		(layer "B.Cu")
		(net "P3V3_STBY_CC_R")
	)
	(segment
		(start 259.34797 -287.027112)
		(end 259.027168 -286.70631)
		(width 0.254)
		(layer "B.Cu")
		(net "P3V3_STBY_CC_R")
	)
	(segment
		(start 259.027168 -286.70631)
		(end 259.027168 -285.874968)
		(width 0.254)
		(layer "B.Cu")
		(net "P3V3_STBY_CC_R")
	)
	(segment
		(start 260.24713 -287.782)
		(end 259.82549 -287.36036)
		(width 0.254)
		(layer "B.Cu")
		(net "P3V3_STBY_CC_R")
	)
	(segment
		(start 260.7818 -287.9471)
		(end 260.6167 -287.782)
		(width 0.254)
		(layer "B.Cu")
		(net "P3V3_STBY_CC_R")
	)
	(segment
		(start 259.027168 -285.874968)
		(end 258.1402 -284.988)
		(width 0.254)
		(layer "B.Cu")
		(net "P3V3_STBY_CC_R")
	)
	(segment
		(start 259.82549 -287.027112)
		(end 259.34797 -287.027112)
		(width 0.254)
		(layer "B.Cu")
		(net "P3V3_STBY_CC_R")
	)
	(segment
		(start 259.849366 -288.879534)
		(end 260.7818 -287.9471)
		(width 0.254)
		(layer "B.Cu")
		(net "P3V3_STBY_CC_R")
	)
	(segment
		(start 257.2766 -284.988)
		(end 257.2512 -285.0134)
		(width 0.254)
		(layer "B.Cu")
		(net "P3V3_STBY_CC_R")
	)
	(segment
		(start 260.6167 -287.782)
		(end 260.24713 -287.782)
		(width 0.254)
		(layer "B.Cu")
		(net "P3V3_STBY_CC_R")
	)
	(via
		(at 245.237 -286.512)
		(size 0.6604)
		(drill 0.3048)
		(layers "F.Cu" "B.Cu")
		(net "P3V3_STBY_CC")
	)
	(via
		(at 261.665212 -288.07791)
		(size 0.5588)
		(drill 0.3048)
		(layers "F.Cu" "B.Cu")
		(net "P3V3_STBY_CC")
	)
	(segment
		(start 259.388864 -290.403534)
		(end 259.388864 -290.354258)
		(width 0.254)
		(layer "B.Cu")
		(net "P3V3_STBY_CC")
	)
	(segment
		(start 259.388864 -290.354258)
		(end 261.665212 -288.07791)
		(width 0.254)
		(layer "B.Cu")
		(net "P3V3_STBY_CC")
	)
	(segment
		(start 245.237 -285.8135)
		(end 245.237 -286.512)
		(width 0.254)
		(layer "B.Cu")
		(net "P3V3_STBY_CC")
	)
	(segment
		(start 259.878322 -289.8648)
		(end 261.665212 -288.07791)
		(width 0.254)
		(layer "In5.Cu")
		(net "P3V3_STBY_CC")
	)
	(segment
		(start 245.237 -286.512)
		(end 248.5898 -289.8648)
		(width 0.254)
		(layer "In5.Cu")
		(net "P3V3_STBY_CC")
	)
	(segment
		(start 248.5898 -289.8648)
		(end 259.878322 -289.8648)
		(width 0.254)
		(layer "In5.Cu")
		(net "P3V3_STBY_CC")
	)
	(segment
		(start 246.745252 -368.340132)
		(end 245.475252 -368.340132)
		(width 0.254)
		(layer "F.Cu")
		(net "MB3_TEMP_E")
	)
	(segment
		(start 239.811814 -367.130838)
		(end 241.240564 -367.130838)
		(width 0.254)
		(layer "F.Cu")
		(net "MB3_TEMP_E")
	)
	(segment
		(start 245.475252 -368.340132)
		(end 244.567202 -368.340132)
		(width 0.254)
		(layer "F.Cu")
		(net "MB3_TEMP_E")
	)
	(segment
		(start 239.780064 -367.162588)
		(end 239.811814 -367.130838)
		(width 0.254)
		(layer "F.Cu")
		(net "MB3_TEMP_E")
	)
	(segment
		(start 243.357908 -367.130838)
		(end 241.240564 -367.130838)
		(width 0.254)
		(layer "F.Cu")
		(net "MB3_TEMP_E")
	)
	(segment
		(start 244.567202 -368.340132)
		(end 243.357908 -367.130838)
		(width 0.254)
		(layer "F.Cu")
		(net "MB3_TEMP_E")
	)
	(via
		(at 245.475252 -368.340132)
		(size 0.6604)
		(drill 0.3302)
		(layers "F.Cu" "B.Cu")
		(net "MB3_TEMP_E")
	)
	(segment
		(start 245.48211 -369.462812)
		(end 246.511572 -369.462812)
		(width 0.254)
		(layer "F.Cu")
		(net "MB3_TEMP_B")
	)
	(segment
		(start 246.745252 -369.229132)
		(end 247.761252 -369.229132)
		(width 0.254)
		(layer "F.Cu")
		(net "MB3_TEMP_B")
	)
	(segment
		(start 243.145564 -368.115088)
		(end 242.422172 -368.115088)
		(width 0.254)
		(layer "F.Cu")
		(net "MB3_TEMP_B")
	)
	(segment
		(start 241.437922 -369.099338)
		(end 241.240564 -369.099338)
		(width 0.254)
		(layer "F.Cu")
		(net "MB3_TEMP_B")
	)
	(segment
		(start 245.48211 -369.462812)
		(end 244.706902 -369.462812)
		(width 0.254)
		(layer "F.Cu")
		(net "MB3_TEMP_B")
	)
	(segment
		(start 242.422172 -368.115088)
		(end 241.437922 -369.099338)
		(width 0.254)
		(layer "F.Cu")
		(net "MB3_TEMP_B")
	)
	(segment
		(start 244.706902 -369.462812)
		(end 243.359178 -368.115088)
		(width 0.254)
		(layer "F.Cu")
		(net "MB3_TEMP_B")
	)
	(segment
		(start 243.359178 -368.115088)
		(end 243.145564 -368.115088)
		(width 0.254)
		(layer "F.Cu")
		(net "MB3_TEMP_B")
	)
	(segment
		(start 246.511572 -369.462812)
		(end 246.745252 -369.229132)
		(width 0.254)
		(layer "F.Cu")
		(net "MB3_TEMP_B")
	)
	(via
		(at 245.48211 -369.462812)
		(size 0.6604)
		(drill 0.3302)
		(layers "F.Cu" "B.Cu")
		(net "MB3_TEMP_B")
	)
	(segment
		(start 288.547048 -349.852742)
		(end 289.080448 -349.319342)
		(width 0.17145)
		(layer "F.Cu")
		(net "MAX31790_B_WD_ST")
	)
	(segment
		(start 289.080448 -347.985842)
		(end 289.080448 -349.319342)
		(width 0.17145)
		(layer "F.Cu")
		(net "MAX31790_B_WD_ST")
	)
	(segment
		(start 286.051498 -350.243902)
		(end 286.442658 -349.852742)
		(width 0.17145)
		(layer "F.Cu")
		(net "MAX31790_B_WD_ST")
	)
	(segment
		(start 286.051498 -350.716342)
		(end 286.051498 -350.243902)
		(width 0.17145)
		(layer "F.Cu")
		(net "MAX31790_B_WD_ST")
	)
	(segment
		(start 286.442658 -349.852742)
		(end 288.547048 -349.852742)
		(width 0.17145)
		(layer "F.Cu")
		(net "MAX31790_B_WD_ST")
	)
	(via
		(at 289.080448 -349.319342)
		(size 0.6604)
		(drill 0.3302)
		(layers "F.Cu" "B.Cu")
		(net "MAX31790_B_WD_ST")
	)
	(segment
		(start 284.851348 -350.716342)
		(end 284.851348 -350.221042)
		(width 0.17145)
		(layer "F.Cu")
		(net "MAX31790_B_SPIN_ST")
	)
	(segment
		(start 284.000448 -347.985842)
		(end 284.000448 -348.531942)
		(width 0.17145)
		(layer "F.Cu")
		(net "MAX31790_B_SPIN_ST")
	)
	(segment
		(start 284.851348 -350.221042)
		(end 284.048454 -349.418148)
		(width 0.17145)
		(layer "F.Cu")
		(net "MAX31790_B_SPIN_ST")
	)
	(segment
		(start 284.048454 -348.579948)
		(end 284.048454 -349.112332)
		(width 0.17145)
		(layer "F.Cu")
		(net "MAX31790_B_SPIN_ST")
	)
	(segment
		(start 284.000448 -348.531942)
		(end 284.048454 -348.579948)
		(width 0.17145)
		(layer "F.Cu")
		(net "MAX31790_B_SPIN_ST")
	)
	(segment
		(start 284.048454 -349.418148)
		(end 284.048454 -349.112332)
		(width 0.17145)
		(layer "F.Cu")
		(net "MAX31790_B_SPIN_ST")
	)
	(via
		(at 284.048454 -349.112332)
		(size 0.6604)
		(drill 0.3302)
		(layers "F.Cu" "B.Cu")
		(net "MAX31790_B_SPIN_ST")
	)
	(segment
		(start 280.8859 -349.3008)
		(end 280.8859 -350.332294)
		(width 0.17145)
		(layer "F.Cu")
		(net "MAX31790_B_PWM_ST1")
	)
	(segment
		(start 281.206448 -350.335342)
		(end 282.222448 -351.351342)
		(width 0.17145)
		(layer "F.Cu")
		(net "MAX31790_B_PWM_ST1")
	)
	(segment
		(start 280.8859 -350.332294)
		(end 280.888948 -350.335342)
		(width 0.17145)
		(layer "F.Cu")
		(net "MAX31790_B_PWM_ST1")
	)
	(segment
		(start 283.619448 -352.348292)
		(end 282.784042 -352.348292)
		(width 0.17145)
		(layer "F.Cu")
		(net "MAX31790_B_PWM_ST1")
	)
	(segment
		(start 280.888948 -350.335342)
		(end 281.206448 -350.335342)
		(width 0.17145)
		(layer "F.Cu")
		(net "MAX31790_B_PWM_ST1")
	)
	(segment
		(start 282.784042 -352.348292)
		(end 282.222448 -351.786698)
		(width 0.17145)
		(layer "F.Cu")
		(net "MAX31790_B_PWM_ST1")
	)
	(segment
		(start 282.222448 -351.786698)
		(end 282.222448 -351.351342)
		(width 0.17145)
		(layer "F.Cu")
		(net "MAX31790_B_PWM_ST1")
	)
	(via
		(at 282.222448 -351.351342)
		(size 0.6604)
		(drill 0.3302)
		(layers "F.Cu" "B.Cu")
		(net "MAX31790_B_PWM_ST1")
	)
	(segment
		(start 280.888948 -352.367342)
		(end 281.841448 -352.367342)
		(width 0.17145)
		(layer "F.Cu")
		(net "MAX31790_B_PWM_ST0")
	)
	(segment
		(start 281.968448 -352.367342)
		(end 281.841448 -352.367342)
		(width 0.17145)
		(layer "F.Cu")
		(net "MAX31790_B_PWM_ST0")
	)
	(segment
		(start 280.888948 -351.351342)
		(end 280.888948 -352.367342)
		(width 0.17145)
		(layer "F.Cu")
		(net "MAX31790_B_PWM_ST0")
	)
	(segment
		(start 282.349448 -352.748342)
		(end 281.968448 -352.367342)
		(width 0.17145)
		(layer "F.Cu")
		(net "MAX31790_B_PWM_ST0")
	)
	(segment
		(start 283.619448 -352.748342)
		(end 282.349448 -352.748342)
		(width 0.17145)
		(layer "F.Cu")
		(net "MAX31790_B_PWM_ST0")
	)
	(via
		(at 281.841448 -352.367342)
		(size 0.6604)
		(drill 0.3302)
		(layers "F.Cu" "B.Cu")
		(net "MAX31790_B_PWM_ST0")
	)
	(segment
		(start 284.451552 -350.716342)
		(end 284.127448 -350.716342)
		(width 0.17145)
		(layer "F.Cu")
		(net "MAX31790_B_FREQ_ST")
	)
	(segment
		(start 282.984448 -349.192342)
		(end 282.984448 -347.985842)
		(width 0.17145)
		(layer "F.Cu")
		(net "MAX31790_B_FREQ_ST")
	)
	(segment
		(start 284.127448 -350.716342)
		(end 282.984448 -349.573342)
		(width 0.17145)
		(layer "F.Cu")
		(net "MAX31790_B_FREQ_ST")
	)
	(segment
		(start 282.984448 -349.573342)
		(end 282.984448 -349.192342)
		(width 0.17145)
		(layer "F.Cu")
		(net "MAX31790_B_FREQ_ST")
	)
	(via
		(at 282.984448 -349.192342)
		(size 0.6604)
		(drill 0.3302)
		(layers "F.Cu" "B.Cu")
		(net "MAX31790_B_FREQ_ST")
	)
	(segment
		(start 242.67795 -309.26405)
		(end 242.316 -309.626)
		(width 0.17145)
		(layer "F.Cu")
		(net "MAX31790_A_WD_ST")
	)
	(segment
		(start 242.316 -309.626)
		(end 240.157 -309.626)
		(width 0.17145)
		(layer "F.Cu")
		(net "MAX31790_A_WD_ST")
	)
	(segment
		(start 239.649 -310.134)
		(end 239.649 -311.4675)
		(width 0.17145)
		(layer "F.Cu")
		(net "MAX31790_A_WD_ST")
	)
	(segment
		(start 242.67795 -308.737)
		(end 242.67795 -309.26405)
		(width 0.17145)
		(layer "F.Cu")
		(net "MAX31790_A_WD_ST")
	)
	(segment
		(start 240.157 -309.626)
		(end 239.649 -310.134)
		(width 0.17145)
		(layer "F.Cu")
		(net "MAX31790_A_WD_ST")
	)
	(via
		(at 239.649 -310.134)
		(size 0.6604)
		(drill 0.3302)
		(layers "F.Cu" "B.Cu")
		(net "MAX31790_A_WD_ST")
	)
	(segment
		(start 244.729 -310.515)
		(end 244.729 -311.4675)
		(width 0.17145)
		(layer "F.Cu")
		(net "MAX31790_A_SPIN_ST")
	)
	(segment
		(start 243.8781 -309.2831)
		(end 244.729 -310.134)
		(width 0.17145)
		(layer "F.Cu")
		(net "MAX31790_A_SPIN_ST")
	)
	(segment
		(start 243.8781 -308.737)
		(end 243.8781 -309.2831)
		(width 0.17145)
		(layer "F.Cu")
		(net "MAX31790_A_SPIN_ST")
	)
	(segment
		(start 244.729 -310.134)
		(end 244.729 -310.515)
		(width 0.17145)
		(layer "F.Cu")
		(net "MAX31790_A_SPIN_ST")
	)
	(via
		(at 244.729 -310.515)
		(size 0.6604)
		(drill 0.3302)
		(layers "F.Cu" "B.Cu")
		(net "MAX31790_A_SPIN_ST")
	)
	(segment
		(start 245.91645 -307.10505)
		(end 246.507 -307.6956)
		(width 0.17145)
		(layer "F.Cu")
		(net "MAX31790_A_PWM_ST1")
	)
	(segment
		(start 247.8405 -309.118)
		(end 247.8405 -310.134)
		(width 0.17145)
		(layer "F.Cu")
		(net "MAX31790_A_PWM_ST1")
	)
	(segment
		(start 246.507 -308.102)
		(end 246.507 -308.7878)
		(width 0.17145)
		(layer "F.Cu")
		(net "MAX31790_A_PWM_ST1")
	)
	(segment
		(start 246.8372 -309.118)
		(end 247.8405 -309.118)
		(width 0.17145)
		(layer "F.Cu")
		(net "MAX31790_A_PWM_ST1")
	)
	(segment
		(start 246.507 -307.6956)
		(end 246.507 -308.102)
		(width 0.17145)
		(layer "F.Cu")
		(net "MAX31790_A_PWM_ST1")
	)
	(segment
		(start 246.507 -308.7878)
		(end 246.8372 -309.118)
		(width 0.17145)
		(layer "F.Cu")
		(net "MAX31790_A_PWM_ST1")
	)
	(segment
		(start 245.11 -307.10505)
		(end 245.91645 -307.10505)
		(width 0.17145)
		(layer "F.Cu")
		(net "MAX31790_A_PWM_ST1")
	)
	(via
		(at 246.507 -308.102)
		(size 0.6604)
		(drill 0.3302)
		(layers "F.Cu" "B.Cu")
		(net "MAX31790_A_PWM_ST1")
	)
	(segment
		(start 246.7356 -307.086)
		(end 246.888 -307.086)
		(width 0.17145)
		(layer "F.Cu")
		(net "MAX31790_A_PWM_ST0")
	)
	(segment
		(start 246.386604 -306.737004)
		(end 246.7356 -307.086)
		(width 0.17145)
		(layer "F.Cu")
		(net "MAX31790_A_PWM_ST0")
	)
	(segment
		(start 246.888 -307.086)
		(end 247.8405 -307.086)
		(width 0.17145)
		(layer "F.Cu")
		(net "MAX31790_A_PWM_ST0")
	)
	(segment
		(start 245.11 -306.705)
		(end 246.109744 -306.705)
		(width 0.17145)
		(layer "F.Cu")
		(net "MAX31790_A_PWM_ST0")
	)
	(segment
		(start 246.109744 -306.705)
		(end 246.141748 -306.737004)
		(width 0.17145)
		(layer "F.Cu")
		(net "MAX31790_A_PWM_ST0")
	)
	(segment
		(start 246.141748 -306.737004)
		(end 246.386604 -306.737004)
		(width 0.17145)
		(layer "F.Cu")
		(net "MAX31790_A_PWM_ST0")
	)
	(segment
		(start 247.8405 -308.102)
		(end 247.8405 -307.086)
		(width 0.17145)
		(layer "F.Cu")
		(net "MAX31790_A_PWM_ST0")
	)
	(via
		(at 246.888 -307.086)
		(size 0.6604)
		(drill 0.3302)
		(layers "F.Cu" "B.Cu")
		(net "MAX31790_A_PWM_ST0")
	)
	(segment
		(start 244.277896 -308.737)
		(end 244.602 -308.737)
		(width 0.17145)
		(layer "F.Cu")
		(net "MAX31790_A_FREQ_ST")
	)
	(segment
		(start 245.745 -310.134)
		(end 245.745 -311.4675)
		(width 0.17145)
		(layer "F.Cu")
		(net "MAX31790_A_FREQ_ST")
	)
	(segment
		(start 245.745 -309.88)
		(end 245.745 -310.134)
		(width 0.17145)
		(layer "F.Cu")
		(net "MAX31790_A_FREQ_ST")
	)
	(segment
		(start 244.602 -308.737)
		(end 245.745 -309.88)
		(width 0.17145)
		(layer "F.Cu")
		(net "MAX31790_A_FREQ_ST")
	)
	(via
		(at 245.745 -310.134)
		(size 0.6604)
		(drill 0.3302)
		(layers "F.Cu" "B.Cu")
		(net "MAX31790_A_FREQ_ST")
	)
	(via
		(at 266.7127 -379.987556)
		(size 0.6604)
		(drill 0.3302)
		(layers "F.Cu" "B.Cu")
		(net "IR_SWITCH_E")
	)
	(via
		(at 265.8999 -377.320556)
		(size 0.6604)
		(drill 0.3302)
		(layers "F.Cu" "B.Cu")
		(net "IR_SWITCH_C")
	)
	(segment
		(start 219.210382 -165.12794)
		(end 219.95003 -164.388292)
		(width 0.17145)
		(layer "F.Cu")
		(net "IO_EXP6_INT_N")
	)
	(segment
		(start 218.33586 -165.12794)
		(end 219.210382 -165.12794)
		(width 0.17145)
		(layer "F.Cu")
		(net "IO_EXP6_INT_N")
	)
	(segment
		(start 221.29496 -162.35426)
		(end 220.439742 -162.35426)
		(width 0.17145)
		(layer "F.Cu")
		(net "IO_EXP6_INT_N")
	)
	(segment
		(start 220.439742 -162.35426)
		(end 219.95003 -162.843972)
		(width 0.17145)
		(layer "F.Cu")
		(net "IO_EXP6_INT_N")
	)
	(segment
		(start 219.95003 -162.843972)
		(end 219.95003 -163.496752)
		(width 0.17145)
		(layer "F.Cu")
		(net "IO_EXP6_INT_N")
	)
	(segment
		(start 219.95003 -164.388292)
		(end 219.95003 -163.496752)
		(width 0.17145)
		(layer "F.Cu")
		(net "IO_EXP6_INT_N")
	)
	(via
		(at 219.95003 -163.496752)
		(size 0.6604)
		(drill 0.3302)
		(layers "F.Cu" "B.Cu")
		(net "IO_EXP6_INT_N")
	)
	(segment
		(start 463.971894 -375.07291)
		(end 464.699604 -374.3452)
		(width 0.254)
		(layer "F.Cu")
		(net "FAN_BLUE3")
	)
	(segment
		(start 464.699604 -372.6434)
		(end 465.080604 -372.2624)
		(width 0.254)
		(layer "F.Cu")
		(net "FAN_BLUE3")
	)
	(segment
		(start 465.080604 -372.2624)
		(end 465.969604 -372.2624)
		(width 0.254)
		(layer "F.Cu")
		(net "FAN_BLUE3")
	)
	(segment
		(start 463.564986 -375.07291)
		(end 463.971894 -375.07291)
		(width 0.254)
		(layer "F.Cu")
		(net "FAN_BLUE3")
	)
	(segment
		(start 464.699604 -374.3452)
		(end 464.699604 -372.6434)
		(width 0.254)
		(layer "F.Cu")
		(net "FAN_BLUE3")
	)
	(segment
		(start 461.946244 -375.07291)
		(end 463.564986 -375.07291)
		(width 0.254)
		(layer "F.Cu")
		(net "FAN_BLUE3")
	)
	(via
		(at 463.564986 -375.07291)
		(size 0.6604)
		(drill 0.3302)
		(layers "F.Cu" "B.Cu")
		(net "FAN_BLUE3")
	)
	(segment
		(start 319.880996 -381.3556)
		(end 318.1096 -381.3556)
		(width 0.254)
		(layer "F.Cu")
		(net "FAN_BLUE2")
	)
	(segment
		(start 321.312286 -380.53391)
		(end 320.490596 -381.3556)
		(width 0.254)
		(layer "F.Cu")
		(net "FAN_BLUE2")
	)
	(segment
		(start 315.791596 -379.037596)
		(end 315.791596 -374.396)
		(width 0.254)
		(layer "F.Cu")
		(net "FAN_BLUE2")
	)
	(segment
		(start 321.312286 -379.97384)
		(end 321.312286 -380.53391)
		(width 0.254)
		(layer "F.Cu")
		(net "FAN_BLUE2")
	)
	(segment
		(start 315.791596 -374.396)
		(end 315.588396 -374.1928)
		(width 0.254)
		(layer "F.Cu")
		(net "FAN_BLUE2")
	)
	(segment
		(start 318.1096 -381.3556)
		(end 315.791596 -379.037596)
		(width 0.254)
		(layer "F.Cu")
		(net "FAN_BLUE2")
	)
	(segment
		(start 320.490596 -381.3556)
		(end 319.880996 -381.3556)
		(width 0.254)
		(layer "F.Cu")
		(net "FAN_BLUE2")
	)
	(via
		(at 319.880996 -381.3556)
		(size 0.6604)
		(drill 0.3302)
		(layers "F.Cu" "B.Cu")
		(net "FAN_BLUE2")
	)
	(via
		(at 282.618942 -381.088392)
		(size 0.6604)
		(drill 0.3302)
		(layers "F.Cu" "B.Cu")
		(net "EMITTER_K")
	)
	(segment
		(start 214.40648 -247.44172)
		(end 215.47328 -247.44172)
		(width 0.17145)
		(layer "F.Cu")
		(net "DRIVE_INSERT_ALERT_B_N")
	)
	(segment
		(start 214.40648 -247.44172)
		(end 213.35238 -247.44172)
		(width 0.17145)
		(layer "F.Cu")
		(net "DRIVE_INSERT_ALERT_B_N")
	)
	(segment
		(start 221.29496 -161.46526)
		(end 221.0308 -161.2011)
		(width 0.17145)
		(layer "F.Cu")
		(net "DRIVE_INSERT_ALERT_B_N")
	)
	(segment
		(start 220.8149 -202.8698)
		(end 221.6404 -202.8698)
		(width 0.17145)
		(layer "F.Cu")
		(net "DRIVE_INSERT_ALERT_B_N")
	)
	(segment
		(start 213.35238 -247.44172)
		(end 213.35238 -246.35968)
		(width 0.17145)
		(layer "F.Cu")
		(net "DRIVE_INSERT_ALERT_B_N")
	)
	(segment
		(start 215.47328 -247.44172)
		(end 215.4936 -247.4214)
		(width 0.17145)
		(layer "F.Cu")
		(net "DRIVE_INSERT_ALERT_B_N")
	)
	(segment
		(start 220.599 -203.0857)
		(end 220.8149 -202.8698)
		(width 0.17145)
		(layer "F.Cu")
		(net "DRIVE_INSERT_ALERT_B_N")
	)
	(segment
		(start 221.0308 -161.2011)
		(end 221.0308 -160.401)
		(width 0.17145)
		(layer "F.Cu")
		(net "DRIVE_INSERT_ALERT_B_N")
	)
	(via
		(at 214.40648 -247.44172)
		(size 0.6604)
		(drill 0.3302)
		(layers "F.Cu" "B.Cu")
		(net "DRIVE_INSERT_ALERT_B_N")
	)
	(via
		(at 221.0308 -160.401)
		(size 0.5588)
		(drill 0.3048)
		(layers "F.Cu" "B.Cu")
		(net "DRIVE_INSERT_ALERT_B_N")
	)
	(via
		(at 221.6404 -202.8698)
		(size 0.5588)
		(drill 0.3048)
		(layers "F.Cu" "B.Cu")
		(net "DRIVE_INSERT_ALERT_B_N")
	)
	(via
		(at 221.0308 -216.459562)
		(size 0.5588)
		(drill 0.3048)
		(layers "F.Cu" "B.Cu")
		(net "DRIVE_INSERT_ALERT_B_N")
	)
	(via
		(at 215.4936 -247.4214)
		(size 0.5588)
		(drill 0.3048)
		(layers "F.Cu" "B.Cu")
		(net "DRIVE_INSERT_ALERT_B_N")
	)
	(segment
		(start 222.061024 -203.290424)
		(end 222.061024 -215.429338)
		(width 0.14605)
		(layer "In2.Cu")
		(net "DRIVE_INSERT_ALERT_B_N")
	)
	(segment
		(start 215.4936 -230.51516)
		(end 215.4936 -247.4214)
		(width 0.14605)
		(layer "In2.Cu")
		(net "DRIVE_INSERT_ALERT_B_N")
	)
	(segment
		(start 221.5642 -160.9344)
		(end 221.0308 -160.401)
		(width 0.14605)
		(layer "In2.Cu")
		(net "DRIVE_INSERT_ALERT_B_N")
	)
	(segment
		(start 221.6404 -202.8698)
		(end 222.061024 -203.290424)
		(width 0.14605)
		(layer "In2.Cu")
		(net "DRIVE_INSERT_ALERT_B_N")
	)
	(segment
		(start 217.37955 -228.62921)
		(end 215.4936 -230.51516)
		(width 0.14605)
		(layer "In2.Cu")
		(net "DRIVE_INSERT_ALERT_B_N")
	)
	(segment
		(start 221.5642 -202.7936)
		(end 221.5642 -160.9344)
		(width 0.14605)
		(layer "In2.Cu")
		(net "DRIVE_INSERT_ALERT_B_N")
	)
	(segment
		(start 218.4654 -226.4664)
		(end 217.37955 -227.55225)
		(width 0.14605)
		(layer "In2.Cu")
		(net "DRIVE_INSERT_ALERT_B_N")
	)
	(segment
		(start 218.4654 -224.803716)
		(end 218.4654 -226.4664)
		(width 0.14605)
		(layer "In2.Cu")
		(net "DRIVE_INSERT_ALERT_B_N")
	)
	(segment
		(start 221.0308 -222.238316)
		(end 218.4654 -224.803716)
		(width 0.14605)
		(layer "In2.Cu")
		(net "DRIVE_INSERT_ALERT_B_N")
	)
	(segment
		(start 217.37955 -227.55225)
		(end 217.37955 -228.62921)
		(width 0.14605)
		(layer "In2.Cu")
		(net "DRIVE_INSERT_ALERT_B_N")
	)
	(segment
		(start 222.061024 -215.429338)
		(end 221.0308 -216.459562)
		(width 0.14605)
		(layer "In2.Cu")
		(net "DRIVE_INSERT_ALERT_B_N")
	)
	(segment
		(start 221.0308 -216.459562)
		(end 221.0308 -222.238316)
		(width 0.14605)
		(layer "In2.Cu")
		(net "DRIVE_INSERT_ALERT_B_N")
	)
	(segment
		(start 221.6404 -202.8698)
		(end 221.5642 -202.7936)
		(width 0.14605)
		(layer "In2.Cu")
		(net "DRIVE_INSERT_ALERT_B_N")
	)
	(segment
		(start 271.058386 -220.9038)
		(end 245.0846 -220.9038)
		(width 0.14605)
		(layer "In5.Cu")
		(net "DRIVE_INSERT_ALERT_B_N")
	)
	(segment
		(start 231.41305 -220.3704)
		(end 227.954586 -216.911936)
		(width 0.14605)
		(layer "In5.Cu")
		(net "DRIVE_INSERT_ALERT_B_N")
	)
	(segment
		(start 244.02923 -221.95917)
		(end 240.149634 -221.95917)
		(width 0.14605)
		(layer "In5.Cu")
		(net "DRIVE_INSERT_ALERT_B_N")
	)
	(segment
		(start 239.71631 -221.5261)
		(end 238.56061 -220.3704)
		(width 0.14605)
		(layer "In5.Cu")
		(net "DRIVE_INSERT_ALERT_B_N")
	)
	(segment
		(start 272.41119 -219.550996)
		(end 271.058386 -220.9038)
		(width 0.14605)
		(layer "In5.Cu")
		(net "DRIVE_INSERT_ALERT_B_N")
	)
	(segment
		(start 245.0846 -220.9038)
		(end 244.02923 -221.95917)
		(width 0.14605)
		(layer "In5.Cu")
		(net "DRIVE_INSERT_ALERT_B_N")
	)
	(segment
		(start 240.149634 -221.95917)
		(end 239.716564 -221.5261)
		(width 0.14605)
		(layer "In5.Cu")
		(net "DRIVE_INSERT_ALERT_B_N")
	)
	(segment
		(start 284.236668 -220.694504)
		(end 283.400246 -219.858082)
		(width 0.14605)
		(layer "In5.Cu")
		(net "DRIVE_INSERT_ALERT_B_N")
	)
	(segment
		(start 283.400246 -219.858082)
		(end 275.160486 -219.858082)
		(width 0.14605)
		(layer "In5.Cu")
		(net "DRIVE_INSERT_ALERT_B_N")
	)
	(segment
		(start 227.954586 -216.911936)
		(end 221.483174 -216.911936)
		(width 0.14605)
		(layer "In5.Cu")
		(net "DRIVE_INSERT_ALERT_B_N")
	)
	(segment
		(start 238.56061 -220.3704)
		(end 231.41305 -220.3704)
		(width 0.14605)
		(layer "In5.Cu")
		(net "DRIVE_INSERT_ALERT_B_N")
	)
	(segment
		(start 221.483174 -216.911936)
		(end 221.0308 -216.459562)
		(width 0.14605)
		(layer "In5.Cu")
		(net "DRIVE_INSERT_ALERT_B_N")
	)
	(segment
		(start 275.160486 -219.858082)
		(end 274.8534 -219.550996)
		(width 0.14605)
		(layer "In5.Cu")
		(net "DRIVE_INSERT_ALERT_B_N")
	)
	(segment
		(start 274.8534 -219.550996)
		(end 272.41119 -219.550996)
		(width 0.14605)
		(layer "In5.Cu")
		(net "DRIVE_INSERT_ALERT_B_N")
	)
	(segment
		(start 239.716564 -221.5261)
		(end 239.71631 -221.5261)
		(width 0.14605)
		(layer "In5.Cu")
		(net "DRIVE_INSERT_ALERT_B_N")
	)
	(segment
		(start 263.4869 -378.349256)
		(end 263.4869 -377.879356)
		(width 0.254)
		(layer "F.Cu")
		(net "DRAWER_OUT_NET_B")
	)
	(segment
		(start 262.6614 -379.174756)
		(end 263.4869 -378.349256)
		(width 0.254)
		(layer "F.Cu")
		(net "DRAWER_OUT_NET_B")
	)
	(segment
		(start 262.10895 -377.714256)
		(end 263.3218 -377.714256)
		(width 0.254)
		(layer "F.Cu")
		(net "DRAWER_OUT_NET_B")
	)
	(segment
		(start 263.3218 -377.714256)
		(end 263.4869 -377.879356)
		(width 0.254)
		(layer "F.Cu")
		(net "DRAWER_OUT_NET_B")
	)
	(via
		(at 263.4869 -377.879356)
		(size 0.6604)
		(drill 0.3302)
		(layers "F.Cu" "B.Cu")
		(net "DRAWER_OUT_NET_B")
	)
	(segment
		(start 264.4775 -381.486156)
		(end 264.6172 -381.346456)
		(width 0.254)
		(layer "F.Cu")
		(net "DRAWER_OUT_NET")
	)
	(segment
		(start 264.6172 -381.346456)
		(end 264.6172 -380.216156)
		(width 0.254)
		(layer "F.Cu")
		(net "DRAWER_OUT_NET")
	)
	(segment
		(start 264.0203 -381.486156)
		(end 264.4775 -381.486156)
		(width 0.254)
		(layer "F.Cu")
		(net "DRAWER_OUT_NET")
	)
	(segment
		(start 263.5504 -381.257556)
		(end 263.5504 -380.216156)
		(width 0.254)
		(layer "F.Cu")
		(net "DRAWER_OUT_NET")
	)
	(segment
		(start 264.0203 -381.486156)
		(end 263.779 -381.486156)
		(width 0.254)
		(layer "F.Cu")
		(net "DRAWER_OUT_NET")
	)
	(segment
		(start 264.6172 -380.216156)
		(end 264.6172 -379.174756)
		(width 0.254)
		(layer "F.Cu")
		(net "DRAWER_OUT_NET")
	)
	(segment
		(start 263.779 -381.486156)
		(end 263.5504 -381.257556)
		(width 0.254)
		(layer "F.Cu")
		(net "DRAWER_OUT_NET")
	)
	(segment
		(start 263.5504 -380.216156)
		(end 263.5504 -379.174756)
		(width 0.254)
		(layer "F.Cu")
		(net "DRAWER_OUT_NET")
	)
	(via
		(at 264.0203 -381.486156)
		(size 0.6604)
		(drill 0.3302)
		(layers "F.Cu" "B.Cu")
		(net "DRAWER_OUT_NET")
	)
	(segment
		(start 260.096 -379.174756)
		(end 261.0993 -379.174756)
		(width 0.254)
		(layer "F.Cu")
		(net "DRAWER_OUT#_C")
	)
	(segment
		(start 261.1247 -375.809256)
		(end 261.1247 -377.980956)
		(width 0.254)
		(layer "F.Cu")
		(net "DRAWER_OUT#_C")
	)
	(segment
		(start 261.2771 -379.352556)
		(end 261.2771 -379.657356)
		(width 0.254)
		(layer "F.Cu")
		(net "DRAWER_OUT#_C")
	)
	(segment
		(start 261.2771 -379.962156)
		(end 261.2771 -379.657356)
		(width 0.254)
		(layer "F.Cu")
		(net "DRAWER_OUT#_C")
	)
	(segment
		(start 260.096 -379.009656)
		(end 260.096 -379.174756)
		(width 0.254)
		(layer "F.Cu")
		(net "DRAWER_OUT#_C")
	)
	(segment
		(start 261.0993 -379.174756)
		(end 261.2771 -379.352556)
		(width 0.254)
		(layer "F.Cu")
		(net "DRAWER_OUT#_C")
	)
	(segment
		(start 260.096 -380.190756)
		(end 261.0485 -380.190756)
		(width 0.254)
		(layer "F.Cu")
		(net "DRAWER_OUT#_C")
	)
	(segment
		(start 261.0485 -380.190756)
		(end 261.2771 -379.962156)
		(width 0.254)
		(layer "F.Cu")
		(net "DRAWER_OUT#_C")
	)
	(segment
		(start 261.1247 -377.980956)
		(end 260.096 -379.009656)
		(width 0.254)
		(layer "F.Cu")
		(net "DRAWER_OUT#_C")
	)
	(via
		(at 261.2771 -379.657356)
		(size 0.6604)
		(drill 0.3302)
		(layers "F.Cu" "B.Cu")
		(net "DRAWER_OUT#_C")
	)
	(segment
		(start 259.207 -376.063256)
		(end 259.207 -379.174756)
		(width 0.254)
		(layer "F.Cu")
		(net "DRAWER_MOSFET_G")
	)
	(segment
		(start 259.0927 -382.273556)
		(end 257.9497 -381.130556)
		(width 0.254)
		(layer "F.Cu")
		(net "DRAWER_MOSFET_G")
	)
	(segment
		(start 261.92226 -374.837706)
		(end 260.43255 -374.837706)
		(width 0.254)
		(layer "F.Cu")
		(net "DRAWER_MOSFET_G")
	)
	(segment
		(start 257.9497 -380.038356)
		(end 257.9497 -379.631956)
		(width 0.254)
		(layer "F.Cu")
		(net "DRAWER_MOSFET_G")
	)
	(segment
		(start 265.0871 -382.273556)
		(end 259.0927 -382.273556)
		(width 0.254)
		(layer "F.Cu")
		(net "DRAWER_MOSFET_G")
	)
	(segment
		(start 260.43255 -374.837706)
		(end 259.207 -376.063256)
		(width 0.254)
		(layer "F.Cu")
		(net "DRAWER_MOSFET_G")
	)
	(segment
		(start 265.5062 -380.216156)
		(end 265.5062 -381.854456)
		(width 0.254)
		(layer "F.Cu")
		(net "DRAWER_MOSFET_G")
	)
	(segment
		(start 265.5062 -381.854456)
		(end 265.0871 -382.273556)
		(width 0.254)
		(layer "F.Cu")
		(net "DRAWER_MOSFET_G")
	)
	(segment
		(start 262.899652 -373.860314)
		(end 261.92226 -374.837706)
		(width 0.254)
		(layer "F.Cu")
		(net "DRAWER_MOSFET_G")
	)
	(segment
		(start 257.9497 -381.130556)
		(end 257.9497 -380.038356)
		(width 0.254)
		(layer "F.Cu")
		(net "DRAWER_MOSFET_G")
	)
	(segment
		(start 257.9497 -379.631956)
		(end 258.4069 -379.174756)
		(width 0.254)
		(layer "F.Cu")
		(net "DRAWER_MOSFET_G")
	)
	(segment
		(start 258.4069 -379.174756)
		(end 259.207 -379.174756)
		(width 0.254)
		(layer "F.Cu")
		(net "DRAWER_MOSFET_G")
	)
	(via
		(at 257.9497 -380.038356)
		(size 0.6604)
		(drill 0.3302)
		(layers "F.Cu" "B.Cu")
		(net "DRAWER_MOSFET_G")
	)
	(segment
		(start 261.493 -280.6446)
		(end 260.9088 -281.2288)
		(width 0.254)
		(layer "F.Cu")
		(net "AGND_P3V3_STBY")
	)
	(segment
		(start 260.9088 -283.6926)
		(end 261.239 -284.0228)
		(width 0.254)
		(layer "F.Cu")
		(net "AGND_P3V3_STBY")
	)
	(segment
		(start 260.9088 -281.2288)
		(end 260.9088 -283.6926)
		(width 0.254)
		(layer "F.Cu")
		(net "AGND_P3V3_STBY")
	)
	(segment
		(start 261.239 -284.0228)
		(end 261.239 -284.124654)
		(width 0.254)
		(layer "F.Cu")
		(net "AGND_P3V3_STBY")
	)
	(via
		(at 261.239 -284.124654)
		(size 0.6604)
		(drill 0.3048)
		(layers "F.Cu" "B.Cu")
		(net "AGND_P3V3_STBY")
	)
	(via
		(at 261.493 -280.6446)
		(size 0.5588)
		(drill 0.3048)
		(layers "F.Cu" "B.Cu")
		(net "AGND_P3V3_STBY")
	)
	(segment
		(start 261.239 -284.124654)
		(end 260.310122 -284.124654)
		(width 0.254)
		(layer "B.Cu")
		(net "AGND_P3V3_STBY")
	)
	(segment
		(start 254.2413 -214.75954)
		(end 253.873 -215.12784)
		(width 0.17145)
		(layer "F.Cu")
		(net "VOL_SEN_SDA")
	)
	(segment
		(start 255.397 -217.45702)
		(end 255.397 -216.662)
		(width 0.17145)
		(layer "F.Cu")
		(net "VOL_SEN_SDA")
	)
	(segment
		(start 255.397 -216.662)
		(end 255.143 -216.408)
		(width 0.17145)
		(layer "F.Cu")
		(net "VOL_SEN_SDA")
	)
	(segment
		(start 253.873 -215.12784)
		(end 253.873 -215.773)
		(width 0.17145)
		(layer "F.Cu")
		(net "VOL_SEN_SDA")
	)
	(segment
		(start 255.143 -216.408)
		(end 254.508 -216.408)
		(width 0.17145)
		(layer "F.Cu")
		(net "VOL_SEN_SDA")
	)
	(segment
		(start 254.508 -216.408)
		(end 253.873 -215.773)
		(width 0.17145)
		(layer "F.Cu")
		(net "VOL_SEN_SDA")
	)
	(via
		(at 253.873 -215.773)
		(size 0.6604)
		(drill 0.3302)
		(layers "F.Cu" "B.Cu")
		(net "VOL_SEN_SDA")
	)
	(segment
		(start 255.3843 -214.75954)
		(end 255.3843 -215.688164)
		(width 0.17145)
		(layer "F.Cu")
		(net "VOL_SEN_SCL")
	)
	(segment
		(start 255.787652 -216.606882)
		(end 255.551432 -216.370662)
		(width 0.17145)
		(layer "F.Cu")
		(net "VOL_SEN_SCL")
	)
	(segment
		(start 256.04724 -216.877138)
		(end 255.787652 -216.61755)
		(width 0.17145)
		(layer "F.Cu")
		(net "VOL_SEN_SCL")
	)
	(segment
		(start 255.551432 -215.855296)
		(end 255.3843 -215.688164)
		(width 0.17145)
		(layer "F.Cu")
		(net "VOL_SEN_SCL")
	)
	(segment
		(start 255.787652 -216.61755)
		(end 255.787652 -216.606882)
		(width 0.17145)
		(layer "F.Cu")
		(net "VOL_SEN_SCL")
	)
	(segment
		(start 255.551432 -216.370662)
		(end 255.551432 -215.855296)
		(width 0.17145)
		(layer "F.Cu")
		(net "VOL_SEN_SCL")
	)
	(segment
		(start 256.04724 -217.45702)
		(end 256.04724 -216.877138)
		(width 0.17145)
		(layer "F.Cu")
		(net "VOL_SEN_SCL")
	)
	(via
		(at 255.3843 -215.688164)
		(size 0.6604)
		(drill 0.3302)
		(layers "F.Cu" "B.Cu")
		(net "VOL_SEN_SCL")
	)
	(segment
		(start 234.28071 -90.9574)
		(end 234.3658 -90.9574)
		(width 0.17145)
		(layer "F.Cu")
		(net "UART_IOC_B_TX")
	)
	(segment
		(start 224.010728 -80.687418)
		(end 234.28071 -90.9574)
		(width 0.17145)
		(layer "F.Cu")
		(net "UART_IOC_B_TX")
	)
	(segment
		(start 224.010728 -70.61073)
		(end 224.010728 -80.687418)
		(width 0.17145)
		(layer "F.Cu")
		(net "UART_IOC_B_TX")
	)
	(segment
		(start 222.600012 -69.200014)
		(end 224.010728 -70.61073)
		(width 0.17145)
		(layer "F.Cu")
		(net "UART_IOC_B_TX")
	)
	(via
		(at 253.098808 -102.695756)
		(size 0.6096)
		(drill 0.3048)
		(layers "F.Cu" "B.Cu")
		(net "UART_IOC_B_TX")
	)
	(via
		(at 234.3658 -90.9574)
		(size 0.5588)
		(drill 0.3048)
		(layers "F.Cu" "B.Cu")
		(net "UART_IOC_B_TX")
	)
	(segment
		(start 235.585 -92.456)
		(end 240.734596 -97.605596)
		(width 0.17145)
		(layer "B.Cu")
		(net "UART_IOC_B_TX")
	)
	(segment
		(start 258.311142 -107.90809)
		(end 253.098808 -102.695756)
		(width 0.17145)
		(layer "B.Cu")
		(net "UART_IOC_B_TX")
	)
	(segment
		(start 284.236668 -137.922508)
		(end 284.77972 -138.46556)
		(width 0.17145)
		(layer "B.Cu")
		(net "UART_IOC_B_TX")
	)
	(segment
		(start 235.585 -92.1766)
		(end 235.585 -92.456)
		(width 0.17145)
		(layer "B.Cu")
		(net "UART_IOC_B_TX")
	)
	(segment
		(start 289.16884 -138.46556)
		(end 290.372292 -137.262108)
		(width 0.17145)
		(layer "B.Cu")
		(net "UART_IOC_B_TX")
	)
	(segment
		(start 290.372292 -137.262108)
		(end 290.372292 -131.66344)
		(width 0.17145)
		(layer "B.Cu")
		(net "UART_IOC_B_TX")
	)
	(segment
		(start 284.236668 -137.494518)
		(end 284.236668 -137.922508)
		(width 0.17145)
		(layer "B.Cu")
		(net "UART_IOC_B_TX")
	)
	(segment
		(start 248.008648 -97.605596)
		(end 253.098808 -102.695756)
		(width 0.17145)
		(layer "B.Cu")
		(net "UART_IOC_B_TX")
	)
	(segment
		(start 285.080202 -126.37135)
		(end 280.280618 -126.37135)
		(width 0.17145)
		(layer "B.Cu")
		(net "UART_IOC_B_TX")
	)
	(segment
		(start 284.77972 -138.46556)
		(end 289.16884 -138.46556)
		(width 0.17145)
		(layer "B.Cu")
		(net "UART_IOC_B_TX")
	)
	(segment
		(start 240.734596 -97.605596)
		(end 248.008648 -97.605596)
		(width 0.17145)
		(layer "B.Cu")
		(net "UART_IOC_B_TX")
	)
	(segment
		(start 261.817358 -107.90809)
		(end 258.311142 -107.90809)
		(width 0.17145)
		(layer "B.Cu")
		(net "UART_IOC_B_TX")
	)
	(segment
		(start 234.3658 -90.9574)
		(end 235.585 -92.1766)
		(width 0.17145)
		(layer "B.Cu")
		(net "UART_IOC_B_TX")
	)
	(segment
		(start 290.372292 -131.66344)
		(end 285.080202 -126.37135)
		(width 0.17145)
		(layer "B.Cu")
		(net "UART_IOC_B_TX")
	)
	(segment
		(start 280.280618 -126.37135)
		(end 261.817358 -107.90809)
		(width 0.17145)
		(layer "B.Cu")
		(net "UART_IOC_B_TX")
	)
	(segment
		(start 223.331278 -80.989678)
		(end 234.3912 -92.0496)
		(width 0.17145)
		(layer "F.Cu")
		(net "UART_IOC_B_RX")
	)
	(segment
		(start 223.331278 -71.331328)
		(end 223.331278 -80.989678)
		(width 0.17145)
		(layer "F.Cu")
		(net "UART_IOC_B_RX")
	)
	(segment
		(start 222.600012 -70.600062)
		(end 223.331278 -71.331328)
		(width 0.17145)
		(layer "F.Cu")
		(net "UART_IOC_B_RX")
	)
	(via
		(at 234.3912 -92.0496)
		(size 0.5588)
		(drill 0.3048)
		(layers "F.Cu" "B.Cu")
		(net "UART_IOC_B_RX")
	)
	(via
		(at 248.169938 -99.877118)
		(size 0.6096)
		(drill 0.3048)
		(layers "F.Cu" "B.Cu")
		(net "UART_IOC_B_RX")
	)
	(segment
		(start 289.56635 -135.51027)
		(end 289.56635 -131.818634)
		(width 0.17145)
		(layer "B.Cu")
		(net "UART_IOC_B_RX")
	)
	(segment
		(start 279.94102 -127.0508)
		(end 261.47776 -108.58754)
		(width 0.17145)
		(layer "B.Cu")
		(net "UART_IOC_B_RX")
	)
	(segment
		(start 289.56635 -131.818634)
		(end 284.798516 -127.0508)
		(width 0.17145)
		(layer "B.Cu")
		(net "UART_IOC_B_RX")
	)
	(segment
		(start 282.83662 -137.494518)
		(end 282.83662 -137.17524)
		(width 0.17145)
		(layer "B.Cu")
		(net "UART_IOC_B_RX")
	)
	(segment
		(start 261.47776 -108.58754)
		(end 256.88036 -108.58754)
		(width 0.17145)
		(layer "B.Cu")
		(net "UART_IOC_B_RX")
	)
	(segment
		(start 246.621046 -98.328226)
		(end 248.169938 -99.877118)
		(width 0.17145)
		(layer "B.Cu")
		(net "UART_IOC_B_RX")
	)
	(segment
		(start 234.70997 -92.54363)
		(end 240.494566 -98.328226)
		(width 0.17145)
		(layer "B.Cu")
		(net "UART_IOC_B_RX")
	)
	(segment
		(start 234.3912 -92.0496)
		(end 234.70997 -92.36837)
		(width 0.17145)
		(layer "B.Cu")
		(net "UART_IOC_B_RX")
	)
	(segment
		(start 256.88036 -108.58754)
		(end 248.169938 -99.877118)
		(width 0.17145)
		(layer "B.Cu")
		(net "UART_IOC_B_RX")
	)
	(segment
		(start 282.83662 -137.17524)
		(end 283.62148 -136.39038)
		(width 0.17145)
		(layer "B.Cu")
		(net "UART_IOC_B_RX")
	)
	(segment
		(start 284.798516 -127.0508)
		(end 279.94102 -127.0508)
		(width 0.17145)
		(layer "B.Cu")
		(net "UART_IOC_B_RX")
	)
	(segment
		(start 234.70997 -92.36837)
		(end 234.70997 -92.54363)
		(width 0.17145)
		(layer "B.Cu")
		(net "UART_IOC_B_RX")
	)
	(segment
		(start 240.494566 -98.328226)
		(end 246.621046 -98.328226)
		(width 0.17145)
		(layer "B.Cu")
		(net "UART_IOC_B_RX")
	)
	(segment
		(start 283.62148 -136.39038)
		(end 288.68624 -136.39038)
		(width 0.17145)
		(layer "B.Cu")
		(net "UART_IOC_B_RX")
	)
	(segment
		(start 288.68624 -136.39038)
		(end 289.56635 -135.51027)
		(width 0.17145)
		(layer "B.Cu")
		(net "UART_IOC_B_RX")
	)
	(via
		(at 217.9574 -215.9)
		(size 0.5588)
		(drill 0.3048)
		(layers "F.Cu" "B.Cu")
		(net "UART_EXP_B_TX")
	)
	(segment
		(start 219.133928 -214.723472)
		(end 217.9574 -215.9)
		(width 0.14605)
		(layer "In2.Cu")
		(net "UART_EXP_B_TX")
	)
	(segment
		(start 222.03791 -84.078572)
		(end 221.927674 -84.188808)
		(width 0.14605)
		(layer "In2.Cu")
		(net "UART_EXP_B_TX")
	)
	(segment
		(start 219.133928 -170.572938)
		(end 219.133928 -214.723472)
		(width 0.14605)
		(layer "In2.Cu")
		(net "UART_EXP_B_TX")
	)
	(segment
		(start 221.9452 -79.531718)
		(end 222.03791 -79.624428)
		(width 0.14605)
		(layer "In2.Cu")
		(net "UART_EXP_B_TX")
	)
	(segment
		(start 217.371422 -117.819932)
		(end 216.166954 -119.0244)
		(width 0.14605)
		(layer "In2.Cu")
		(net "UART_EXP_B_TX")
	)
	(segment
		(start 217.371422 -104.617012)
		(end 217.371422 -117.819932)
		(width 0.14605)
		(layer "In2.Cu")
		(net "UART_EXP_B_TX")
	)
	(segment
		(start 221.927674 -84.188808)
		(end 221.927674 -100.06076)
		(width 0.14605)
		(layer "In2.Cu")
		(net "UART_EXP_B_TX")
	)
	(segment
		(start 218.03614 -161.027364)
		(end 218.03614 -169.47515)
		(width 0.14605)
		(layer "In2.Cu")
		(net "UART_EXP_B_TX")
	)
	(segment
		(start 222.03791 -79.624428)
		(end 222.03791 -84.078572)
		(width 0.14605)
		(layer "In2.Cu")
		(net "UART_EXP_B_TX")
	)
	(segment
		(start 221.9452 -67.945)
		(end 221.9452 -79.531718)
		(width 0.14605)
		(layer "In2.Cu")
		(net "UART_EXP_B_TX")
	)
	(segment
		(start 216.166954 -119.0244)
		(end 216.166954 -159.158178)
		(width 0.14605)
		(layer "In2.Cu")
		(net "UART_EXP_B_TX")
	)
	(segment
		(start 216.166954 -159.158178)
		(end 218.03614 -161.027364)
		(width 0.14605)
		(layer "In2.Cu")
		(net "UART_EXP_B_TX")
	)
	(segment
		(start 218.03614 -169.47515)
		(end 219.133928 -170.572938)
		(width 0.14605)
		(layer "In2.Cu")
		(net "UART_EXP_B_TX")
	)
	(segment
		(start 221.927674 -100.06076)
		(end 217.371422 -104.617012)
		(width 0.14605)
		(layer "In2.Cu")
		(net "UART_EXP_B_TX")
	)
	(segment
		(start 220.800168 -66.799968)
		(end 221.9452 -67.945)
		(width 0.14605)
		(layer "In2.Cu")
		(net "UART_EXP_B_TX")
	)
	(segment
		(start 238.571532 -219.456)
		(end 231.423718 -219.456)
		(width 0.14605)
		(layer "In5.Cu")
		(net "UART_EXP_B_TX")
	)
	(segment
		(start 243.181886 -221.30512)
		(end 240.420652 -221.30512)
		(width 0.14605)
		(layer "In5.Cu")
		(net "UART_EXP_B_TX")
	)
	(segment
		(start 283.078428 -218.252802)
		(end 272.784316 -218.252802)
		(width 0.14605)
		(layer "In5.Cu")
		(net "UART_EXP_B_TX")
	)
	(segment
		(start 270.869918 -220.1672)
		(end 244.319806 -220.1672)
		(width 0.14605)
		(layer "In5.Cu")
		(net "UART_EXP_B_TX")
	)
	(segment
		(start 240.420652 -221.30512)
		(end 238.571532 -219.456)
		(width 0.14605)
		(layer "In5.Cu")
		(net "UART_EXP_B_TX")
	)
	(segment
		(start 272.784316 -218.252802)
		(end 270.869918 -220.1672)
		(width 0.14605)
		(layer "In5.Cu")
		(net "UART_EXP_B_TX")
	)
	(segment
		(start 222.178372 -216.24925)
		(end 221.752922 -215.8238)
		(width 0.14605)
		(layer "In5.Cu")
		(net "UART_EXP_B_TX")
	)
	(segment
		(start 284.236668 -217.094562)
		(end 283.078428 -218.252802)
		(width 0.14605)
		(layer "In5.Cu")
		(net "UART_EXP_B_TX")
	)
	(segment
		(start 231.423718 -219.456)
		(end 228.216968 -216.24925)
		(width 0.14605)
		(layer "In5.Cu")
		(net "UART_EXP_B_TX")
	)
	(segment
		(start 221.752922 -215.8238)
		(end 218.0336 -215.8238)
		(width 0.14605)
		(layer "In5.Cu")
		(net "UART_EXP_B_TX")
	)
	(segment
		(start 244.319806 -220.1672)
		(end 243.181886 -221.30512)
		(width 0.14605)
		(layer "In5.Cu")
		(net "UART_EXP_B_TX")
	)
	(segment
		(start 218.0336 -215.8238)
		(end 217.9574 -215.9)
		(width 0.14605)
		(layer "In5.Cu")
		(net "UART_EXP_B_TX")
	)
	(segment
		(start 228.216968 -216.24925)
		(end 222.178372 -216.24925)
		(width 0.14605)
		(layer "In5.Cu")
		(net "UART_EXP_B_TX")
	)
	(via
		(at 218.059 -214.8078)
		(size 0.5588)
		(drill 0.3048)
		(layers "F.Cu" "B.Cu")
		(net "UART_EXP_B_RX")
	)
	(segment
		(start 221.44355 -68.843398)
		(end 221.44355 -80.1878)
		(width 0.14605)
		(layer "In2.Cu")
		(net "UART_EXP_B_RX")
	)
	(segment
		(start 217.090752 -161.007044)
		(end 217.090752 -173.040802)
		(width 0.14605)
		(layer "In2.Cu")
		(net "UART_EXP_B_RX")
	)
	(segment
		(start 221.38386 -83.803998)
		(end 220.994986 -84.192872)
		(width 0.14605)
		(layer "In2.Cu")
		(net "UART_EXP_B_RX")
	)
	(segment
		(start 216.717372 -104.051608)
		(end 216.717372 -117.548914)
		(width 0.14605)
		(layer "In2.Cu")
		(net "UART_EXP_B_RX")
	)
	(segment
		(start 215.512904 -159.429196)
		(end 217.090752 -161.007044)
		(width 0.14605)
		(layer "In2.Cu")
		(net "UART_EXP_B_RX")
	)
	(segment
		(start 221.44355 -80.1878)
		(end 221.38386 -80.24749)
		(width 0.14605)
		(layer "In2.Cu")
		(net "UART_EXP_B_RX")
	)
	(segment
		(start 218.479878 -214.386922)
		(end 218.059 -214.8078)
		(width 0.14605)
		(layer "In2.Cu")
		(net "UART_EXP_B_RX")
	)
	(segment
		(start 221.38386 -80.24749)
		(end 221.38386 -83.803998)
		(width 0.14605)
		(layer "In2.Cu")
		(net "UART_EXP_B_RX")
	)
	(segment
		(start 220.994986 -84.192872)
		(end 220.994986 -99.773994)
		(width 0.14605)
		(layer "In2.Cu")
		(net "UART_EXP_B_RX")
	)
	(segment
		(start 218.479878 -174.429928)
		(end 218.479878 -214.386922)
		(width 0.14605)
		(layer "In2.Cu")
		(net "UART_EXP_B_RX")
	)
	(segment
		(start 217.090752 -173.040802)
		(end 218.479878 -174.429928)
		(width 0.14605)
		(layer "In2.Cu")
		(net "UART_EXP_B_RX")
	)
	(segment
		(start 216.717372 -117.548914)
		(end 215.512904 -118.753382)
		(width 0.14605)
		(layer "In2.Cu")
		(net "UART_EXP_B_RX")
	)
	(segment
		(start 215.512904 -118.753382)
		(end 215.512904 -159.429196)
		(width 0.14605)
		(layer "In2.Cu")
		(net "UART_EXP_B_RX")
	)
	(segment
		(start 220.800168 -68.200016)
		(end 221.44355 -68.843398)
		(width 0.14605)
		(layer "In2.Cu")
		(net "UART_EXP_B_RX")
	)
	(segment
		(start 220.994986 -99.773994)
		(end 216.717372 -104.051608)
		(width 0.14605)
		(layer "In2.Cu")
		(net "UART_EXP_B_RX")
	)
	(segment
		(start 282.18765 -217.743532)
		(end 277.396194 -217.743532)
		(width 0.14605)
		(layer "In5.Cu")
		(net "UART_EXP_B_RX")
	)
	(segment
		(start 244.1194 -219.4306)
		(end 242.89893 -220.65107)
		(width 0.14605)
		(layer "In5.Cu")
		(net "UART_EXP_B_RX")
	)
	(segment
		(start 277.20417 -217.551508)
		(end 265.353292 -217.551508)
		(width 0.14605)
		(layer "In5.Cu")
		(net "UART_EXP_B_RX")
	)
	(segment
		(start 282.83662 -217.094562)
		(end 282.18765 -217.743532)
		(width 0.14605)
		(layer "In5.Cu")
		(net "UART_EXP_B_RX")
	)
	(segment
		(start 263.4742 -219.4306)
		(end 244.1194 -219.4306)
		(width 0.14605)
		(layer "In5.Cu")
		(net "UART_EXP_B_RX")
	)
	(segment
		(start 228.487986 -215.5952)
		(end 222.44939 -215.5952)
		(width 0.14605)
		(layer "In5.Cu")
		(net "UART_EXP_B_RX")
	)
	(segment
		(start 231.535986 -218.6432)
		(end 228.487986 -215.5952)
		(width 0.14605)
		(layer "In5.Cu")
		(net "UART_EXP_B_RX")
	)
	(segment
		(start 240.69167 -220.65107)
		(end 238.6838 -218.6432)
		(width 0.14605)
		(layer "In5.Cu")
		(net "UART_EXP_B_RX")
	)
	(segment
		(start 277.396194 -217.743532)
		(end 277.20417 -217.551508)
		(width 0.14605)
		(layer "In5.Cu")
		(net "UART_EXP_B_RX")
	)
	(segment
		(start 218.207336 -214.956136)
		(end 218.059 -214.8078)
		(width 0.14605)
		(layer "In5.Cu")
		(net "UART_EXP_B_RX")
	)
	(segment
		(start 222.44939 -215.5952)
		(end 221.810326 -214.956136)
		(width 0.14605)
		(layer "In5.Cu")
		(net "UART_EXP_B_RX")
	)
	(segment
		(start 265.353292 -217.551508)
		(end 263.4742 -219.4306)
		(width 0.14605)
		(layer "In5.Cu")
		(net "UART_EXP_B_RX")
	)
	(segment
		(start 238.6838 -218.6432)
		(end 231.535986 -218.6432)
		(width 0.14605)
		(layer "In5.Cu")
		(net "UART_EXP_B_RX")
	)
	(segment
		(start 242.89893 -220.65107)
		(end 240.69167 -220.65107)
		(width 0.14605)
		(layer "In5.Cu")
		(net "UART_EXP_B_RX")
	)
	(segment
		(start 221.810326 -214.956136)
		(end 218.207336 -214.956136)
		(width 0.14605)
		(layer "In5.Cu")
		(net "UART_EXP_B_RX")
	)
	(segment
		(start 459.3082 -12.8143)
		(end 459.3082 -11.7348)
		(width 0.17145)
		(layer "F.Cu")
		(net "TEMP2_SDA")
	)
	(segment
		(start 458.475334 -10.054844)
		(end 458.475334 -10.901934)
		(width 0.17145)
		(layer "F.Cu")
		(net "TEMP2_SDA")
	)
	(segment
		(start 458.475334 -10.901934)
		(end 459.2828 -11.7094)
		(width 0.17145)
		(layer "F.Cu")
		(net "TEMP2_SDA")
	)
	(segment
		(start 459.3082 -11.7348)
		(end 459.2828 -11.7094)
		(width 0.17145)
		(layer "F.Cu")
		(net "TEMP2_SDA")
	)
	(via
		(at 459.2828 -11.7094)
		(size 0.6604)
		(drill 0.3302)
		(layers "F.Cu" "B.Cu")
		(net "TEMP2_SDA")
	)
	(segment
		(start 458.1906 -12.6619)
		(end 458.1906 -11.7094)
		(width 0.17145)
		(layer "F.Cu")
		(net "TEMP2_SCL")
	)
	(segment
		(start 457.825094 -11.343894)
		(end 458.1906 -11.7094)
		(width 0.17145)
		(layer "F.Cu")
		(net "TEMP2_SCL")
	)
	(segment
		(start 458.0636 -12.7889)
		(end 458.1906 -12.6619)
		(width 0.17145)
		(layer "F.Cu")
		(net "TEMP2_SCL")
	)
	(segment
		(start 457.825094 -10.054844)
		(end 457.825094 -11.343894)
		(width 0.17145)
		(layer "F.Cu")
		(net "TEMP2_SCL")
	)
	(via
		(at 458.1906 -11.7094)
		(size 0.6604)
		(drill 0.3302)
		(layers "F.Cu" "B.Cu")
		(net "TEMP2_SCL")
	)
	(segment
		(start 457.5048 -9.017)
		(end 459.2574 -9.017)
		(width 0.17145)
		(layer "F.Cu")
		(net "TEMP2_ALERT")
	)
	(segment
		(start 457.174854 -9.346946)
		(end 457.5048 -9.017)
		(width 0.17145)
		(layer "F.Cu")
		(net "TEMP2_ALERT")
	)
	(segment
		(start 459.9432 -9.7028)
		(end 460.4512 -9.7028)
		(width 0.17145)
		(layer "F.Cu")
		(net "TEMP2_ALERT")
	)
	(segment
		(start 459.2574 -9.017)
		(end 459.9432 -9.7028)
		(width 0.17145)
		(layer "F.Cu")
		(net "TEMP2_ALERT")
	)
	(segment
		(start 457.174854 -10.054844)
		(end 457.174854 -9.346946)
		(width 0.17145)
		(layer "F.Cu")
		(net "TEMP2_ALERT")
	)
	(segment
		(start 467.0679 -5.3594)
		(end 466.9663 -5.2578)
		(width 0.17145)
		(layer "F.Cu")
		(net "TEMP2_A2")
	)
	(segment
		(start 466.0392 -5.3086)
		(end 466.09 -5.2578)
		(width 0.17145)
		(layer "F.Cu")
		(net "TEMP2_A2")
	)
	(segment
		(start 465.0613 -5.0673)
		(end 465.0613 -5.3086)
		(width 0.17145)
		(layer "F.Cu")
		(net "TEMP2_A2")
	)
	(segment
		(start 456.524614 -4.67233)
		(end 457.901294 -3.29565)
		(width 0.17145)
		(layer "F.Cu")
		(net "TEMP2_A2")
	)
	(segment
		(start 457.901294 -3.29565)
		(end 463.28965 -3.29565)
		(width 0.17145)
		(layer "F.Cu")
		(net "TEMP2_A2")
	)
	(segment
		(start 463.28965 -3.29565)
		(end 465.0613 -5.0673)
		(width 0.17145)
		(layer "F.Cu")
		(net "TEMP2_A2")
	)
	(segment
		(start 465.0613 -5.3086)
		(end 466.0392 -5.3086)
		(width 0.17145)
		(layer "F.Cu")
		(net "TEMP2_A2")
	)
	(segment
		(start 466.9663 -5.2578)
		(end 466.09 -5.2578)
		(width 0.17145)
		(layer "F.Cu")
		(net "TEMP2_A2")
	)
	(segment
		(start 456.524614 -5.945124)
		(end 456.524614 -4.67233)
		(width 0.17145)
		(layer "F.Cu")
		(net "TEMP2_A2")
	)
	(via
		(at 466.09 -5.2578)
		(size 0.6604)
		(drill 0.3302)
		(layers "F.Cu" "B.Cu")
		(net "TEMP2_A2")
	)
	(segment
		(start 463.438494 -7.05485)
		(end 463.479896 -7.096252)
		(width 0.17145)
		(layer "F.Cu")
		(net "TEMP2_A1")
	)
	(segment
		(start 466.09 -6.477)
		(end 465.1629 -6.477)
		(width 0.17145)
		(layer "F.Cu")
		(net "TEMP2_A1")
	)
	(segment
		(start 461.153256 -3.81)
		(end 462.239614 -4.896358)
		(width 0.17145)
		(layer "F.Cu")
		(net "TEMP2_A1")
	)
	(segment
		(start 457.174854 -5.945124)
		(end 457.174854 -4.749546)
		(width 0.17145)
		(layer "F.Cu")
		(net "TEMP2_A1")
	)
	(segment
		(start 467.0679 -6.4008)
		(end 466.9917 -6.477)
		(width 0.17145)
		(layer "F.Cu")
		(net "TEMP2_A1")
	)
	(segment
		(start 462.239614 -4.896358)
		(end 462.239614 -6.140958)
		(width 0.17145)
		(layer "F.Cu")
		(net "TEMP2_A1")
	)
	(segment
		(start 466.9917 -6.477)
		(end 466.09 -6.477)
		(width 0.17145)
		(layer "F.Cu")
		(net "TEMP2_A1")
	)
	(segment
		(start 462.239614 -6.140958)
		(end 463.153506 -7.05485)
		(width 0.17145)
		(layer "F.Cu")
		(net "TEMP2_A1")
	)
	(segment
		(start 464.893152 -6.543548)
		(end 465.0613 -6.3754)
		(width 0.17145)
		(layer "F.Cu")
		(net "TEMP2_A1")
	)
	(segment
		(start 463.479896 -7.096252)
		(end 464.471258 -7.096252)
		(width 0.17145)
		(layer "F.Cu")
		(net "TEMP2_A1")
	)
	(segment
		(start 464.471258 -7.096252)
		(end 464.893152 -6.674358)
		(width 0.17145)
		(layer "F.Cu")
		(net "TEMP2_A1")
	)
	(segment
		(start 463.153506 -7.05485)
		(end 463.438494 -7.05485)
		(width 0.17145)
		(layer "F.Cu")
		(net "TEMP2_A1")
	)
	(segment
		(start 464.893152 -6.674358)
		(end 464.893152 -6.543548)
		(width 0.17145)
		(layer "F.Cu")
		(net "TEMP2_A1")
	)
	(segment
		(start 458.1144 -3.81)
		(end 461.153256 -3.81)
		(width 0.17145)
		(layer "F.Cu")
		(net "TEMP2_A1")
	)
	(segment
		(start 457.174854 -4.749546)
		(end 458.1144 -3.81)
		(width 0.17145)
		(layer "F.Cu")
		(net "TEMP2_A1")
	)
	(segment
		(start 465.1629 -6.477)
		(end 465.0613 -6.3754)
		(width 0.17145)
		(layer "F.Cu")
		(net "TEMP2_A1")
	)
	(via
		(at 466.09 -6.477)
		(size 0.6604)
		(drill 0.3302)
		(layers "F.Cu" "B.Cu")
		(net "TEMP2_A1")
	)
	(segment
		(start 461.1116 -4.4958)
		(end 460.1972 -4.4958)
		(width 0.17145)
		(layer "F.Cu")
		(net "TEMP2_A0")
	)
	(segment
		(start 463.6389 -8.128)
		(end 463.0801 -7.5692)
		(width 0.17145)
		(layer "F.Cu")
		(net "TEMP2_A0")
	)
	(segment
		(start 458.1906 -4.4958)
		(end 460.1972 -4.4958)
		(width 0.17145)
		(layer "F.Cu")
		(net "TEMP2_A0")
	)
	(segment
		(start 461.725264 -5.109464)
		(end 461.1116 -4.4958)
		(width 0.17145)
		(layer "F.Cu")
		(net "TEMP2_A0")
	)
	(segment
		(start 457.825094 -4.861306)
		(end 458.1906 -4.4958)
		(width 0.17145)
		(layer "F.Cu")
		(net "TEMP2_A0")
	)
	(segment
		(start 461.725264 -6.354064)
		(end 461.725264 -5.109464)
		(width 0.17145)
		(layer "F.Cu")
		(net "TEMP2_A0")
	)
	(segment
		(start 466.0773 -7.4422)
		(end 465.3915 -8.128)
		(width 0.17145)
		(layer "F.Cu")
		(net "TEMP2_A0")
	)
	(segment
		(start 463.0801 -7.5692)
		(end 462.9404 -7.5692)
		(width 0.17145)
		(layer "F.Cu")
		(net "TEMP2_A0")
	)
	(segment
		(start 465.3915 -8.128)
		(end 463.6389 -8.128)
		(width 0.17145)
		(layer "F.Cu")
		(net "TEMP2_A0")
	)
	(segment
		(start 462.9404 -7.5692)
		(end 461.725264 -6.354064)
		(width 0.17145)
		(layer "F.Cu")
		(net "TEMP2_A0")
	)
	(segment
		(start 457.825094 -5.945124)
		(end 457.825094 -4.861306)
		(width 0.17145)
		(layer "F.Cu")
		(net "TEMP2_A0")
	)
	(via
		(at 460.1972 -4.4958)
		(size 0.6604)
		(drill 0.3302)
		(layers "F.Cu" "B.Cu")
		(net "TEMP2_A0")
	)
	(segment
		(start 35.741356 -10.385044)
		(end 35.8648 -10.2616)
		(width 0.17145)
		(layer "F.Cu")
		(net "TEMP1_SDA")
	)
	(segment
		(start 36.7538 -10.3632)
		(end 36.6776 -10.287)
		(width 0.17145)
		(layer "F.Cu")
		(net "TEMP1_SDA")
	)
	(segment
		(start 34.925254 -10.385044)
		(end 35.741356 -10.385044)
		(width 0.17145)
		(layer "F.Cu")
		(net "TEMP1_SDA")
	)
	(segment
		(start 36.7538 -11.1125)
		(end 36.7538 -10.3632)
		(width 0.17145)
		(layer "F.Cu")
		(net "TEMP1_SDA")
	)
	(segment
		(start 36.6522 -10.2616)
		(end 36.6776 -10.287)
		(width 0.17145)
		(layer "F.Cu")
		(net "TEMP1_SDA")
	)
	(segment
		(start 35.8648 -10.2616)
		(end 36.6522 -10.2616)
		(width 0.17145)
		(layer "F.Cu")
		(net "TEMP1_SDA")
	)
	(segment
		(start 36.5887 -11.2776)
		(end 36.7538 -11.1125)
		(width 0.17145)
		(layer "F.Cu")
		(net "TEMP1_SDA")
	)
	(via
		(at 36.6776 -10.287)
		(size 0.6604)
		(drill 0.3302)
		(layers "F.Cu" "B.Cu")
		(net "TEMP1_SDA")
	)
	(segment
		(start 34.275014 -10.385044)
		(end 34.275014 -11.415014)
		(width 0.17145)
		(layer "F.Cu")
		(net "TEMP1_SCL")
	)
	(segment
		(start 35.6362 -12.319)
		(end 35.6108 -12.2936)
		(width 0.17145)
		(layer "F.Cu")
		(net "TEMP1_SCL")
	)
	(segment
		(start 36.5887 -12.319)
		(end 35.6362 -12.319)
		(width 0.17145)
		(layer "F.Cu")
		(net "TEMP1_SCL")
	)
	(segment
		(start 34.275014 -11.415014)
		(end 35.1536 -12.2936)
		(width 0.17145)
		(layer "F.Cu")
		(net "TEMP1_SCL")
	)
	(segment
		(start 35.1536 -12.2936)
		(end 35.6108 -12.2936)
		(width 0.17145)
		(layer "F.Cu")
		(net "TEMP1_SCL")
	)
	(via
		(at 35.6108 -12.2936)
		(size 0.6604)
		(drill 0.3302)
		(layers "F.Cu" "B.Cu")
		(net "TEMP1_SCL")
	)
	(segment
		(start 37.823394 -9.375394)
		(end 37.9222 -9.4742)
		(width 0.17145)
		(layer "F.Cu")
		(net "TEMP1_ALERT")
	)
	(segment
		(start 33.624774 -9.402826)
		(end 34.031174 -8.996426)
		(width 0.17145)
		(layer "F.Cu")
		(net "TEMP1_ALERT")
	)
	(segment
		(start 35.289744 -8.996426)
		(end 35.668712 -9.375394)
		(width 0.17145)
		(layer "F.Cu")
		(net "TEMP1_ALERT")
	)
	(segment
		(start 34.031174 -8.996426)
		(end 35.289744 -8.996426)
		(width 0.17145)
		(layer "F.Cu")
		(net "TEMP1_ALERT")
	)
	(segment
		(start 35.668712 -9.375394)
		(end 37.823394 -9.375394)
		(width 0.17145)
		(layer "F.Cu")
		(net "TEMP1_ALERT")
	)
	(segment
		(start 33.624774 -10.385044)
		(end 33.624774 -9.402826)
		(width 0.17145)
		(layer "F.Cu")
		(net "TEMP1_ALERT")
	)
	(segment
		(start 34.35096 -3.42265)
		(end 40.65905 -3.42265)
		(width 0.17145)
		(layer "F.Cu")
		(net "TEMP1_A2")
	)
	(segment
		(start 42.5704 -5.3594)
		(end 42.7228 -5.207)
		(width 0.17145)
		(layer "F.Cu")
		(net "TEMP1_A2")
	)
	(segment
		(start 41.7195 -5.3594)
		(end 42.5704 -5.3594)
		(width 0.17145)
		(layer "F.Cu")
		(net "TEMP1_A2")
	)
	(segment
		(start 32.974534 -6.275324)
		(end 32.974534 -4.799076)
		(width 0.17145)
		(layer "F.Cu")
		(net "TEMP1_A2")
	)
	(segment
		(start 32.974534 -4.799076)
		(end 34.35096 -3.42265)
		(width 0.17145)
		(layer "F.Cu")
		(net "TEMP1_A2")
	)
	(segment
		(start 43.6245 -5.207)
		(end 42.7228 -5.207)
		(width 0.17145)
		(layer "F.Cu")
		(net "TEMP1_A2")
	)
	(segment
		(start 40.65905 -3.42265)
		(end 41.7195 -4.4831)
		(width 0.17145)
		(layer "F.Cu")
		(net "TEMP1_A2")
	)
	(segment
		(start 43.7261 -5.3086)
		(end 43.6245 -5.207)
		(width 0.17145)
		(layer "F.Cu")
		(net "TEMP1_A2")
	)
	(segment
		(start 41.7195 -4.4831)
		(end 41.7195 -5.3594)
		(width 0.17145)
		(layer "F.Cu")
		(net "TEMP1_A2")
	)
	(via
		(at 42.7228 -5.207)
		(size 0.6604)
		(drill 0.3302)
		(layers "F.Cu" "B.Cu")
		(net "TEMP1_A2")
	)
	(segment
		(start 38.989 -6.201156)
		(end 39.884096 -7.096252)
		(width 0.17145)
		(layer "F.Cu")
		(net "TEMP1_A1")
	)
	(segment
		(start 43.6753 -6.4262)
		(end 42.6974 -6.4262)
		(width 0.17145)
		(layer "F.Cu")
		(net "TEMP1_A1")
	)
	(segment
		(start 34.7726 -3.937)
		(end 38.564058 -3.937)
		(width 0.17145)
		(layer "F.Cu")
		(net "TEMP1_A1")
	)
	(segment
		(start 42.6466 -6.3754)
		(end 42.6974 -6.4262)
		(width 0.17145)
		(layer "F.Cu")
		(net "TEMP1_A1")
	)
	(segment
		(start 38.989 -4.361942)
		(end 38.989 -6.201156)
		(width 0.17145)
		(layer "F.Cu")
		(net "TEMP1_A1")
	)
	(segment
		(start 43.7261 -6.3754)
		(end 43.6753 -6.4262)
		(width 0.17145)
		(layer "F.Cu")
		(net "TEMP1_A1")
	)
	(segment
		(start 41.7195 -6.3754)
		(end 42.6466 -6.3754)
		(width 0.17145)
		(layer "F.Cu")
		(net "TEMP1_A1")
	)
	(segment
		(start 33.624774 -5.084826)
		(end 34.7726 -3.937)
		(width 0.17145)
		(layer "F.Cu")
		(net "TEMP1_A1")
	)
	(segment
		(start 39.884096 -7.096252)
		(end 41.002458 -7.096252)
		(width 0.17145)
		(layer "F.Cu")
		(net "TEMP1_A1")
	)
	(segment
		(start 38.564058 -3.937)
		(end 38.989 -4.361942)
		(width 0.17145)
		(layer "F.Cu")
		(net "TEMP1_A1")
	)
	(segment
		(start 33.624774 -6.275324)
		(end 33.624774 -5.084826)
		(width 0.17145)
		(layer "F.Cu")
		(net "TEMP1_A1")
	)
	(segment
		(start 41.7195 -6.37921)
		(end 41.7195 -6.3754)
		(width 0.17145)
		(layer "F.Cu")
		(net "TEMP1_A1")
	)
	(segment
		(start 41.002458 -7.096252)
		(end 41.7195 -6.37921)
		(width 0.17145)
		(layer "F.Cu")
		(net "TEMP1_A1")
	)
	(via
		(at 42.6974 -6.4262)
		(size 0.6604)
		(drill 0.3302)
		(layers "F.Cu" "B.Cu")
		(net "TEMP1_A1")
	)
	(segment
		(start 42.7609 -7.4168)
		(end 41.5163 -7.4168)
		(width 0.17145)
		(layer "F.Cu")
		(net "TEMP1_A0")
	)
	(segment
		(start 38.39464 -6.334252)
		(end 38.39464 -4.749546)
		(width 0.17145)
		(layer "F.Cu")
		(net "TEMP1_A0")
	)
	(segment
		(start 38.39464 -4.74599)
		(end 38.39464 -4.749546)
		(width 0.17145)
		(layer "F.Cu")
		(net "TEMP1_A0")
	)
	(segment
		(start 38.1 -4.45135)
		(end 38.39464 -4.74599)
		(width 0.17145)
		(layer "F.Cu")
		(net "TEMP1_A0")
	)
	(segment
		(start 39.67099 -7.610602)
		(end 38.39464 -6.334252)
		(width 0.17145)
		(layer "F.Cu")
		(net "TEMP1_A0")
	)
	(segment
		(start 41.5163 -7.4168)
		(end 40.7797 -8.1534)
		(width 0.17145)
		(layer "F.Cu")
		(net "TEMP1_A0")
	)
	(segment
		(start 40.236902 -7.610602)
		(end 39.67099 -7.610602)
		(width 0.17145)
		(layer "F.Cu")
		(net "TEMP1_A0")
	)
	(segment
		(start 34.275014 -6.275324)
		(end 34.275014 -5.164836)
		(width 0.17145)
		(layer "F.Cu")
		(net "TEMP1_A0")
	)
	(segment
		(start 34.9885 -4.45135)
		(end 38.1 -4.45135)
		(width 0.17145)
		(layer "F.Cu")
		(net "TEMP1_A0")
	)
	(segment
		(start 40.7797 -8.1534)
		(end 40.236902 -7.610602)
		(width 0.17145)
		(layer "F.Cu")
		(net "TEMP1_A0")
	)
	(segment
		(start 34.275014 -5.164836)
		(end 34.9885 -4.45135)
		(width 0.17145)
		(layer "F.Cu")
		(net "TEMP1_A0")
	)
	(via
		(at 38.39464 -4.749546)
		(size 0.6604)
		(drill 0.3302)
		(layers "F.Cu" "B.Cu")
		(net "TEMP1_A0")
	)
	(segment
		(start 21.082 -246.253)
		(end 21.082 -246.38)
		(width 0.17145)
		(layer "F.Cu")
		(net "SW_PWR_R_HDD0")
	)
	(segment
		(start 20.828 -249.555)
		(end 22.5425 -249.555)
		(width 0.17145)
		(layer "F.Cu")
		(net "SW_PWR_R_HDD0")
	)
	(segment
		(start 22.5425 -249.555)
		(end 22.5425 -247.015)
		(width 0.17145)
		(layer "F.Cu")
		(net "SW_PWR_R_HDD0")
	)
	(segment
		(start 21.082 -246.780304)
		(end 21.082 -246.38)
		(width 0.17145)
		(layer "F.Cu")
		(net "SW_PWR_R_HDD0")
	)
	(segment
		(start 21.463 -245.872)
		(end 21.082 -246.253)
		(width 0.17145)
		(layer "F.Cu")
		(net "SW_PWR_R_HDD0")
	)
	(segment
		(start 22.5425 -245.872)
		(end 21.463 -245.872)
		(width 0.17145)
		(layer "F.Cu")
		(net "SW_PWR_R_HDD0")
	)
	(segment
		(start 21.316696 -247.015)
		(end 21.082 -246.780304)
		(width 0.17145)
		(layer "F.Cu")
		(net "SW_PWR_R_HDD0")
	)
	(segment
		(start 20.447 -249.936)
		(end 20.828 -249.555)
		(width 0.17145)
		(layer "F.Cu")
		(net "SW_PWR_R_HDD0")
	)
	(segment
		(start 20.447 -250.4948)
		(end 20.447 -249.936)
		(width 0.17145)
		(layer "F.Cu")
		(net "SW_PWR_R_HDD0")
	)
	(segment
		(start 22.5425 -247.015)
		(end 21.316696 -247.015)
		(width 0.17145)
		(layer "F.Cu")
		(net "SW_PWR_R_HDD0")
	)
	(via
		(at 21.082 -246.38)
		(size 0.6604)
		(drill 0.3302)
		(layers "F.Cu" "B.Cu")
		(net "SW_PWR_R_HDD0")
	)
	(segment
		(start 16.891 -246.507)
		(end 16.891 -245.237)
		(width 0.17145)
		(layer "F.Cu")
		(net "SW_HDD_R0")
	)
	(segment
		(start 21.09724 -248.6152)
		(end 21.09724 -247.523)
		(width 0.17145)
		(layer "F.Cu")
		(net "SW_HDD_R0")
	)
	(segment
		(start 15.3035 -246.634)
		(end 15.3035 -245.3005)
		(width 0.17145)
		(layer "F.Cu")
		(net "SW_HDD_R0")
	)
	(segment
		(start 17.526 -246.507)
		(end 17.8435 -246.1895)
		(width 0.17145)
		(layer "F.Cu")
		(net "SW_HDD_R0")
	)
	(segment
		(start 16.891 -245.237)
		(end 16.637 -244.983)
		(width 0.17145)
		(layer "F.Cu")
		(net "SW_HDD_R0")
	)
	(segment
		(start 15.621 -244.983)
		(end 16.002 -244.983)
		(width 0.17145)
		(layer "F.Cu")
		(net "SW_HDD_R0")
	)
	(segment
		(start 21.09724 -247.523)
		(end 19.76374 -246.1895)
		(width 0.17145)
		(layer "F.Cu")
		(net "SW_HDD_R0")
	)
	(segment
		(start 17.8435 -246.1895)
		(end 18.415 -246.1895)
		(width 0.17145)
		(layer "F.Cu")
		(net "SW_HDD_R0")
	)
	(segment
		(start 16.891 -246.507)
		(end 17.526 -246.507)
		(width 0.17145)
		(layer "F.Cu")
		(net "SW_HDD_R0")
	)
	(segment
		(start 16.637 -244.983)
		(end 16.002 -244.983)
		(width 0.17145)
		(layer "F.Cu")
		(net "SW_HDD_R0")
	)
	(segment
		(start 15.3035 -245.3005)
		(end 15.621 -244.983)
		(width 0.17145)
		(layer "F.Cu")
		(net "SW_HDD_R0")
	)
	(segment
		(start 15.24 -246.6975)
		(end 15.3035 -246.634)
		(width 0.17145)
		(layer "F.Cu")
		(net "SW_HDD_R0")
	)
	(segment
		(start 15.24 -247.7135)
		(end 15.24 -246.6975)
		(width 0.17145)
		(layer "F.Cu")
		(net "SW_HDD_R0")
	)
	(segment
		(start 19.76374 -246.1895)
		(end 18.415 -246.1895)
		(width 0.17145)
		(layer "F.Cu")
		(net "SW_HDD_R0")
	)
	(via
		(at 16.002 -244.983)
		(size 0.6604)
		(drill 0.3302)
		(layers "F.Cu" "B.Cu")
		(net "SW_HDD_R0")
	)
	(segment
		(start 18.796 -258.826)
		(end 18.796 -257.302)
		(width 0.17145)
		(layer "F.Cu")
		(net "SW_HDD_P0")
	)
	(segment
		(start 18.796 -257.302)
		(end 17.2085 -255.7145)
		(width 0.17145)
		(layer "F.Cu")
		(net "SW_HDD_P0")
	)
	(segment
		(start 17.2085 -251.5235)
		(end 17.2085 -253.111)
		(width 0.17145)
		(layer "F.Cu")
		(net "SW_HDD_P0")
	)
	(segment
		(start 17.2085 -253.111)
		(end 17.2085 -254.127)
		(width 0.17145)
		(layer "F.Cu")
		(net "SW_HDD_P0")
	)
	(segment
		(start 18.2372 -250.4948)
		(end 17.526 -251.206)
		(width 0.17145)
		(layer "F.Cu")
		(net "SW_HDD_P0")
	)
	(segment
		(start 19.79676 -250.4948)
		(end 18.2372 -250.4948)
		(width 0.17145)
		(layer "F.Cu")
		(net "SW_HDD_P0")
	)
	(segment
		(start 17.2085 -255.7145)
		(end 17.2085 -254.127)
		(width 0.17145)
		(layer "F.Cu")
		(net "SW_HDD_P0")
	)
	(segment
		(start 17.526 -251.206)
		(end 17.2085 -251.5235)
		(width 0.17145)
		(layer "F.Cu")
		(net "SW_HDD_P0")
	)
	(via
		(at 17.526 -251.206)
		(size 0.6604)
		(drill 0.3302)
		(layers "F.Cu" "B.Cu")
		(net "SW_HDD_P0")
	)
	(segment
		(start 15.24 -250.6345)
		(end 15.3035 -250.698)
		(width 0.17145)
		(layer "F.Cu")
		(net "SW_HDD_N0")
	)
	(segment
		(start 15.3035 -250.698)
		(end 15.3035 -254.508)
		(width 0.17145)
		(layer "F.Cu")
		(net "SW_HDD_N0")
	)
	(segment
		(start 15.24 -248.6025)
		(end 15.24 -250.317)
		(width 0.17145)
		(layer "F.Cu")
		(net "SW_HDD_N0")
	)
	(segment
		(start 16.891 -248.793)
		(end 16.7005 -248.6025)
		(width 0.17145)
		(layer "F.Cu")
		(net "SW_HDD_N0")
	)
	(segment
		(start 15.3035 -254.508)
		(end 15.3035 -255.524)
		(width 0.17145)
		(layer "F.Cu")
		(net "SW_HDD_N0")
	)
	(segment
		(start 16.764 -256.9845)
		(end 15.3035 -255.524)
		(width 0.17145)
		(layer "F.Cu")
		(net "SW_HDD_N0")
	)
	(segment
		(start 16.7005 -248.6025)
		(end 15.24 -248.6025)
		(width 0.17145)
		(layer "F.Cu")
		(net "SW_HDD_N0")
	)
	(segment
		(start 16.764 -258.318)
		(end 16.764 -256.9845)
		(width 0.17145)
		(layer "F.Cu")
		(net "SW_HDD_N0")
	)
	(segment
		(start 15.24 -250.317)
		(end 15.24 -250.6345)
		(width 0.17145)
		(layer "F.Cu")
		(net "SW_HDD_N0")
	)
	(via
		(at 15.24 -250.317)
		(size 0.6604)
		(drill 0.3302)
		(layers "F.Cu" "B.Cu")
		(net "SW_HDD_N0")
	)
	(segment
		(start 20.447 -248.6152)
		(end 20.447 -247.8913)
		(width 0.17145)
		(layer "F.Cu")
		(net "SW_HDD_G0")
	)
	(segment
		(start 19.6342 -247.0785)
		(end 18.415 -247.0785)
		(width 0.17145)
		(layer "F.Cu")
		(net "SW_HDD_G0")
	)
	(segment
		(start 20.447 -247.8913)
		(end 19.6342 -247.0785)
		(width 0.17145)
		(layer "F.Cu")
		(net "SW_HDD_G0")
	)
	(via
		(at 19.6342 -247.0785)
		(size 0.6604)
		(drill 0.3302)
		(layers "F.Cu" "B.Cu")
		(net "SW_HDD_G0")
	)
	(segment
		(start 312.74639 -173.75759)
		(end 313.05246 -174.06366)
		(width 0.17145)
		(layer "F.Cu")
		(net "SCC_B_TYPE_2")
	)
	(segment
		(start 288.033206 -172.155104)
		(end 289.635692 -173.75759)
		(width 0.17145)
		(layer "F.Cu")
		(net "SCC_B_TYPE_2")
	)
	(segment
		(start 281.349196 -172.155104)
		(end 288.033206 -172.155104)
		(width 0.17145)
		(layer "F.Cu")
		(net "SCC_B_TYPE_2")
	)
	(segment
		(start 288.85388 -230.331772)
		(end 283.873956 -230.331772)
		(width 0.17145)
		(layer "F.Cu")
		(net "SCC_B_TYPE_2")
	)
	(segment
		(start 294.141652 -225.044)
		(end 288.85388 -230.331772)
		(width 0.17145)
		(layer "F.Cu")
		(net "SCC_B_TYPE_2")
	)
	(segment
		(start 300.9265 -225.044)
		(end 294.141652 -225.044)
		(width 0.17145)
		(layer "F.Cu")
		(net "SCC_B_TYPE_2")
	)
	(segment
		(start 283.873956 -230.331772)
		(end 283.23667 -229.694486)
		(width 0.17145)
		(layer "F.Cu")
		(net "SCC_B_TYPE_2")
	)
	(segment
		(start 300.9265 -225.8568)
		(end 300.9265 -225.044)
		(width 0.17145)
		(layer "F.Cu")
		(net "SCC_B_TYPE_2")
	)
	(segment
		(start 289.635692 -173.75759)
		(end 312.74639 -173.75759)
		(width 0.17145)
		(layer "F.Cu")
		(net "SCC_B_TYPE_2")
	)
	(via
		(at 313.05246 -174.06366)
		(size 0.5588)
		(drill 0.3048)
		(layers "F.Cu" "B.Cu")
		(net "SCC_B_TYPE_2")
	)
	(via
		(at 266.048236 -108.968032)
		(size 0.6096)
		(drill 0.3048)
		(layers "F.Cu" "B.Cu")
		(net "SCC_B_TYPE_2")
	)
	(via
		(at 280.079958 -123.727464)
		(size 0.5588)
		(drill 0.3048)
		(layers "F.Cu" "B.Cu")
		(net "SCC_B_TYPE_2")
	)
	(via
		(at 300.9265 -225.8568)
		(size 0.5588)
		(drill 0.3048)
		(layers "F.Cu" "B.Cu")
		(net "SCC_B_TYPE_2")
	)
	(via
		(at 281.349196 -172.155104)
		(size 0.5588)
		(drill 0.3048)
		(layers "F.Cu" "B.Cu")
		(net "SCC_B_TYPE_2")
	)
	(segment
		(start 227.6602 -79.599282)
		(end 227.6602 -82.83321)
		(width 0.17145)
		(layer "B.Cu")
		(net "SCC_B_TYPE_2")
	)
	(segment
		(start 241.184176 -87.552022)
		(end 247.510554 -93.8784)
		(width 0.17145)
		(layer "B.Cu")
		(net "SCC_B_TYPE_2")
	)
	(segment
		(start 259.527294 -102.44836)
		(end 259.528564 -102.44836)
		(width 0.17145)
		(layer "B.Cu")
		(net "SCC_B_TYPE_2")
	)
	(segment
		(start 259.209032 -102.128828)
		(end 259.209032 -102.130098)
		(width 0.17145)
		(layer "B.Cu")
		(net "SCC_B_TYPE_2")
	)
	(segment
		(start 259.528564 -102.44836)
		(end 266.048236 -108.968032)
		(width 0.17145)
		(layer "B.Cu")
		(net "SCC_B_TYPE_2")
	)
	(segment
		(start 227.6602 -82.83321)
		(end 232.379012 -87.552022)
		(width 0.17145)
		(layer "B.Cu")
		(net "SCC_B_TYPE_2")
	)
	(segment
		(start 266.048236 -108.968032)
		(end 280.079958 -122.999754)
		(width 0.17145)
		(layer "B.Cu")
		(net "SCC_B_TYPE_2")
	)
	(segment
		(start 227.4062 -79.345282)
		(end 227.6602 -79.599282)
		(width 0.17145)
		(layer "B.Cu")
		(net "SCC_B_TYPE_2")
	)
	(segment
		(start 259.209032 -102.130098)
		(end 259.527294 -102.44836)
		(width 0.17145)
		(layer "B.Cu")
		(net "SCC_B_TYPE_2")
	)
	(segment
		(start 228.000052 -77.799946)
		(end 227.4062 -78.393798)
		(width 0.17145)
		(layer "B.Cu")
		(net "SCC_B_TYPE_2")
	)
	(segment
		(start 232.379012 -87.552022)
		(end 241.184176 -87.552022)
		(width 0.17145)
		(layer "B.Cu")
		(net "SCC_B_TYPE_2")
	)
	(segment
		(start 227.4062 -78.393798)
		(end 227.4062 -79.345282)
		(width 0.17145)
		(layer "B.Cu")
		(net "SCC_B_TYPE_2")
	)
	(segment
		(start 280.079958 -122.999754)
		(end 280.079958 -123.727464)
		(width 0.17145)
		(layer "B.Cu")
		(net "SCC_B_TYPE_2")
	)
	(segment
		(start 250.958604 -93.8784)
		(end 259.209032 -102.128828)
		(width 0.17145)
		(layer "B.Cu")
		(net "SCC_B_TYPE_2")
	)
	(segment
		(start 247.510554 -93.8784)
		(end 250.958604 -93.8784)
		(width 0.17145)
		(layer "B.Cu")
		(net "SCC_B_TYPE_2")
	)
	(segment
		(start 297.688508 -200.377298)
		(end 297.688508 -222.618808)
		(width 0.14605)
		(layer "In2.Cu")
		(net "SCC_B_TYPE_2")
	)
	(segment
		(start 313.05246 -174.06366)
		(end 313.05246 -191.461136)
		(width 0.14605)
		(layer "In2.Cu")
		(net "SCC_B_TYPE_2")
	)
	(segment
		(start 309.149496 -195.3641)
		(end 302.701706 -195.3641)
		(width 0.14605)
		(layer "In2.Cu")
		(net "SCC_B_TYPE_2")
	)
	(segment
		(start 297.688508 -222.618808)
		(end 300.9265 -225.8568)
		(width 0.14605)
		(layer "In2.Cu")
		(net "SCC_B_TYPE_2")
	)
	(segment
		(start 302.701706 -195.3641)
		(end 297.688508 -200.377298)
		(width 0.14605)
		(layer "In2.Cu")
		(net "SCC_B_TYPE_2")
	)
	(segment
		(start 313.05246 -191.461136)
		(end 309.149496 -195.3641)
		(width 0.14605)
		(layer "In2.Cu")
		(net "SCC_B_TYPE_2")
	)
	(segment
		(start 281.349196 -172.155104)
		(end 281.5971 -172.155104)
		(width 0.14605)
		(layer "In5.Cu")
		(net "SCC_B_TYPE_2")
	)
	(segment
		(start 298.577 -148.16074)
		(end 298.577 -140.848842)
		(width 0.14605)
		(layer "In5.Cu")
		(net "SCC_B_TYPE_2")
	)
	(segment
		(start 283.163264 -125.435106)
		(end 282.066238 -125.435106)
		(width 0.14605)
		(layer "In5.Cu")
		(net "SCC_B_TYPE_2")
	)
	(segment
		(start 280.079958 -123.751848)
		(end 280.079958 -123.727464)
		(width 0.14605)
		(layer "In5.Cu")
		(net "SCC_B_TYPE_2")
	)
	(segment
		(start 282.066238 -125.435106)
		(end 280.38298 -123.751848)
		(width 0.14605)
		(layer "In5.Cu")
		(net "SCC_B_TYPE_2")
	)
	(segment
		(start 280.38298 -123.751848)
		(end 280.079958 -123.751848)
		(width 0.14605)
		(layer "In5.Cu")
		(net "SCC_B_TYPE_2")
	)
	(segment
		(start 293.732204 -160.02)
		(end 293.732204 -153.005536)
		(width 0.14605)
		(layer "In5.Cu")
		(net "SCC_B_TYPE_2")
	)
	(segment
		(start 298.577 -140.848842)
		(end 283.163264 -125.435106)
		(width 0.14605)
		(layer "In5.Cu")
		(net "SCC_B_TYPE_2")
	)
	(segment
		(start 281.5971 -172.155104)
		(end 293.732204 -160.02)
		(width 0.14605)
		(layer "In5.Cu")
		(net "SCC_B_TYPE_2")
	)
	(segment
		(start 293.732204 -153.005536)
		(end 298.577 -148.16074)
		(width 0.14605)
		(layer "In5.Cu")
		(net "SCC_B_TYPE_2")
	)
	(segment
		(start 300.9265 -230.1494)
		(end 300.9265 -230.322628)
		(width 0.17145)
		(layer "F.Cu")
		(net "SCC_B_TYPE_1")
	)
	(segment
		(start 228.000052 -76.399898)
		(end 228.000052 -76.545948)
		(width 0.17145)
		(layer "F.Cu")
		(net "SCC_B_TYPE_1")
	)
	(segment
		(start 267.8176 -113.919)
		(end 264.5664 -110.6678)
		(width 0.17145)
		(layer "F.Cu")
		(net "SCC_B_TYPE_1")
	)
	(segment
		(start 276.352 -113.919)
		(end 267.8176 -113.919)
		(width 0.17145)
		(layer "F.Cu")
		(net "SCC_B_TYPE_1")
	)
	(segment
		(start 227.362258 -77.183742)
		(end 227.362258 -79.30134)
		(width 0.17145)
		(layer "F.Cu")
		(net "SCC_B_TYPE_1")
	)
	(segment
		(start 227.55606 -79.495142)
		(end 227.55606 -80.456024)
		(width 0.17145)
		(layer "F.Cu")
		(net "SCC_B_TYPE_1")
	)
	(segment
		(start 229.567486 -82.46745)
		(end 230.589836 -82.46745)
		(width 0.17145)
		(layer "F.Cu")
		(net "SCC_B_TYPE_1")
	)
	(segment
		(start 257.701542 -109.579156)
		(end 263.477756 -109.579156)
		(width 0.17145)
		(layer "F.Cu")
		(net "SCC_B_TYPE_1")
	)
	(segment
		(start 300.494446 -230.754682)
		(end 292.891718 -230.754682)
		(width 0.17145)
		(layer "F.Cu")
		(net "SCC_B_TYPE_1")
	)
	(segment
		(start 300.9265 -230.322628)
		(end 300.494446 -230.754682)
		(width 0.17145)
		(layer "F.Cu")
		(net "SCC_B_TYPE_1")
	)
	(segment
		(start 263.477756 -109.579156)
		(end 264.5664 -110.6678)
		(width 0.17145)
		(layer "F.Cu")
		(net "SCC_B_TYPE_1")
	)
	(segment
		(start 227.55606 -80.456024)
		(end 229.567486 -82.46745)
		(width 0.17145)
		(layer "F.Cu")
		(net "SCC_B_TYPE_1")
	)
	(segment
		(start 284.000702 -232.658666)
		(end 282.83662 -231.494584)
		(width 0.17145)
		(layer "F.Cu")
		(net "SCC_B_TYPE_1")
	)
	(segment
		(start 292.891718 -230.754682)
		(end 290.987734 -232.658666)
		(width 0.17145)
		(layer "F.Cu")
		(net "SCC_B_TYPE_1")
	)
	(segment
		(start 300.1137 -230.1494)
		(end 300.9265 -230.1494)
		(width 0.17145)
		(layer "F.Cu")
		(net "SCC_B_TYPE_1")
	)
	(segment
		(start 227.362258 -79.30134)
		(end 227.55606 -79.495142)
		(width 0.17145)
		(layer "F.Cu")
		(net "SCC_B_TYPE_1")
	)
	(segment
		(start 230.589836 -82.46745)
		(end 257.701542 -109.579156)
		(width 0.17145)
		(layer "F.Cu")
		(net "SCC_B_TYPE_1")
	)
	(segment
		(start 290.987734 -232.658666)
		(end 284.000702 -232.658666)
		(width 0.17145)
		(layer "F.Cu")
		(net "SCC_B_TYPE_1")
	)
	(segment
		(start 228.000052 -76.545948)
		(end 227.362258 -77.183742)
		(width 0.17145)
		(layer "F.Cu")
		(net "SCC_B_TYPE_1")
	)
	(via
		(at 264.5664 -110.6678)
		(size 0.6604)
		(drill 0.3302)
		(layers "F.Cu" "B.Cu")
		(net "SCC_B_TYPE_1")
	)
	(via
		(at 276.352 -113.919)
		(size 0.5588)
		(drill 0.3048)
		(layers "F.Cu" "B.Cu")
		(net "SCC_B_TYPE_1")
	)
	(via
		(at 300.1137 -230.1494)
		(size 0.5588)
		(drill 0.3048)
		(layers "F.Cu" "B.Cu")
		(net "SCC_B_TYPE_1")
	)
	(segment
		(start 296.374058 -193.871596)
		(end 296.373804 -193.871342)
		(width 0.14605)
		(layer "In2.Cu")
		(net "SCC_B_TYPE_1")
	)
	(segment
		(start 301.27702 -188.605668)
		(end 301.691802 -188.190886)
		(width 0.14605)
		(layer "In2.Cu")
		(net "SCC_B_TYPE_1")
	)
	(segment
		(start 277.491698 -115.058698)
		(end 276.352 -113.919)
		(width 0.14605)
		(layer "In2.Cu")
		(net "SCC_B_TYPE_1")
	)
	(segment
		(start 302.363124 -185.47969)
		(end 302.363124 -122.508264)
		(width 0.14605)
		(layer "In2.Cu")
		(net "SCC_B_TYPE_1")
	)
	(segment
		(start 302.363124 -122.508264)
		(end 294.862504 -115.007644)
		(width 0.14605)
		(layer "In2.Cu")
		(net "SCC_B_TYPE_1")
	)
	(segment
		(start 301.276766 -188.605668)
		(end 301.27702 -188.605668)
		(width 0.14605)
		(layer "In2.Cu")
		(net "SCC_B_TYPE_1")
	)
	(segment
		(start 296.374058 -226.409758)
		(end 296.374058 -193.871596)
		(width 0.14605)
		(layer "In2.Cu")
		(net "SCC_B_TYPE_1")
	)
	(segment
		(start 279.66162 -115.058698)
		(end 277.491698 -115.058698)
		(width 0.14605)
		(layer "In2.Cu")
		(net "SCC_B_TYPE_1")
	)
	(segment
		(start 300.1137 -230.1494)
		(end 296.374058 -226.409758)
		(width 0.14605)
		(layer "In2.Cu")
		(net "SCC_B_TYPE_1")
	)
	(segment
		(start 302.363124 -187.519564)
		(end 302.394112 -187.488576)
		(width 0.14605)
		(layer "In2.Cu")
		(net "SCC_B_TYPE_1")
	)
	(segment
		(start 294.862504 -115.007644)
		(end 279.712674 -115.007644)
		(width 0.14605)
		(layer "In2.Cu")
		(net "SCC_B_TYPE_1")
	)
	(segment
		(start 302.394112 -185.510678)
		(end 302.363124 -185.47969)
		(width 0.14605)
		(layer "In2.Cu")
		(net "SCC_B_TYPE_1")
	)
	(segment
		(start 296.373804 -193.871342)
		(end 296.373804 -193.50863)
		(width 0.14605)
		(layer "In2.Cu")
		(net "SCC_B_TYPE_1")
	)
	(segment
		(start 301.691802 -188.190886)
		(end 301.692056 -188.190886)
		(width 0.14605)
		(layer "In2.Cu")
		(net "SCC_B_TYPE_1")
	)
	(segment
		(start 302.394112 -187.488576)
		(end 302.394112 -185.510678)
		(width 0.14605)
		(layer "In2.Cu")
		(net "SCC_B_TYPE_1")
	)
	(segment
		(start 296.373804 -193.50863)
		(end 301.276766 -188.605668)
		(width 0.14605)
		(layer "In2.Cu")
		(net "SCC_B_TYPE_1")
	)
	(segment
		(start 279.712674 -115.007644)
		(end 279.66162 -115.058698)
		(width 0.14605)
		(layer "In2.Cu")
		(net "SCC_B_TYPE_1")
	)
	(segment
		(start 301.692056 -188.190886)
		(end 302.363124 -187.519818)
		(width 0.14605)
		(layer "In2.Cu")
		(net "SCC_B_TYPE_1")
	)
	(segment
		(start 302.363124 -187.519818)
		(end 302.363124 -187.519564)
		(width 0.14605)
		(layer "In2.Cu")
		(net "SCC_B_TYPE_1")
	)
	(segment
		(start 276.6568 -113.1824)
		(end 269.494 -113.1824)
		(width 0.17145)
		(layer "F.Cu")
		(net "SCC_B_TYPE_0")
	)
	(segment
		(start 228.000052 -75.407012)
		(end 228.636068 -76.043028)
		(width 0.17145)
		(layer "F.Cu")
		(net "SCC_B_TYPE_0")
	)
	(segment
		(start 228.636068 -76.043028)
		(end 228.636068 -80.808576)
		(width 0.17145)
		(layer "F.Cu")
		(net "SCC_B_TYPE_0")
	)
	(segment
		(start 277.368 -113.8936)
		(end 276.6568 -113.1824)
		(width 0.17145)
		(layer "F.Cu")
		(net "SCC_B_TYPE_0")
	)
	(segment
		(start 284.872684 -232.1306)
		(end 284.236668 -231.494584)
		(width 0.17145)
		(layer "F.Cu")
		(net "SCC_B_TYPE_0")
	)
	(segment
		(start 294.13073 -228.473)
		(end 290.47313 -232.1306)
		(width 0.17145)
		(layer "F.Cu")
		(net "SCC_B_TYPE_0")
	)
	(segment
		(start 228.000052 -75.300078)
		(end 228.000052 -75.407012)
		(width 0.17145)
		(layer "F.Cu")
		(net "SCC_B_TYPE_0")
	)
	(segment
		(start 290.47313 -232.1306)
		(end 284.872684 -232.1306)
		(width 0.17145)
		(layer "F.Cu")
		(net "SCC_B_TYPE_0")
	)
	(segment
		(start 229.724458 -81.896966)
		(end 230.746808 -81.896966)
		(width 0.17145)
		(layer "F.Cu")
		(net "SCC_B_TYPE_0")
	)
	(segment
		(start 257.914648 -109.064806)
		(end 265.376406 -109.064806)
		(width 0.17145)
		(layer "F.Cu")
		(net "SCC_B_TYPE_0")
	)
	(segment
		(start 228.636068 -80.808576)
		(end 229.724458 -81.896966)
		(width 0.17145)
		(layer "F.Cu")
		(net "SCC_B_TYPE_0")
	)
	(segment
		(start 269.494 -113.1824)
		(end 266.1666 -109.855)
		(width 0.17145)
		(layer "F.Cu")
		(net "SCC_B_TYPE_0")
	)
	(segment
		(start 300.9265 -228.473)
		(end 294.13073 -228.473)
		(width 0.17145)
		(layer "F.Cu")
		(net "SCC_B_TYPE_0")
	)
	(segment
		(start 265.376406 -109.064806)
		(end 266.1666 -109.855)
		(width 0.17145)
		(layer "F.Cu")
		(net "SCC_B_TYPE_0")
	)
	(segment
		(start 299.74286 -227.717096)
		(end 300.170596 -227.717096)
		(width 0.17145)
		(layer "F.Cu")
		(net "SCC_B_TYPE_0")
	)
	(segment
		(start 230.746808 -81.896966)
		(end 257.914648 -109.064806)
		(width 0.17145)
		(layer "F.Cu")
		(net "SCC_B_TYPE_0")
	)
	(segment
		(start 300.170596 -227.717096)
		(end 300.9265 -228.473)
		(width 0.17145)
		(layer "F.Cu")
		(net "SCC_B_TYPE_0")
	)
	(via
		(at 266.1666 -109.855)
		(size 0.6604)
		(drill 0.3302)
		(layers "F.Cu" "B.Cu")
		(net "SCC_B_TYPE_0")
	)
	(via
		(at 299.74286 -227.717096)
		(size 0.5588)
		(drill 0.3048)
		(layers "F.Cu" "B.Cu")
		(net "SCC_B_TYPE_0")
	)
	(via
		(at 277.368 -113.8936)
		(size 0.5588)
		(drill 0.3048)
		(layers "F.Cu" "B.Cu")
		(net "SCC_B_TYPE_0")
	)
	(segment
		(start 301.873666 -188.629036)
		(end 302.544734 -187.957968)
		(width 0.14605)
		(layer "In2.Cu")
		(net "SCC_B_TYPE_0")
	)
	(segment
		(start 302.544734 -187.957968)
		(end 302.544988 -187.957968)
		(width 0.14605)
		(layer "In2.Cu")
		(net "SCC_B_TYPE_0")
	)
	(segment
		(start 301.45863 -189.043818)
		(end 301.873412 -188.629036)
		(width 0.14605)
		(layer "In2.Cu")
		(net "SCC_B_TYPE_0")
	)
	(segment
		(start 302.801274 -187.701174)
		(end 302.832262 -187.670186)
		(width 0.14605)
		(layer "In2.Cu")
		(net "SCC_B_TYPE_0")
	)
	(segment
		(start 299.379386 -227.353622)
		(end 298.994322 -227.353622)
		(width 0.14605)
		(layer "In2.Cu")
		(net "SCC_B_TYPE_0")
	)
	(segment
		(start 302.801274 -185.297826)
		(end 302.801274 -122.326654)
		(width 0.14605)
		(layer "In2.Cu")
		(net "SCC_B_TYPE_0")
	)
	(segment
		(start 302.801274 -187.701682)
		(end 302.801274 -187.701174)
		(width 0.14605)
		(layer "In2.Cu")
		(net "SCC_B_TYPE_0")
	)
	(segment
		(start 299.74286 -227.717096)
		(end 299.379386 -227.353622)
		(width 0.14605)
		(layer "In2.Cu")
		(net "SCC_B_TYPE_0")
	)
	(segment
		(start 301.458376 -189.043818)
		(end 301.45863 -189.043818)
		(width 0.14605)
		(layer "In2.Cu")
		(net "SCC_B_TYPE_0")
	)
	(segment
		(start 296.812208 -193.689986)
		(end 301.458376 -189.043818)
		(width 0.14605)
		(layer "In2.Cu")
		(net "SCC_B_TYPE_0")
	)
	(segment
		(start 302.832262 -187.670186)
		(end 302.832262 -185.328814)
		(width 0.14605)
		(layer "In2.Cu")
		(net "SCC_B_TYPE_0")
	)
	(segment
		(start 298.994322 -227.353622)
		(end 296.812208 -225.171508)
		(width 0.14605)
		(layer "In2.Cu")
		(net "SCC_B_TYPE_0")
	)
	(segment
		(start 279.53081 -114.569494)
		(end 279.479756 -114.620548)
		(width 0.14605)
		(layer "In2.Cu")
		(net "SCC_B_TYPE_0")
	)
	(segment
		(start 296.812208 -225.171508)
		(end 296.812208 -193.689986)
		(width 0.14605)
		(layer "In2.Cu")
		(net "SCC_B_TYPE_0")
	)
	(segment
		(start 302.832262 -185.328814)
		(end 302.801274 -185.297826)
		(width 0.14605)
		(layer "In2.Cu")
		(net "SCC_B_TYPE_0")
	)
	(segment
		(start 301.873412 -188.629036)
		(end 301.873666 -188.629036)
		(width 0.14605)
		(layer "In2.Cu")
		(net "SCC_B_TYPE_0")
	)
	(segment
		(start 295.044114 -114.569494)
		(end 279.53081 -114.569494)
		(width 0.14605)
		(layer "In2.Cu")
		(net "SCC_B_TYPE_0")
	)
	(segment
		(start 278.094948 -114.620548)
		(end 277.368 -113.8936)
		(width 0.14605)
		(layer "In2.Cu")
		(net "SCC_B_TYPE_0")
	)
	(segment
		(start 279.479756 -114.620548)
		(end 278.094948 -114.620548)
		(width 0.14605)
		(layer "In2.Cu")
		(net "SCC_B_TYPE_0")
	)
	(segment
		(start 302.544988 -187.957968)
		(end 302.801274 -187.701682)
		(width 0.14605)
		(layer "In2.Cu")
		(net "SCC_B_TYPE_0")
	)
	(segment
		(start 302.801274 -122.326654)
		(end 295.044114 -114.569494)
		(width 0.14605)
		(layer "In2.Cu")
		(net "SCC_B_TYPE_0")
	)
	(segment
		(start 301.667418 -233.601768)
		(end 301.881286 -233.3879)
		(width 0.17145)
		(layer "F.Cu")
		(net "SCC_B_SLOT_ID_1")
	)
	(segment
		(start 302.074072 -233.195114)
		(end 301.881286 -233.3879)
		(width 0.17145)
		(layer "F.Cu")
		(net "SCC_B_SLOT_ID_1")
	)
	(segment
		(start 283.000196 -234.458002)
		(end 299.983398 -234.458002)
		(width 0.17145)
		(layer "F.Cu")
		(net "SCC_B_SLOT_ID_1")
	)
	(segment
		(start 299.983398 -234.458002)
		(end 300.839632 -233.601768)
		(width 0.17145)
		(layer "F.Cu")
		(net "SCC_B_SLOT_ID_1")
	)
	(segment
		(start 281.836622 -233.294428)
		(end 283.000196 -234.458002)
		(width 0.17145)
		(layer "F.Cu")
		(net "SCC_B_SLOT_ID_1")
	)
	(segment
		(start 303.160176 -233.195114)
		(end 302.074072 -233.195114)
		(width 0.17145)
		(layer "F.Cu")
		(net "SCC_B_SLOT_ID_1")
	)
	(segment
		(start 300.839632 -233.601768)
		(end 301.667418 -233.601768)
		(width 0.17145)
		(layer "F.Cu")
		(net "SCC_B_SLOT_ID_1")
	)
	(via
		(at 301.881286 -233.3879)
		(size 0.6604)
		(drill 0.3302)
		(layers "F.Cu" "B.Cu")
		(net "SCC_B_SLOT_ID_1")
	)
	(segment
		(start 302.170846 -231.732074)
		(end 302.062896 -231.840024)
		(width 0.17145)
		(layer "F.Cu")
		(net "SCC_B_SLOT_ID_0")
	)
	(segment
		(start 301.051976 -232.850944)
		(end 302.062896 -231.840024)
		(width 0.17145)
		(layer "F.Cu")
		(net "SCC_B_SLOT_ID_0")
	)
	(segment
		(start 283.23667 -233.294428)
		(end 283.873194 -233.930952)
		(width 0.17145)
		(layer "F.Cu")
		(net "SCC_B_SLOT_ID_0")
	)
	(segment
		(start 299.291248 -233.930952)
		(end 300.371256 -232.850944)
		(width 0.17145)
		(layer "F.Cu")
		(net "SCC_B_SLOT_ID_0")
	)
	(segment
		(start 300.371256 -232.850944)
		(end 301.051976 -232.850944)
		(width 0.17145)
		(layer "F.Cu")
		(net "SCC_B_SLOT_ID_0")
	)
	(segment
		(start 283.873194 -233.930952)
		(end 299.291248 -233.930952)
		(width 0.17145)
		(layer "F.Cu")
		(net "SCC_B_SLOT_ID_0")
	)
	(segment
		(start 303.142396 -231.732074)
		(end 302.170846 -231.732074)
		(width 0.17145)
		(layer "F.Cu")
		(net "SCC_B_SLOT_ID_0")
	)
	(via
		(at 302.062896 -231.840024)
		(size 0.6604)
		(drill 0.3302)
		(layers "F.Cu" "B.Cu")
		(net "SCC_B_SLOT_ID_0")
	)
	(segment
		(start 264.033 -224.3455)
		(end 264.033 -223.139)
		(width 0.17145)
		(layer "F.Cu")
		(net "SCC_B_INS_N")
	)
	(segment
		(start 264.033 -223.139)
		(end 264.033 -222.1738)
		(width 0.17145)
		(layer "F.Cu")
		(net "SCC_B_INS_N")
	)
	(via
		(at 264.033 -223.139)
		(size 0.6604)
		(drill 0.3302)
		(layers "F.Cu" "B.Cu")
		(net "SCC_B_INS_N")
	)
	(via
		(at 264.033 -222.1738)
		(size 0.5588)
		(drill 0.3048)
		(layers "F.Cu" "B.Cu")
		(net "SCC_B_INS_N")
	)
	(via
		(at 220.13037 -217.1954)
		(size 0.5588)
		(drill 0.3048)
		(layers "F.Cu" "B.Cu")
		(net "SCC_B_INS_N")
	)
	(segment
		(start 218.595194 -124.793248)
		(end 218.595194 -151.917654)
		(width 0.14605)
		(layer "In2.Cu")
		(net "SCC_B_INS_N")
	)
	(segment
		(start 220.5228 -160.64484)
		(end 220.5228 -169.239946)
		(width 0.14605)
		(layer "In2.Cu")
		(net "SCC_B_INS_N")
	)
	(segment
		(start 218.595194 -151.917654)
		(end 219.677742 -153.000202)
		(width 0.14605)
		(layer "In2.Cu")
		(net "SCC_B_INS_N")
	)
	(segment
		(start 219.264992 -124.12345)
		(end 218.595194 -124.793248)
		(width 0.14605)
		(layer "In2.Cu")
		(net "SCC_B_INS_N")
	)
	(segment
		(start 219.677742 -153.000202)
		(end 219.677742 -155.636722)
		(width 0.14605)
		(layer "In2.Cu")
		(net "SCC_B_INS_N")
	)
	(segment
		(start 227.35286 -105.713784)
		(end 220.246194 -112.82045)
		(width 0.14605)
		(layer "In2.Cu")
		(net "SCC_B_INS_N")
	)
	(segment
		(start 220.5228 -169.239946)
		(end 221.058232 -169.775378)
		(width 0.14605)
		(layer "In2.Cu")
		(net "SCC_B_INS_N")
	)
	(segment
		(start 221.622874 -215.153494)
		(end 220.13037 -216.645998)
		(width 0.14605)
		(layer "In2.Cu")
		(net "SCC_B_INS_N")
	)
	(segment
		(start 227.35286 -74.847196)
		(end 227.35286 -105.713784)
		(width 0.14605)
		(layer "In2.Cu")
		(net "SCC_B_INS_N")
	)
	(segment
		(start 221.622874 -203.566268)
		(end 221.622874 -215.153494)
		(width 0.14605)
		(layer "In2.Cu")
		(net "SCC_B_INS_N")
	)
	(segment
		(start 220.246194 -118.906544)
		(end 219.264992 -119.887746)
		(width 0.14605)
		(layer "In2.Cu")
		(net "SCC_B_INS_N")
	)
	(segment
		(start 219.264992 -119.887746)
		(end 219.264992 -124.12345)
		(width 0.14605)
		(layer "In2.Cu")
		(net "SCC_B_INS_N")
	)
	(segment
		(start 228.000052 -74.200004)
		(end 227.35286 -74.847196)
		(width 0.14605)
		(layer "In2.Cu")
		(net "SCC_B_INS_N")
	)
	(segment
		(start 219.85986 -159.9819)
		(end 220.5228 -160.64484)
		(width 0.14605)
		(layer "In2.Cu")
		(net "SCC_B_INS_N")
	)
	(segment
		(start 220.246194 -112.82045)
		(end 220.246194 -118.906544)
		(width 0.14605)
		(layer "In2.Cu")
		(net "SCC_B_INS_N")
	)
	(segment
		(start 220.13037 -216.645998)
		(end 220.13037 -217.1954)
		(width 0.14605)
		(layer "In2.Cu")
		(net "SCC_B_INS_N")
	)
	(segment
		(start 221.058232 -203.001626)
		(end 221.622874 -203.566268)
		(width 0.14605)
		(layer "In2.Cu")
		(net "SCC_B_INS_N")
	)
	(segment
		(start 219.85986 -155.81884)
		(end 219.85986 -159.9819)
		(width 0.14605)
		(layer "In2.Cu")
		(net "SCC_B_INS_N")
	)
	(segment
		(start 221.058232 -169.775378)
		(end 221.058232 -203.001626)
		(width 0.14605)
		(layer "In2.Cu")
		(net "SCC_B_INS_N")
	)
	(segment
		(start 219.677742 -155.636722)
		(end 219.85986 -155.81884)
		(width 0.14605)
		(layer "In2.Cu")
		(net "SCC_B_INS_N")
	)
	(segment
		(start 271.239996 -221.34195)
		(end 271.45488 -221.127066)
		(width 0.14605)
		(layer "In5.Cu")
		(net "SCC_B_INS_N")
	)
	(segment
		(start 277.172928 -221.127066)
		(end 277.400258 -221.354396)
		(width 0.14605)
		(layer "In5.Cu")
		(net "SCC_B_INS_N")
	)
	(segment
		(start 227.135182 -217.40495)
		(end 220.33992 -217.40495)
		(width 0.14605)
		(layer "In5.Cu")
		(net "SCC_B_INS_N")
	)
	(segment
		(start 264.033 -222.1738)
		(end 262.494268 -222.1738)
		(width 0.14605)
		(layer "In5.Cu")
		(net "SCC_B_INS_N")
	)
	(segment
		(start 264.033 -222.1738)
		(end 264.86485 -221.34195)
		(width 0.14605)
		(layer "In5.Cu")
		(net "SCC_B_INS_N")
	)
	(segment
		(start 227.676964 -217.404696)
		(end 227.135436 -217.404696)
		(width 0.14605)
		(layer "In5.Cu")
		(net "SCC_B_INS_N")
	)
	(segment
		(start 220.33992 -217.40495)
		(end 220.13037 -217.1954)
		(width 0.14605)
		(layer "In5.Cu")
		(net "SCC_B_INS_N")
	)
	(segment
		(start 238.65205 -221.0816)
		(end 231.353868 -221.0816)
		(width 0.14605)
		(layer "In5.Cu")
		(net "SCC_B_INS_N")
	)
	(segment
		(start 239.96777 -222.39732)
		(end 238.65205 -221.0816)
		(width 0.14605)
		(layer "In5.Cu")
		(net "SCC_B_INS_N")
	)
	(segment
		(start 282.176728 -221.354396)
		(end 282.83662 -220.694504)
		(width 0.14605)
		(layer "In5.Cu")
		(net "SCC_B_INS_N")
	)
	(segment
		(start 277.400258 -221.354396)
		(end 282.176728 -221.354396)
		(width 0.14605)
		(layer "In5.Cu")
		(net "SCC_B_INS_N")
	)
	(segment
		(start 244.53088 -222.39732)
		(end 239.96777 -222.39732)
		(width 0.14605)
		(layer "In5.Cu")
		(net "SCC_B_INS_N")
	)
	(segment
		(start 261.662418 -221.34195)
		(end 245.58625 -221.34195)
		(width 0.14605)
		(layer "In5.Cu")
		(net "SCC_B_INS_N")
	)
	(segment
		(start 271.45488 -221.127066)
		(end 277.172928 -221.127066)
		(width 0.14605)
		(layer "In5.Cu")
		(net "SCC_B_INS_N")
	)
	(segment
		(start 245.58625 -221.34195)
		(end 244.53088 -222.39732)
		(width 0.14605)
		(layer "In5.Cu")
		(net "SCC_B_INS_N")
	)
	(segment
		(start 231.353868 -221.0816)
		(end 227.676964 -217.404696)
		(width 0.14605)
		(layer "In5.Cu")
		(net "SCC_B_INS_N")
	)
	(segment
		(start 227.135436 -217.404696)
		(end 227.135182 -217.40495)
		(width 0.14605)
		(layer "In5.Cu")
		(net "SCC_B_INS_N")
	)
	(segment
		(start 264.86485 -221.34195)
		(end 271.239996 -221.34195)
		(width 0.14605)
		(layer "In5.Cu")
		(net "SCC_B_INS_N")
	)
	(segment
		(start 262.494268 -222.1738)
		(end 261.662418 -221.34195)
		(width 0.14605)
		(layer "In5.Cu")
		(net "SCC_B_INS_N")
	)
	(segment
		(start 307.997098 -189.25413)
		(end 306.561998 -190.68923)
		(width 0.17145)
		(layer "F.Cu")
		(net "SCC_B_HEARTBEAT")
	)
	(segment
		(start 304.636678 -235.094526)
		(end 305.650138 -234.081066)
		(width 0.17145)
		(layer "F.Cu")
		(net "SCC_B_HEARTBEAT")
	)
	(segment
		(start 305.650138 -221.291404)
		(end 301.794164 -217.43543)
		(width 0.17145)
		(layer "F.Cu")
		(net "SCC_B_HEARTBEAT")
	)
	(segment
		(start 284.872684 -235.730542)
		(end 289.161474 -235.730542)
		(width 0.17145)
		(layer "F.Cu")
		(net "SCC_B_HEARTBEAT")
	)
	(segment
		(start 301.794164 -217.43543)
		(end 301.794164 -208.454244)
		(width 0.17145)
		(layer "F.Cu")
		(net "SCC_B_HEARTBEAT")
	)
	(segment
		(start 305.650138 -234.081066)
		(end 305.650138 -221.291404)
		(width 0.17145)
		(layer "F.Cu")
		(net "SCC_B_HEARTBEAT")
	)
	(segment
		(start 301.794164 -208.454244)
		(end 306.561998 -203.68641)
		(width 0.17145)
		(layer "F.Cu")
		(net "SCC_B_HEARTBEAT")
	)
	(segment
		(start 306.561998 -203.68641)
		(end 306.561998 -191.770508)
		(width 0.17145)
		(layer "F.Cu")
		(net "SCC_B_HEARTBEAT")
	)
	(segment
		(start 284.236668 -235.094526)
		(end 284.872684 -235.730542)
		(width 0.17145)
		(layer "F.Cu")
		(net "SCC_B_HEARTBEAT")
	)
	(segment
		(start 289.161474 -235.730542)
		(end 289.79749 -235.094526)
		(width 0.17145)
		(layer "F.Cu")
		(net "SCC_B_HEARTBEAT")
	)
	(segment
		(start 306.561998 -190.68923)
		(end 306.561998 -191.770508)
		(width 0.17145)
		(layer "F.Cu")
		(net "SCC_B_HEARTBEAT")
	)
	(segment
		(start 289.79749 -235.094526)
		(end 304.636678 -235.094526)
		(width 0.17145)
		(layer "F.Cu")
		(net "SCC_B_HEARTBEAT")
	)
	(via
		(at 307.997098 -189.25413)
		(size 0.5588)
		(drill 0.3048)
		(layers "F.Cu" "B.Cu")
		(net "SCC_B_HEARTBEAT")
	)
	(via
		(at 288.544 -113.499646)
		(size 0.5588)
		(drill 0.3048)
		(layers "F.Cu" "B.Cu")
		(net "SCC_B_HEARTBEAT")
	)
	(via
		(at 306.561998 -191.770508)
		(size 0.6604)
		(drill 0.3302)
		(layers "F.Cu" "B.Cu")
		(net "SCC_B_HEARTBEAT")
	)
	(segment
		(start 307.997098 -189.25413)
		(end 303.677574 -184.934606)
		(width 0.14605)
		(layer "In2.Cu")
		(net "SCC_B_HEARTBEAT")
	)
	(segment
		(start 303.677574 -184.934606)
		(end 303.677574 -121.963434)
		(width 0.14605)
		(layer "In2.Cu")
		(net "SCC_B_HEARTBEAT")
	)
	(segment
		(start 288.737548 -113.693194)
		(end 288.544 -113.499646)
		(width 0.14605)
		(layer "In2.Cu")
		(net "SCC_B_HEARTBEAT")
	)
	(segment
		(start 303.677574 -121.963434)
		(end 295.407334 -113.693194)
		(width 0.14605)
		(layer "In2.Cu")
		(net "SCC_B_HEARTBEAT")
	)
	(segment
		(start 295.407334 -113.693194)
		(end 288.737548 -113.693194)
		(width 0.14605)
		(layer "In2.Cu")
		(net "SCC_B_HEARTBEAT")
	)
	(segment
		(start 231.599994 -70.600062)
		(end 232.7402 -71.740268)
		(width 0.14605)
		(layer "In5.Cu")
		(net "SCC_B_HEARTBEAT")
	)
	(segment
		(start 275.97735 -115.044474)
		(end 286.999172 -115.044474)
		(width 0.14605)
		(layer "In5.Cu")
		(net "SCC_B_HEARTBEAT")
	)
	(segment
		(start 232.7402 -81.905602)
		(end 252.38075 -101.546152)
		(width 0.14605)
		(layer "In5.Cu")
		(net "SCC_B_HEARTBEAT")
	)
	(segment
		(start 275.977096 -115.04422)
		(end 275.97735 -115.044474)
		(width 0.14605)
		(layer "In5.Cu")
		(net "SCC_B_HEARTBEAT")
	)
	(segment
		(start 286.999172 -115.044474)
		(end 288.544 -113.499646)
		(width 0.14605)
		(layer "In5.Cu")
		(net "SCC_B_HEARTBEAT")
	)
	(segment
		(start 275.88718 -115.04422)
		(end 275.977096 -115.04422)
		(width 0.14605)
		(layer "In5.Cu")
		(net "SCC_B_HEARTBEAT")
	)
	(segment
		(start 232.7402 -71.740268)
		(end 232.7402 -81.905602)
		(width 0.14605)
		(layer "In5.Cu")
		(net "SCC_B_HEARTBEAT")
	)
	(segment
		(start 252.38075 -101.546152)
		(end 262.389112 -101.546152)
		(width 0.14605)
		(layer "In5.Cu")
		(net "SCC_B_HEARTBEAT")
	)
	(segment
		(start 262.389112 -101.546152)
		(end 275.88718 -115.04422)
		(width 0.14605)
		(layer "In5.Cu")
		(net "SCC_B_HEARTBEAT")
	)
	(segment
		(start 230.280464 -89.565988)
		(end 229.257606 -90.588846)
		(width 0.17145)
		(layer "F.Cu")
		(net "SCC_A_INS_N")
	)
	(segment
		(start 229.257606 -90.588846)
		(end 229.257606 -139.982194)
		(width 0.17145)
		(layer "F.Cu")
		(net "SCC_A_INS_N")
	)
	(segment
		(start 204.502512 -166.941754)
		(end 204.502512 -164.20465)
		(width 0.17145)
		(layer "F.Cu")
		(net "SCC_A_INS_N")
	)
	(segment
		(start 230.280464 -89.302844)
		(end 230.280464 -89.565988)
		(width 0.17145)
		(layer "F.Cu")
		(net "SCC_A_INS_N")
	)
	(segment
		(start 206.478378 -162.761422)
		(end 205.94574 -162.761422)
		(width 0.17145)
		(layer "F.Cu")
		(net "SCC_A_INS_N")
	)
	(segment
		(start 210.936332 -167.7289)
		(end 209.679032 -168.9862)
		(width 0.17145)
		(layer "F.Cu")
		(net "SCC_A_INS_N")
	)
	(segment
		(start 209.679032 -168.9862)
		(end 206.546958 -168.9862)
		(width 0.17145)
		(layer "F.Cu")
		(net "SCC_A_INS_N")
	)
	(segment
		(start 229.257606 -139.982194)
		(end 206.478378 -162.761422)
		(width 0.17145)
		(layer "F.Cu")
		(net "SCC_A_INS_N")
	)
	(segment
		(start 206.546958 -168.9862)
		(end 204.502512 -166.941754)
		(width 0.17145)
		(layer "F.Cu")
		(net "SCC_A_INS_N")
	)
	(segment
		(start 205.94574 -162.761422)
		(end 204.502512 -164.20465)
		(width 0.17145)
		(layer "F.Cu")
		(net "SCC_A_INS_N")
	)
	(segment
		(start 212.69706 -167.7289)
		(end 210.936332 -167.7289)
		(width 0.17145)
		(layer "F.Cu")
		(net "SCC_A_INS_N")
	)
	(via
		(at 230.280464 -89.302844)
		(size 0.5588)
		(drill 0.3048)
		(layers "F.Cu" "B.Cu")
		(net "SCC_A_INS_N")
	)
	(via
		(at 204.502512 -164.20465)
		(size 0.6604)
		(drill 0.3302)
		(layers "F.Cu" "B.Cu")
		(net "SCC_A_INS_N")
	)
	(segment
		(start 228.365558 -79.833724)
		(end 228.365558 -81.446878)
		(width 0.14605)
		(layer "In5.Cu")
		(net "SCC_A_INS_N")
	)
	(segment
		(start 230.304848 -85.917024)
		(end 230.304848 -89.27846)
		(width 0.14605)
		(layer "In5.Cu")
		(net "SCC_A_INS_N")
	)
	(segment
		(start 228.91623 -84.528406)
		(end 230.304848 -85.917024)
		(width 0.14605)
		(layer "In5.Cu")
		(net "SCC_A_INS_N")
	)
	(segment
		(start 228.365558 -81.446878)
		(end 228.91623 -81.99755)
		(width 0.14605)
		(layer "In5.Cu")
		(net "SCC_A_INS_N")
	)
	(segment
		(start 228.91623 -81.99755)
		(end 228.91623 -84.528406)
		(width 0.14605)
		(layer "In5.Cu")
		(net "SCC_A_INS_N")
	)
	(segment
		(start 230.304848 -89.27846)
		(end 230.280464 -89.302844)
		(width 0.14605)
		(layer "In5.Cu")
		(net "SCC_A_INS_N")
	)
	(segment
		(start 228.653086 -79.546196)
		(end 228.365558 -79.833724)
		(width 0.14605)
		(layer "In5.Cu")
		(net "SCC_A_INS_N")
	)
	(segment
		(start 228.000052 -72.799956)
		(end 228.653086 -73.45299)
		(width 0.14605)
		(layer "In5.Cu")
		(net "SCC_A_INS_N")
	)
	(segment
		(start 228.653086 -73.45299)
		(end 228.653086 -79.546196)
		(width 0.14605)
		(layer "In5.Cu")
		(net "SCC_A_INS_N")
	)
	(segment
		(start 302.308514 -208.66735)
		(end 308.026562 -202.949302)
		(width 0.17145)
		(layer "F.Cu")
		(net "SCC_A_HEARTBEAT")
	)
	(segment
		(start 308.026562 -190.350394)
		(end 308.026562 -192.64249)
		(width 0.17145)
		(layer "F.Cu")
		(net "SCC_A_HEARTBEAT")
	)
	(segment
		(start 289.5981 -236.257592)
		(end 289.976306 -235.879386)
		(width 0.17145)
		(layer "F.Cu")
		(net "SCC_A_HEARTBEAT")
	)
	(segment
		(start 306.164488 -221.078298)
		(end 302.308514 -217.222324)
		(width 0.17145)
		(layer "F.Cu")
		(net "SCC_A_HEARTBEAT")
	)
	(segment
		(start 308.026562 -202.949302)
		(end 308.026562 -192.64249)
		(width 0.17145)
		(layer "F.Cu")
		(net "SCC_A_HEARTBEAT")
	)
	(segment
		(start 289.976306 -235.879386)
		(end 304.579274 -235.879386)
		(width 0.17145)
		(layer "F.Cu")
		(net "SCC_A_HEARTBEAT")
	)
	(segment
		(start 283.999686 -236.257592)
		(end 289.5981 -236.257592)
		(width 0.17145)
		(layer "F.Cu")
		(net "SCC_A_HEARTBEAT")
	)
	(segment
		(start 302.308514 -217.222324)
		(end 302.308514 -208.66735)
		(width 0.17145)
		(layer "F.Cu")
		(net "SCC_A_HEARTBEAT")
	)
	(segment
		(start 307.997098 -190.32093)
		(end 308.026562 -190.350394)
		(width 0.17145)
		(layer "F.Cu")
		(net "SCC_A_HEARTBEAT")
	)
	(segment
		(start 304.579274 -235.879386)
		(end 306.164488 -234.294172)
		(width 0.17145)
		(layer "F.Cu")
		(net "SCC_A_HEARTBEAT")
	)
	(segment
		(start 282.83662 -235.094526)
		(end 283.999686 -236.257592)
		(width 0.17145)
		(layer "F.Cu")
		(net "SCC_A_HEARTBEAT")
	)
	(segment
		(start 306.164488 -234.294172)
		(end 306.164488 -221.078298)
		(width 0.17145)
		(layer "F.Cu")
		(net "SCC_A_HEARTBEAT")
	)
	(via
		(at 308.026562 -192.64249)
		(size 0.6604)
		(drill 0.3302)
		(layers "F.Cu" "B.Cu")
		(net "SCC_A_HEARTBEAT")
	)
	(via
		(at 307.997098 -190.32093)
		(size 0.5588)
		(drill 0.3048)
		(layers "F.Cu" "B.Cu")
		(net "SCC_A_HEARTBEAT")
	)
	(via
		(at 287.4772 -113.4872)
		(size 0.5588)
		(drill 0.3048)
		(layers "F.Cu" "B.Cu")
		(net "SCC_A_HEARTBEAT")
	)
	(segment
		(start 303.239424 -122.145044)
		(end 303.239424 -185.116216)
		(width 0.14605)
		(layer "In2.Cu")
		(net "SCC_A_HEARTBEAT")
	)
	(segment
		(start 288.121344 -114.131344)
		(end 295.225724 -114.131344)
		(width 0.14605)
		(layer "In2.Cu")
		(net "SCC_A_HEARTBEAT")
	)
	(segment
		(start 295.225724 -114.131344)
		(end 303.239424 -122.145044)
		(width 0.14605)
		(layer "In2.Cu")
		(net "SCC_A_HEARTBEAT")
	)
	(segment
		(start 303.313846 -185.190638)
		(end 303.313846 -185.637678)
		(width 0.14605)
		(layer "In2.Cu")
		(net "SCC_A_HEARTBEAT")
	)
	(segment
		(start 287.4772 -113.4872)
		(end 288.121344 -114.131344)
		(width 0.14605)
		(layer "In2.Cu")
		(net "SCC_A_HEARTBEAT")
	)
	(segment
		(start 303.239424 -185.116216)
		(end 303.313846 -185.190638)
		(width 0.14605)
		(layer "In2.Cu")
		(net "SCC_A_HEARTBEAT")
	)
	(segment
		(start 303.313846 -185.637678)
		(end 307.997098 -190.32093)
		(width 0.14605)
		(layer "In2.Cu")
		(net "SCC_A_HEARTBEAT")
	)
	(segment
		(start 233.5784 -71.17842)
		(end 233.5784 -82.10931)
		(width 0.14605)
		(layer "In5.Cu")
		(net "SCC_A_HEARTBEAT")
	)
	(segment
		(start 233.5784 -82.10931)
		(end 252.577092 -101.108002)
		(width 0.14605)
		(layer "In5.Cu")
		(net "SCC_A_HEARTBEAT")
	)
	(segment
		(start 231.599994 -69.200014)
		(end 233.5784 -71.17842)
		(width 0.14605)
		(layer "In5.Cu")
		(net "SCC_A_HEARTBEAT")
	)
	(segment
		(start 276.15896 -114.606324)
		(end 286.358076 -114.606324)
		(width 0.14605)
		(layer "In5.Cu")
		(net "SCC_A_HEARTBEAT")
	)
	(segment
		(start 252.577092 -101.108002)
		(end 262.660638 -101.108002)
		(width 0.14605)
		(layer "In5.Cu")
		(net "SCC_A_HEARTBEAT")
	)
	(segment
		(start 262.660638 -101.108002)
		(end 276.15896 -114.606324)
		(width 0.14605)
		(layer "In5.Cu")
		(net "SCC_A_HEARTBEAT")
	)
	(segment
		(start 286.358076 -114.606324)
		(end 287.4772 -113.4872)
		(width 0.14605)
		(layer "In5.Cu")
		(net "SCC_A_HEARTBEAT")
	)
	(segment
		(start 274.0279 -328.28484)
		(end 274.0279 -327.1266)
		(width 0.254)
		(layer "F.Cu")
		(net "PWM_OUT_FAN0")
	)
	(segment
		(start 274.35683 -328.61377)
		(end 274.0279 -328.28484)
		(width 0.254)
		(layer "F.Cu")
		(net "PWM_OUT_FAN0")
	)
	(segment
		(start 275.859748 -328.82332)
		(end 277.8506 -328.82332)
		(width 0.254)
		(layer "F.Cu")
		(net "PWM_OUT_FAN0")
	)
	(segment
		(start 275.859748 -328.82332)
		(end 275.650198 -328.61377)
		(width 0.254)
		(layer "F.Cu")
		(net "PWM_OUT_FAN0")
	)
	(segment
		(start 34.981896 -374.1166)
		(end 34.956496 -374.0912)
		(width 0.254)
		(layer "F.Cu")
		(net "PWM_OUT_FAN0")
	)
	(segment
		(start 275.650198 -328.61377)
		(end 274.35683 -328.61377)
		(width 0.254)
		(layer "F.Cu")
		(net "PWM_OUT_FAN0")
	)
	(segment
		(start 34.956496 -374.0912)
		(end 34.956496 -373.126)
		(width 0.254)
		(layer "F.Cu")
		(net "PWM_OUT_FAN0")
	)
	(via
		(at 275.859748 -328.82332)
		(size 0.6604)
		(drill 0.3302)
		(layers "F.Cu" "B.Cu")
		(net "PWM_OUT_FAN0")
	)
	(via
		(at 34.956496 -373.126)
		(size 0.5588)
		(drill 0.3048)
		(layers "F.Cu" "B.Cu")
		(net "PWM_OUT_FAN0")
	)
	(via
		(at 274.0279 -327.1266)
		(size 0.5588)
		(drill 0.3048)
		(layers "F.Cu" "B.Cu")
		(net "PWM_OUT_FAN0")
	)
	(segment
		(start 188.28893 -325.27113)
		(end 181.102 -318.0842)
		(width 0.254)
		(layer "In5.Cu")
		(net "PWM_OUT_FAN0")
	)
	(segment
		(start 32.505396 -362.640372)
		(end 32.505396 -371.514878)
		(width 0.254)
		(layer "In5.Cu")
		(net "PWM_OUT_FAN0")
	)
	(segment
		(start 267.479018 -325.27113)
		(end 188.28893 -325.27113)
		(width 0.254)
		(layer "In5.Cu")
		(net "PWM_OUT_FAN0")
	)
	(segment
		(start 47.3202 -318.0842)
		(end 35.756596 -329.647804)
		(width 0.254)
		(layer "In5.Cu")
		(net "PWM_OUT_FAN0")
	)
	(segment
		(start 35.756596 -329.647804)
		(end 35.756596 -359.389172)
		(width 0.254)
		(layer "In5.Cu")
		(net "PWM_OUT_FAN0")
	)
	(segment
		(start 271.635728 -329.42784)
		(end 267.479018 -325.27113)
		(width 0.254)
		(layer "In5.Cu")
		(net "PWM_OUT_FAN0")
	)
	(segment
		(start 181.102 -318.0842)
		(end 47.3202 -318.0842)
		(width 0.254)
		(layer "In5.Cu")
		(net "PWM_OUT_FAN0")
	)
	(segment
		(start 35.756596 -359.389172)
		(end 32.505396 -362.640372)
		(width 0.254)
		(layer "In5.Cu")
		(net "PWM_OUT_FAN0")
	)
	(segment
		(start 34.116518 -373.126)
		(end 34.956496 -373.126)
		(width 0.254)
		(layer "In5.Cu")
		(net "PWM_OUT_FAN0")
	)
	(segment
		(start 32.505396 -371.514878)
		(end 34.116518 -373.126)
		(width 0.254)
		(layer "In5.Cu")
		(net "PWM_OUT_FAN0")
	)
	(segment
		(start 272.791936 -329.42784)
		(end 271.635728 -329.42784)
		(width 0.254)
		(layer "In5.Cu")
		(net "PWM_OUT_FAN0")
	)
	(segment
		(start 274.0279 -328.191876)
		(end 272.791936 -329.42784)
		(width 0.254)
		(layer "In5.Cu")
		(net "PWM_OUT_FAN0")
	)
	(segment
		(start 274.0279 -327.1266)
		(end 274.0279 -328.191876)
		(width 0.254)
		(layer "In5.Cu")
		(net "PWM_OUT_FAN0")
	)
	(segment
		(start 416.005264 -244.660674)
		(end 415.620454 -244.660674)
		(width 0.127)
		(layer "F.Cu")
		(net "PHY_SCC_B_TO_DRV_B_9_DP")
	)
	(segment
		(start 415.620454 -244.660674)
		(end 415.410904 -244.870224)
		(width 0.127)
		(layer "F.Cu")
		(net "PHY_SCC_B_TO_DRV_B_9_DP")
	)
	(segment
		(start 415.410904 -244.870224)
		(end 414.208976 -244.870224)
		(width 0.127)
		(layer "F.Cu")
		(net "PHY_SCC_B_TO_DRV_B_9_DP")
	)
	(segment
		(start 414.042352 -244.7036)
		(end 414.042352 -244.444774)
		(width 0.127)
		(layer "F.Cu")
		(net "PHY_SCC_B_TO_DRV_B_9_DP")
	)
	(arc
		(start 414.208976 -244.870224)
		(mid 414.091155 -244.821421)
		(end 414.042352 -244.7036)
		(width 0.127)
		(layer "F.Cu")
		(net "PHY_SCC_B_TO_DRV_B_9_DP")
	)
	(segment
		(start 408.091386 -243.24437)
		(end 408.191716 -243.435124)
		(width 0.127)
		(layer "B.Cu")
		(net "PHY_SCC_B_TO_DRV_B_9_DP")
	)
	(segment
		(start 410.128466 -243.878608)
		(end 410.228796 -244.069362)
		(width 0.127)
		(layer "B.Cu")
		(net "PHY_SCC_B_TO_DRV_B_9_DP")
	)
	(segment
		(start 414.042352 -244.735096)
		(end 414.042352 -244.444774)
		(width 0.127)
		(layer "B.Cu")
		(net "PHY_SCC_B_TO_DRV_B_9_DP")
	)
	(segment
		(start 279.636728 -222.494348)
		(end 279.244806 -222.494348)
		(width 0.127)
		(layer "B.Cu")
		(net "PHY_SCC_B_TO_DRV_B_9_DP")
	)
	(segment
		(start 407.536904 -243.231162)
		(end 407.727658 -243.131086)
		(width 0.127)
		(layer "B.Cu")
		(net "PHY_SCC_B_TO_DRV_B_9_DP")
	)
	(segment
		(start 409.573984 -243.8654)
		(end 409.764738 -243.765324)
		(width 0.127)
		(layer "B.Cu")
		(net "PHY_SCC_B_TO_DRV_B_9_DP")
	)
	(segment
		(start 412.801054 -244.870224)
		(end 413.907224 -244.870224)
		(width 0.127)
		(layer "B.Cu")
		(net "PHY_SCC_B_TO_DRV_B_9_DP")
	)
	(segment
		(start 410.228796 -244.069362)
		(end 412.801054 -244.870224)
		(width 0.127)
		(layer "B.Cu")
		(net "PHY_SCC_B_TO_DRV_B_9_DP")
	)
	(segment
		(start 408.746198 -243.448078)
		(end 409.109926 -243.561362)
		(width 0.127)
		(layer "B.Cu")
		(net "PHY_SCC_B_TO_DRV_B_9_DP")
	)
	(segment
		(start 409.210256 -243.752116)
		(end 409.573984 -243.8654)
		(width 0.127)
		(layer "B.Cu")
		(net "PHY_SCC_B_TO_DRV_B_9_DP")
	)
	(segment
		(start 337.051904 -228.990144)
		(end 387.70687 -237.057946)
		(width 0.127)
		(layer "B.Cu")
		(net "PHY_SCC_B_TO_DRV_B_9_DP")
	)
	(segment
		(start 279.357328 -223.235774)
		(end 291.358828 -223.235774)
		(width 0.127)
		(layer "B.Cu")
		(net "PHY_SCC_B_TO_DRV_B_9_DP")
	)
	(segment
		(start 409.109926 -243.561362)
		(end 409.210256 -243.752116)
		(width 0.127)
		(layer "B.Cu")
		(net "PHY_SCC_B_TO_DRV_B_9_DP")
	)
	(segment
		(start 291.358828 -223.235774)
		(end 337.051904 -228.990144)
		(width 0.127)
		(layer "B.Cu")
		(net "PHY_SCC_B_TO_DRV_B_9_DP")
	)
	(segment
		(start 409.764738 -243.765324)
		(end 410.128466 -243.878608)
		(width 0.127)
		(layer "B.Cu")
		(net "PHY_SCC_B_TO_DRV_B_9_DP")
	)
	(segment
		(start 279.082754 -222.6564)
		(end 279.082754 -222.9612)
		(width 0.127)
		(layer "B.Cu")
		(net "PHY_SCC_B_TO_DRV_B_9_DP")
	)
	(segment
		(start 387.70687 -237.057946)
		(end 407.536904 -243.231162)
		(width 0.127)
		(layer "B.Cu")
		(net "PHY_SCC_B_TO_DRV_B_9_DP")
	)
	(segment
		(start 407.727658 -243.131086)
		(end 408.091386 -243.24437)
		(width 0.127)
		(layer "B.Cu")
		(net "PHY_SCC_B_TO_DRV_B_9_DP")
	)
	(segment
		(start 408.555444 -243.548408)
		(end 408.746198 -243.448078)
		(width 0.127)
		(layer "B.Cu")
		(net "PHY_SCC_B_TO_DRV_B_9_DP")
	)
	(segment
		(start 408.191716 -243.435124)
		(end 408.555444 -243.548408)
		(width 0.127)
		(layer "B.Cu")
		(net "PHY_SCC_B_TO_DRV_B_9_DP")
	)
	(arc
		(start 279.082754 -222.9612)
		(mid 279.163175 -223.155353)
		(end 279.357328 -223.235774)
		(width 0.127)
		(layer "B.Cu")
		(net "PHY_SCC_B_TO_DRV_B_9_DP")
	)
	(arc
		(start 413.907224 -244.870224)
		(mid 414.002774 -244.830646)
		(end 414.042352 -244.735096)
		(width 0.127)
		(layer "B.Cu")
		(net "PHY_SCC_B_TO_DRV_B_9_DP")
	)
	(arc
		(start 279.244806 -222.494348)
		(mid 279.130218 -222.541812)
		(end 279.082754 -222.6564)
		(width 0.127)
		(layer "B.Cu")
		(net "PHY_SCC_B_TO_DRV_B_9_DP")
	)
	(segment
		(start 415.579052 -245.162324)
		(end 414.208976 -245.162324)
		(width 0.127)
		(layer "F.Cu")
		(net "PHY_SCC_B_TO_DRV_B_9_DN")
	)
	(segment
		(start 416.005264 -245.219474)
		(end 415.636202 -245.219474)
		(width 0.127)
		(layer "F.Cu")
		(net "PHY_SCC_B_TO_DRV_B_9_DN")
	)
	(segment
		(start 414.042352 -245.328948)
		(end 414.042352 -245.587774)
		(width 0.127)
		(layer "F.Cu")
		(net "PHY_SCC_B_TO_DRV_B_9_DN")
	)
	(segment
		(start 415.636202 -245.219474)
		(end 415.579052 -245.162324)
		(width 0.127)
		(layer "F.Cu")
		(net "PHY_SCC_B_TO_DRV_B_9_DN")
	)
	(arc
		(start 414.208976 -245.162324)
		(mid 414.091155 -245.211127)
		(end 414.042352 -245.328948)
		(width 0.127)
		(layer "F.Cu")
		(net "PHY_SCC_B_TO_DRV_B_9_DN")
	)
	(segment
		(start 278.23668 -222.494348)
		(end 278.628602 -222.494348)
		(width 0.127)
		(layer "B.Cu")
		(net "PHY_SCC_B_TO_DRV_B_9_DN")
	)
	(segment
		(start 337.010756 -229.27945)
		(end 362.325158 -233.311192)
		(width 0.127)
		(layer "B.Cu")
		(net "PHY_SCC_B_TO_DRV_B_9_DN")
	)
	(segment
		(start 278.790654 -222.6564)
		(end 278.790654 -222.9612)
		(width 0.127)
		(layer "B.Cu")
		(net "PHY_SCC_B_TO_DRV_B_9_DN")
	)
	(segment
		(start 279.357328 -223.527874)
		(end 291.340286 -223.527874)
		(width 0.127)
		(layer "B.Cu")
		(net "PHY_SCC_B_TO_DRV_B_9_DN")
	)
	(segment
		(start 372.969536 -235.006642)
		(end 387.640068 -237.343188)
		(width 0.127)
		(layer "B.Cu")
		(net "PHY_SCC_B_TO_DRV_B_9_DN")
	)
	(segment
		(start 291.340286 -223.527874)
		(end 337.010756 -229.27945)
		(width 0.127)
		(layer "B.Cu")
		(net "PHY_SCC_B_TO_DRV_B_9_DN")
	)
	(segment
		(start 412.756604 -245.162324)
		(end 413.907224 -245.162324)
		(width 0.127)
		(layer "B.Cu")
		(net "PHY_SCC_B_TO_DRV_B_9_DN")
	)
	(segment
		(start 387.640068 -237.343188)
		(end 412.756604 -245.162324)
		(width 0.127)
		(layer "B.Cu")
		(net "PHY_SCC_B_TO_DRV_B_9_DN")
	)
	(segment
		(start 414.042352 -245.297452)
		(end 414.042352 -245.587774)
		(width 0.127)
		(layer "B.Cu")
		(net "PHY_SCC_B_TO_DRV_B_9_DN")
	)
	(segment
		(start 362.325158 -233.311192)
		(end 372.969536 -235.006642)
		(width 0.127)
		(layer "B.Cu")
		(net "PHY_SCC_B_TO_DRV_B_9_DN")
	)
	(arc
		(start 278.628602 -222.494348)
		(mid 278.74319 -222.541812)
		(end 278.790654 -222.6564)
		(width 0.127)
		(layer "B.Cu")
		(net "PHY_SCC_B_TO_DRV_B_9_DN")
	)
	(arc
		(start 413.907224 -245.162324)
		(mid 414.002774 -245.201902)
		(end 414.042352 -245.297452)
		(width 0.127)
		(layer "B.Cu")
		(net "PHY_SCC_B_TO_DRV_B_9_DN")
	)
	(arc
		(start 278.790654 -222.9612)
		(mid 278.956629 -223.361899)
		(end 279.357328 -223.527874)
		(width 0.127)
		(layer "B.Cu")
		(net "PHY_SCC_B_TO_DRV_B_9_DN")
	)
	(segment
		(start 384.056636 -244.727984)
		(end 382.6891 -244.727984)
		(width 0.127)
		(layer "F.Cu")
		(net "PHY_SCC_B_TO_DRV_B_8_DP")
	)
	(segment
		(start 384.123946 -244.660674)
		(end 384.056636 -244.727984)
		(width 0.127)
		(layer "F.Cu")
		(net "PHY_SCC_B_TO_DRV_B_8_DP")
	)
	(segment
		(start 382.49225 -244.531134)
		(end 382.49225 -244.302534)
		(width 0.127)
		(layer "F.Cu")
		(net "PHY_SCC_B_TO_DRV_B_8_DP")
	)
	(segment
		(start 384.455162 -244.660674)
		(end 384.123946 -244.660674)
		(width 0.127)
		(layer "F.Cu")
		(net "PHY_SCC_B_TO_DRV_B_8_DP")
	)
	(arc
		(start 382.6891 -244.727984)
		(mid 382.549906 -244.670328)
		(end 382.49225 -244.531134)
		(width 0.127)
		(layer "F.Cu")
		(net "PHY_SCC_B_TO_DRV_B_8_DP")
	)
	(segment
		(start 363.67593 -239.621568)
		(end 363.86516 -239.51819)
		(width 0.127)
		(layer "B.Cu")
		(net "PHY_SCC_B_TO_DRV_B_8_DP")
	)
	(segment
		(start 362.841794 -239.2172)
		(end 363.2073 -239.324642)
		(width 0.127)
		(layer "B.Cu")
		(net "PHY_SCC_B_TO_DRV_B_8_DP")
	)
	(segment
		(start 360.795062 -238.614458)
		(end 361.160568 -238.722154)
		(width 0.127)
		(layer "B.Cu")
		(net "PHY_SCC_B_TO_DRV_B_8_DP")
	)
	(segment
		(start 363.2073 -239.324642)
		(end 363.310424 -239.513872)
		(width 0.127)
		(layer "B.Cu")
		(net "PHY_SCC_B_TO_DRV_B_8_DP")
	)
	(segment
		(start 364.33379 -239.815116)
		(end 381.022606 -244.727984)
		(width 0.127)
		(layer "B.Cu")
		(net "PHY_SCC_B_TO_DRV_B_8_DP")
	)
	(segment
		(start 361.263692 -238.911384)
		(end 361.629198 -239.01908)
		(width 0.127)
		(layer "B.Cu")
		(net "PHY_SCC_B_TO_DRV_B_8_DP")
	)
	(segment
		(start 381.022606 -244.727984)
		(end 382.284224 -244.727984)
		(width 0.127)
		(layer "B.Cu")
		(net "PHY_SCC_B_TO_DRV_B_8_DP")
	)
	(segment
		(start 363.86516 -239.51819)
		(end 364.230666 -239.625886)
		(width 0.127)
		(layer "B.Cu")
		(net "PHY_SCC_B_TO_DRV_B_8_DP")
	)
	(segment
		(start 362.287058 -239.212628)
		(end 362.652564 -239.320324)
		(width 0.127)
		(layer "B.Cu")
		(net "PHY_SCC_B_TO_DRV_B_8_DP")
	)
	(segment
		(start 290.898834 -225.035872)
		(end 330.906882 -231.62006)
		(width 0.127)
		(layer "B.Cu")
		(net "PHY_SCC_B_TO_DRV_B_8_DP")
	)
	(segment
		(start 330.906882 -231.62006)
		(end 356.006654 -237.363762)
		(width 0.127)
		(layer "B.Cu")
		(net "PHY_SCC_B_TO_DRV_B_8_DP")
	)
	(segment
		(start 356.006654 -237.363762)
		(end 360.605832 -238.717582)
		(width 0.127)
		(layer "B.Cu")
		(net "PHY_SCC_B_TO_DRV_B_8_DP")
	)
	(segment
		(start 364.230666 -239.625886)
		(end 364.33379 -239.815116)
		(width 0.127)
		(layer "B.Cu")
		(net "PHY_SCC_B_TO_DRV_B_8_DP")
	)
	(segment
		(start 361.818428 -238.915702)
		(end 362.183934 -239.023398)
		(width 0.127)
		(layer "B.Cu")
		(net "PHY_SCC_B_TO_DRV_B_8_DP")
	)
	(segment
		(start 363.310424 -239.513872)
		(end 363.67593 -239.621568)
		(width 0.127)
		(layer "B.Cu")
		(net "PHY_SCC_B_TO_DRV_B_8_DP")
	)
	(segment
		(start 280.328624 -225.035872)
		(end 290.898834 -225.035872)
		(width 0.127)
		(layer "B.Cu")
		(net "PHY_SCC_B_TO_DRV_B_8_DP")
	)
	(segment
		(start 362.652564 -239.320324)
		(end 362.841794 -239.2172)
		(width 0.127)
		(layer "B.Cu")
		(net "PHY_SCC_B_TO_DRV_B_8_DP")
	)
	(segment
		(start 280.636726 -224.294446)
		(end 280.298906 -224.294446)
		(width 0.127)
		(layer "B.Cu")
		(net "PHY_SCC_B_TO_DRV_B_8_DP")
	)
	(segment
		(start 361.160568 -238.722154)
		(end 361.263692 -238.911384)
		(width 0.127)
		(layer "B.Cu")
		(net "PHY_SCC_B_TO_DRV_B_8_DP")
	)
	(segment
		(start 382.49225 -244.519958)
		(end 382.49225 -244.302534)
		(width 0.127)
		(layer "B.Cu")
		(net "PHY_SCC_B_TO_DRV_B_8_DP")
	)
	(segment
		(start 362.183934 -239.023398)
		(end 362.287058 -239.212628)
		(width 0.127)
		(layer "B.Cu")
		(net "PHY_SCC_B_TO_DRV_B_8_DP")
	)
	(segment
		(start 361.629198 -239.01908)
		(end 361.818428 -238.915702)
		(width 0.127)
		(layer "B.Cu")
		(net "PHY_SCC_B_TO_DRV_B_8_DP")
	)
	(segment
		(start 360.605832 -238.717582)
		(end 360.795062 -238.614458)
		(width 0.127)
		(layer "B.Cu")
		(net "PHY_SCC_B_TO_DRV_B_8_DP")
	)
	(segment
		(start 280.082752 -224.5106)
		(end 280.082752 -224.79)
		(width 0.127)
		(layer "B.Cu")
		(net "PHY_SCC_B_TO_DRV_B_8_DP")
	)
	(arc
		(start 382.284224 -244.727984)
		(mid 382.431321 -244.667055)
		(end 382.49225 -244.519958)
		(width 0.127)
		(layer "B.Cu")
		(net "PHY_SCC_B_TO_DRV_B_8_DP")
	)
	(arc
		(start 280.082752 -224.79)
		(mid 280.154766 -224.963858)
		(end 280.328624 -225.035872)
		(width 0.127)
		(layer "B.Cu")
		(net "PHY_SCC_B_TO_DRV_B_8_DP")
	)
	(arc
		(start 280.298906 -224.294446)
		(mid 280.146062 -224.357756)
		(end 280.082752 -224.5106)
		(width 0.127)
		(layer "B.Cu")
		(net "PHY_SCC_B_TO_DRV_B_8_DP")
	)
	(segment
		(start 382.49225 -245.216934)
		(end 382.49225 -245.445534)
		(width 0.127)
		(layer "F.Cu")
		(net "PHY_SCC_B_TO_DRV_B_8_DN")
	)
	(segment
		(start 383.924556 -245.020084)
		(end 382.6891 -245.020084)
		(width 0.127)
		(layer "F.Cu")
		(net "PHY_SCC_B_TO_DRV_B_8_DN")
	)
	(segment
		(start 384.123946 -245.219474)
		(end 383.924556 -245.020084)
		(width 0.127)
		(layer "F.Cu")
		(net "PHY_SCC_B_TO_DRV_B_8_DN")
	)
	(segment
		(start 384.455162 -245.219474)
		(end 384.123946 -245.219474)
		(width 0.127)
		(layer "F.Cu")
		(net "PHY_SCC_B_TO_DRV_B_8_DN")
	)
	(arc
		(start 382.6891 -245.020084)
		(mid 382.549906 -245.07774)
		(end 382.49225 -245.216934)
		(width 0.127)
		(layer "F.Cu")
		(net "PHY_SCC_B_TO_DRV_B_8_DN")
	)
	(segment
		(start 280.328624 -225.327972)
		(end 290.874704 -225.327972)
		(width 0.127)
		(layer "B.Cu")
		(net "PHY_SCC_B_TO_DRV_B_8_DN")
	)
	(segment
		(start 290.874704 -225.327972)
		(end 310.861964 -228.617526)
		(width 0.127)
		(layer "B.Cu")
		(net "PHY_SCC_B_TO_DRV_B_8_DN")
	)
	(segment
		(start 279.790652 -224.5106)
		(end 279.790652 -224.79)
		(width 0.127)
		(layer "B.Cu")
		(net "PHY_SCC_B_TO_DRV_B_8_DN")
	)
	(segment
		(start 279.236678 -224.294446)
		(end 279.574498 -224.294446)
		(width 0.127)
		(layer "B.Cu")
		(net "PHY_SCC_B_TO_DRV_B_8_DN")
	)
	(segment
		(start 355.93274 -237.646718)
		(end 380.980442 -245.020084)
		(width 0.127)
		(layer "B.Cu")
		(net "PHY_SCC_B_TO_DRV_B_8_DN")
	)
	(segment
		(start 330.84897 -231.906572)
		(end 355.93274 -237.646718)
		(width 0.127)
		(layer "B.Cu")
		(net "PHY_SCC_B_TO_DRV_B_8_DN")
	)
	(segment
		(start 382.49225 -245.22811)
		(end 382.49225 -245.445534)
		(width 0.127)
		(layer "B.Cu")
		(net "PHY_SCC_B_TO_DRV_B_8_DN")
	)
	(segment
		(start 310.861964 -228.617526)
		(end 330.84897 -231.906572)
		(width 0.127)
		(layer "B.Cu")
		(net "PHY_SCC_B_TO_DRV_B_8_DN")
	)
	(segment
		(start 380.980442 -245.020084)
		(end 382.284224 -245.020084)
		(width 0.127)
		(layer "B.Cu")
		(net "PHY_SCC_B_TO_DRV_B_8_DN")
	)
	(arc
		(start 279.574498 -224.294446)
		(mid 279.727342 -224.357756)
		(end 279.790652 -224.5106)
		(width 0.127)
		(layer "B.Cu")
		(net "PHY_SCC_B_TO_DRV_B_8_DN")
	)
	(arc
		(start 279.790652 -224.79)
		(mid 279.94822 -225.170404)
		(end 280.328624 -225.327972)
		(width 0.127)
		(layer "B.Cu")
		(net "PHY_SCC_B_TO_DRV_B_8_DN")
	)
	(arc
		(start 382.284224 -245.020084)
		(mid 382.431321 -245.081013)
		(end 382.49225 -245.22811)
		(width 0.127)
		(layer "B.Cu")
		(net "PHY_SCC_B_TO_DRV_B_8_DN")
	)
	(segment
		(start 352.574098 -244.660674)
		(end 352.491548 -244.743224)
		(width 0.127)
		(layer "F.Cu")
		(net "PHY_SCC_B_TO_DRV_B_7_DP")
	)
	(segment
		(start 352.491548 -244.743224)
		(end 351.1169 -244.743224)
		(width 0.127)
		(layer "F.Cu")
		(net "PHY_SCC_B_TO_DRV_B_7_DP")
	)
	(segment
		(start 352.905314 -244.660674)
		(end 352.574098 -244.660674)
		(width 0.127)
		(layer "F.Cu")
		(net "PHY_SCC_B_TO_DRV_B_7_DP")
	)
	(segment
		(start 350.942402 -244.568726)
		(end 350.942402 -244.317774)
		(width 0.127)
		(layer "F.Cu")
		(net "PHY_SCC_B_TO_DRV_B_7_DP")
	)
	(arc
		(start 351.1169 -244.743224)
		(mid 350.993511 -244.692115)
		(end 350.942402 -244.568726)
		(width 0.127)
		(layer "F.Cu")
		(net "PHY_SCC_B_TO_DRV_B_7_DP")
	)
	(segment
		(start 312.304938 -232.296462)
		(end 312.41365 -232.482644)
		(width 0.127)
		(layer "B.Cu")
		(net "PHY_SCC_B_TO_DRV_B_7_DP")
	)
	(segment
		(start 313.33694 -232.566972)
		(end 313.445652 -232.7529)
		(width 0.127)
		(layer "B.Cu")
		(net "PHY_SCC_B_TO_DRV_B_7_DP")
	)
	(segment
		(start 312.41365 -232.482644)
		(end 312.782458 -232.579164)
		(width 0.127)
		(layer "B.Cu")
		(net "PHY_SCC_B_TO_DRV_B_7_DP")
	)
	(segment
		(start 312.968386 -232.470198)
		(end 313.33694 -232.566972)
		(width 0.127)
		(layer "B.Cu")
		(net "PHY_SCC_B_TO_DRV_B_7_DP")
	)
	(segment
		(start 314.368942 -232.837228)
		(end 314.477654 -233.023156)
		(width 0.127)
		(layer "B.Cu")
		(net "PHY_SCC_B_TO_DRV_B_7_DP")
	)
	(segment
		(start 312.782458 -232.579164)
		(end 312.968386 -232.470198)
		(width 0.127)
		(layer "B.Cu")
		(net "PHY_SCC_B_TO_DRV_B_7_DP")
	)
	(segment
		(start 329.521312 -236.963204)
		(end 350.26346 -244.743224)
		(width 0.127)
		(layer "B.Cu")
		(net "PHY_SCC_B_TO_DRV_B_7_DP")
	)
	(segment
		(start 350.26346 -244.743224)
		(end 350.788224 -244.743224)
		(width 0.127)
		(layer "B.Cu")
		(net "PHY_SCC_B_TO_DRV_B_7_DP")
	)
	(segment
		(start 314.477654 -233.023156)
		(end 314.846208 -233.119676)
		(width 0.127)
		(layer "B.Cu")
		(net "PHY_SCC_B_TO_DRV_B_7_DP")
	)
	(segment
		(start 315.400944 -233.107484)
		(end 315.509656 -233.293412)
		(width 0.127)
		(layer "B.Cu")
		(net "PHY_SCC_B_TO_DRV_B_7_DP")
	)
	(segment
		(start 315.03239 -233.010964)
		(end 315.400944 -233.107484)
		(width 0.127)
		(layer "B.Cu")
		(net "PHY_SCC_B_TO_DRV_B_7_DP")
	)
	(segment
		(start 313.814206 -232.84942)
		(end 314.000388 -232.740708)
		(width 0.127)
		(layer "B.Cu")
		(net "PHY_SCC_B_TO_DRV_B_7_DP")
	)
	(segment
		(start 313.445652 -232.7529)
		(end 313.814206 -232.84942)
		(width 0.127)
		(layer "B.Cu")
		(net "PHY_SCC_B_TO_DRV_B_7_DP")
	)
	(segment
		(start 279.401524 -226.83597)
		(end 290.852352 -226.83597)
		(width 0.127)
		(layer "B.Cu")
		(net "PHY_SCC_B_TO_DRV_B_7_DP")
	)
	(segment
		(start 279.636728 -226.094544)
		(end 279.32761 -226.094544)
		(width 0.127)
		(layer "B.Cu")
		(net "PHY_SCC_B_TO_DRV_B_7_DP")
	)
	(segment
		(start 315.509656 -233.293412)
		(end 329.521312 -236.963204)
		(width 0.127)
		(layer "B.Cu")
		(net "PHY_SCC_B_TO_DRV_B_7_DP")
	)
	(segment
		(start 290.852352 -226.83597)
		(end 302.427386 -229.867206)
		(width 0.127)
		(layer "B.Cu")
		(net "PHY_SCC_B_TO_DRV_B_7_DP")
	)
	(segment
		(start 302.427386 -229.867206)
		(end 311.750456 -232.308908)
		(width 0.127)
		(layer "B.Cu")
		(net "PHY_SCC_B_TO_DRV_B_7_DP")
	)
	(segment
		(start 311.750456 -232.308908)
		(end 311.936384 -232.199942)
		(width 0.127)
		(layer "B.Cu")
		(net "PHY_SCC_B_TO_DRV_B_7_DP")
	)
	(segment
		(start 279.082754 -226.3394)
		(end 279.082754 -226.5172)
		(width 0.127)
		(layer "B.Cu")
		(net "PHY_SCC_B_TO_DRV_B_7_DP")
	)
	(segment
		(start 314.000388 -232.740708)
		(end 314.368942 -232.837228)
		(width 0.127)
		(layer "B.Cu")
		(net "PHY_SCC_B_TO_DRV_B_7_DP")
	)
	(segment
		(start 350.942402 -244.589046)
		(end 350.942402 -244.317774)
		(width 0.127)
		(layer "B.Cu")
		(net "PHY_SCC_B_TO_DRV_B_7_DP")
	)
	(segment
		(start 311.936384 -232.199942)
		(end 312.304938 -232.296462)
		(width 0.127)
		(layer "B.Cu")
		(net "PHY_SCC_B_TO_DRV_B_7_DP")
	)
	(segment
		(start 314.846208 -233.119676)
		(end 315.03239 -233.010964)
		(width 0.127)
		(layer "B.Cu")
		(net "PHY_SCC_B_TO_DRV_B_7_DP")
	)
	(arc
		(start 350.788224 -244.743224)
		(mid 350.897244 -244.698066)
		(end 350.942402 -244.589046)
		(width 0.127)
		(layer "B.Cu")
		(net "PHY_SCC_B_TO_DRV_B_7_DP")
	)
	(arc
		(start 279.32761 -226.094544)
		(mid 279.154471 -226.166261)
		(end 279.082754 -226.3394)
		(width 0.127)
		(layer "B.Cu")
		(net "PHY_SCC_B_TO_DRV_B_7_DP")
	)
	(arc
		(start 279.082754 -226.5172)
		(mid 279.17612 -226.742604)
		(end 279.401524 -226.83597)
		(width 0.127)
		(layer "B.Cu")
		(net "PHY_SCC_B_TO_DRV_B_7_DP")
	)
	(segment
		(start 350.942402 -245.209822)
		(end 350.942402 -245.460774)
		(width 0.127)
		(layer "F.Cu")
		(net "PHY_SCC_B_TO_DRV_B_7_DN")
	)
	(segment
		(start 352.389948 -245.035324)
		(end 351.1169 -245.035324)
		(width 0.127)
		(layer "F.Cu")
		(net "PHY_SCC_B_TO_DRV_B_7_DN")
	)
	(segment
		(start 352.574098 -245.219474)
		(end 352.389948 -245.035324)
		(width 0.127)
		(layer "F.Cu")
		(net "PHY_SCC_B_TO_DRV_B_7_DN")
	)
	(segment
		(start 352.905314 -245.219474)
		(end 352.574098 -245.219474)
		(width 0.127)
		(layer "F.Cu")
		(net "PHY_SCC_B_TO_DRV_B_7_DN")
	)
	(arc
		(start 351.1169 -245.035324)
		(mid 350.993511 -245.086433)
		(end 350.942402 -245.209822)
		(width 0.127)
		(layer "F.Cu")
		(net "PHY_SCC_B_TO_DRV_B_7_DN")
	)
	(segment
		(start 350.210374 -245.035324)
		(end 350.788224 -245.035324)
		(width 0.127)
		(layer "B.Cu")
		(net "PHY_SCC_B_TO_DRV_B_7_DN")
	)
	(segment
		(start 279.401524 -227.12807)
		(end 290.814252 -227.12807)
		(width 0.127)
		(layer "B.Cu")
		(net "PHY_SCC_B_TO_DRV_B_7_DN")
	)
	(segment
		(start 350.942402 -245.189502)
		(end 350.942402 -245.460774)
		(width 0.127)
		(layer "B.Cu")
		(net "PHY_SCC_B_TO_DRV_B_7_DN")
	)
	(segment
		(start 278.790654 -226.3394)
		(end 278.790654 -226.5172)
		(width 0.127)
		(layer "B.Cu")
		(net "PHY_SCC_B_TO_DRV_B_7_DN")
	)
	(segment
		(start 302.353472 -230.150162)
		(end 329.431142 -237.241588)
		(width 0.127)
		(layer "B.Cu")
		(net "PHY_SCC_B_TO_DRV_B_7_DN")
	)
	(segment
		(start 278.23668 -226.094544)
		(end 278.545798 -226.094544)
		(width 0.127)
		(layer "B.Cu")
		(net "PHY_SCC_B_TO_DRV_B_7_DN")
	)
	(segment
		(start 290.814252 -227.12807)
		(end 302.353472 -230.150162)
		(width 0.127)
		(layer "B.Cu")
		(net "PHY_SCC_B_TO_DRV_B_7_DN")
	)
	(segment
		(start 329.431142 -237.241588)
		(end 350.210374 -245.035324)
		(width 0.127)
		(layer "B.Cu")
		(net "PHY_SCC_B_TO_DRV_B_7_DN")
	)
	(arc
		(start 278.545798 -226.094544)
		(mid 278.718937 -226.166261)
		(end 278.790654 -226.3394)
		(width 0.127)
		(layer "B.Cu")
		(net "PHY_SCC_B_TO_DRV_B_7_DN")
	)
	(arc
		(start 278.790654 -226.5172)
		(mid 278.969574 -226.94915)
		(end 279.401524 -227.12807)
		(width 0.127)
		(layer "B.Cu")
		(net "PHY_SCC_B_TO_DRV_B_7_DN")
	)
	(arc
		(start 350.788224 -245.035324)
		(mid 350.897244 -245.080482)
		(end 350.942402 -245.189502)
		(width 0.127)
		(layer "B.Cu")
		(net "PHY_SCC_B_TO_DRV_B_7_DN")
	)
	(segment
		(start 321.023996 -244.660674)
		(end 320.946526 -244.738144)
		(width 0.127)
		(layer "F.Cu")
		(net "PHY_SCC_B_TO_DRV_B_6_DP")
	)
	(segment
		(start 319.40246 -244.560344)
		(end 319.40246 -244.312694)
		(width 0.127)
		(layer "F.Cu")
		(net "PHY_SCC_B_TO_DRV_B_6_DP")
	)
	(segment
		(start 320.946526 -244.738144)
		(end 319.58026 -244.738144)
		(width 0.127)
		(layer "F.Cu")
		(net "PHY_SCC_B_TO_DRV_B_6_DP")
	)
	(segment
		(start 321.355212 -244.660674)
		(end 321.023996 -244.660674)
		(width 0.127)
		(layer "F.Cu")
		(net "PHY_SCC_B_TO_DRV_B_6_DP")
	)
	(arc
		(start 319.58026 -244.738144)
		(mid 319.454536 -244.686068)
		(end 319.40246 -244.560344)
		(width 0.127)
		(layer "F.Cu")
		(net "PHY_SCC_B_TO_DRV_B_6_DP")
	)
	(segment
		(start 309.89016 -240.065052)
		(end 317.922148 -244.738144)
		(width 0.127)
		(layer "B.Cu")
		(net "PHY_SCC_B_TO_DRV_B_6_DP")
	)
	(segment
		(start 309.297324 -239.720374)
		(end 309.505858 -239.665256)
		(width 0.127)
		(layer "B.Cu")
		(net "PHY_SCC_B_TO_DRV_B_6_DP")
	)
	(segment
		(start 308.96814 -239.528604)
		(end 309.297324 -239.720374)
		(width 0.127)
		(layer "B.Cu")
		(net "PHY_SCC_B_TO_DRV_B_6_DP")
	)
	(segment
		(start 290.246054 -228.635814)
		(end 306.531518 -238.110776)
		(width 0.127)
		(layer "B.Cu")
		(net "PHY_SCC_B_TO_DRV_B_6_DP")
	)
	(segment
		(start 309.505858 -239.665256)
		(end 309.835042 -239.856772)
		(width 0.127)
		(layer "B.Cu")
		(net "PHY_SCC_B_TO_DRV_B_6_DP")
	)
	(segment
		(start 308.04612 -238.992156)
		(end 308.375304 -239.183926)
		(width 0.127)
		(layer "B.Cu")
		(net "PHY_SCC_B_TO_DRV_B_6_DP")
	)
	(segment
		(start 309.835042 -239.856772)
		(end 309.89016 -240.065052)
		(width 0.127)
		(layer "B.Cu")
		(net "PHY_SCC_B_TO_DRV_B_6_DP")
	)
	(segment
		(start 308.913022 -239.320324)
		(end 308.96814 -239.528604)
		(width 0.127)
		(layer "B.Cu")
		(net "PHY_SCC_B_TO_DRV_B_6_DP")
	)
	(segment
		(start 306.739544 -238.055658)
		(end 307.068728 -238.247428)
		(width 0.127)
		(layer "B.Cu")
		(net "PHY_SCC_B_TO_DRV_B_6_DP")
	)
	(segment
		(start 306.531518 -238.110776)
		(end 306.739544 -238.055658)
		(width 0.127)
		(layer "B.Cu")
		(net "PHY_SCC_B_TO_DRV_B_6_DP")
	)
	(segment
		(start 307.068728 -238.247428)
		(end 307.123846 -238.455708)
		(width 0.127)
		(layer "B.Cu")
		(net "PHY_SCC_B_TO_DRV_B_6_DP")
	)
	(segment
		(start 280.397966 -228.635814)
		(end 290.246054 -228.635814)
		(width 0.127)
		(layer "B.Cu")
		(net "PHY_SCC_B_TO_DRV_B_6_DP")
	)
	(segment
		(start 308.583838 -239.128808)
		(end 308.913022 -239.320324)
		(width 0.127)
		(layer "B.Cu")
		(net "PHY_SCC_B_TO_DRV_B_6_DP")
	)
	(segment
		(start 308.375304 -239.183926)
		(end 308.583838 -239.128808)
		(width 0.127)
		(layer "B.Cu")
		(net "PHY_SCC_B_TO_DRV_B_6_DP")
	)
	(segment
		(start 307.123846 -238.455708)
		(end 307.453284 -238.647224)
		(width 0.127)
		(layer "B.Cu")
		(net "PHY_SCC_B_TO_DRV_B_6_DP")
	)
	(segment
		(start 307.661564 -238.59236)
		(end 307.991002 -238.783876)
		(width 0.127)
		(layer "B.Cu")
		(net "PHY_SCC_B_TO_DRV_B_6_DP")
	)
	(segment
		(start 307.991002 -238.783876)
		(end 308.04612 -238.992156)
		(width 0.127)
		(layer "B.Cu")
		(net "PHY_SCC_B_TO_DRV_B_6_DP")
	)
	(segment
		(start 280.636726 -227.894388)
		(end 280.280364 -227.894388)
		(width 0.127)
		(layer "B.Cu")
		(net "PHY_SCC_B_TO_DRV_B_6_DP")
	)
	(segment
		(start 319.40246 -244.560344)
		(end 319.40246 -244.312694)
		(width 0.127)
		(layer "B.Cu")
		(net "PHY_SCC_B_TO_DRV_B_6_DP")
	)
	(segment
		(start 307.453284 -238.647224)
		(end 307.661564 -238.59236)
		(width 0.127)
		(layer "B.Cu")
		(net "PHY_SCC_B_TO_DRV_B_6_DP")
	)
	(segment
		(start 280.082752 -228.092)
		(end 280.082752 -228.3206)
		(width 0.127)
		(layer "B.Cu")
		(net "PHY_SCC_B_TO_DRV_B_6_DP")
	)
	(segment
		(start 317.922148 -244.738144)
		(end 319.22466 -244.738144)
		(width 0.127)
		(layer "B.Cu")
		(net "PHY_SCC_B_TO_DRV_B_6_DP")
	)
	(arc
		(start 319.22466 -244.738144)
		(mid 319.350384 -244.686068)
		(end 319.40246 -244.560344)
		(width 0.127)
		(layer "B.Cu")
		(net "PHY_SCC_B_TO_DRV_B_6_DP")
	)
	(arc
		(start 280.082752 -228.3206)
		(mid 280.175076 -228.54349)
		(end 280.397966 -228.635814)
		(width 0.127)
		(layer "B.Cu")
		(net "PHY_SCC_B_TO_DRV_B_6_DP")
	)
	(arc
		(start 280.280364 -227.894388)
		(mid 280.140631 -227.952267)
		(end 280.082752 -228.092)
		(width 0.127)
		(layer "B.Cu")
		(net "PHY_SCC_B_TO_DRV_B_6_DP")
	)
	(segment
		(start 321.355212 -245.219474)
		(end 321.023996 -245.219474)
		(width 0.127)
		(layer "F.Cu")
		(net "PHY_SCC_B_TO_DRV_B_6_DN")
	)
	(segment
		(start 321.023996 -245.219474)
		(end 320.834766 -245.030244)
		(width 0.127)
		(layer "F.Cu")
		(net "PHY_SCC_B_TO_DRV_B_6_DN")
	)
	(segment
		(start 320.834766 -245.030244)
		(end 319.58026 -245.030244)
		(width 0.127)
		(layer "F.Cu")
		(net "PHY_SCC_B_TO_DRV_B_6_DN")
	)
	(segment
		(start 319.40246 -245.208044)
		(end 319.40246 -245.455694)
		(width 0.127)
		(layer "F.Cu")
		(net "PHY_SCC_B_TO_DRV_B_6_DN")
	)
	(arc
		(start 319.58026 -245.030244)
		(mid 319.454536 -245.08232)
		(end 319.40246 -245.208044)
		(width 0.127)
		(layer "F.Cu")
		(net "PHY_SCC_B_TO_DRV_B_6_DN")
	)
	(segment
		(start 290.16706 -228.927914)
		(end 317.843154 -245.030244)
		(width 0.127)
		(layer "B.Cu")
		(net "PHY_SCC_B_TO_DRV_B_6_DN")
	)
	(segment
		(start 279.790652 -228.092)
		(end 279.790652 -228.3206)
		(width 0.127)
		(layer "B.Cu")
		(net "PHY_SCC_B_TO_DRV_B_6_DN")
	)
	(segment
		(start 279.236678 -227.894388)
		(end 279.59304 -227.894388)
		(width 0.127)
		(layer "B.Cu")
		(net "PHY_SCC_B_TO_DRV_B_6_DN")
	)
	(segment
		(start 319.40246 -245.208044)
		(end 319.40246 -245.455694)
		(width 0.127)
		(layer "B.Cu")
		(net "PHY_SCC_B_TO_DRV_B_6_DN")
	)
	(segment
		(start 317.843154 -245.030244)
		(end 319.22466 -245.030244)
		(width 0.127)
		(layer "B.Cu")
		(net "PHY_SCC_B_TO_DRV_B_6_DN")
	)
	(segment
		(start 280.397966 -228.927914)
		(end 290.16706 -228.927914)
		(width 0.127)
		(layer "B.Cu")
		(net "PHY_SCC_B_TO_DRV_B_6_DN")
	)
	(arc
		(start 279.790652 -228.3206)
		(mid 279.96853 -228.750036)
		(end 280.397966 -228.927914)
		(width 0.127)
		(layer "B.Cu")
		(net "PHY_SCC_B_TO_DRV_B_6_DN")
	)
	(arc
		(start 319.22466 -245.030244)
		(mid 319.350384 -245.08232)
		(end 319.40246 -245.208044)
		(width 0.127)
		(layer "B.Cu")
		(net "PHY_SCC_B_TO_DRV_B_6_DN")
	)
	(arc
		(start 279.59304 -227.894388)
		(mid 279.732773 -227.952267)
		(end 279.790652 -228.092)
		(width 0.127)
		(layer "B.Cu")
		(net "PHY_SCC_B_TO_DRV_B_6_DN")
	)
	(segment
		(start 192.035684 -244.68582)
		(end 192.035684 -244.419374)
		(width 0.127)
		(layer "F.Cu")
		(net "PHY_SCC_B_TO_DRV_B_5_DP")
	)
	(segment
		(start 190.492888 -244.660674)
		(end 190.888874 -244.660674)
		(width 0.127)
		(layer "F.Cu")
		(net "PHY_SCC_B_TO_DRV_B_5_DP")
	)
	(segment
		(start 190.888874 -244.660674)
		(end 191.073024 -244.844824)
		(width 0.127)
		(layer "F.Cu")
		(net "PHY_SCC_B_TO_DRV_B_5_DP")
	)
	(segment
		(start 191.073024 -244.844824)
		(end 191.87668 -244.844824)
		(width 0.127)
		(layer "F.Cu")
		(net "PHY_SCC_B_TO_DRV_B_5_DP")
	)
	(arc
		(start 191.87668 -244.844824)
		(mid 191.989113 -244.798253)
		(end 192.035684 -244.68582)
		(width 0.127)
		(layer "F.Cu")
		(net "PHY_SCC_B_TO_DRV_B_5_DP")
	)
	(segment
		(start 258.764024 -239.408208)
		(end 243.841778 -236.236002)
		(width 0.127)
		(layer "B.Cu")
		(net "PHY_SCC_B_TO_DRV_B_5_DP")
	)
	(segment
		(start 267.042392 -237.648496)
		(end 258.764024 -239.408208)
		(width 0.127)
		(layer "B.Cu")
		(net "PHY_SCC_B_TO_DRV_B_5_DP")
	)
	(segment
		(start 229.046024 -238.190786)
		(end 214.287354 -240.140998)
		(width 0.127)
		(layer "B.Cu")
		(net "PHY_SCC_B_TO_DRV_B_5_DP")
	)
	(segment
		(start 192.035684 -244.710204)
		(end 192.035684 -244.419374)
		(width 0.127)
		(layer "B.Cu")
		(net "PHY_SCC_B_TO_DRV_B_5_DP")
	)
	(segment
		(start 192.962784 -244.844824)
		(end 192.170304 -244.844824)
		(width 0.127)
		(layer "B.Cu")
		(net "PHY_SCC_B_TO_DRV_B_5_DP")
	)
	(segment
		(start 214.287354 -240.140998)
		(end 192.962784 -244.844824)
		(width 0.127)
		(layer "B.Cu")
		(net "PHY_SCC_B_TO_DRV_B_5_DP")
	)
	(segment
		(start 243.841778 -236.236002)
		(end 229.046024 -238.190786)
		(width 0.127)
		(layer "B.Cu")
		(net "PHY_SCC_B_TO_DRV_B_5_DP")
	)
	(segment
		(start 280.082752 -238.4806)
		(end 280.082752 -238.3028)
		(width 0.127)
		(layer "B.Cu")
		(net "PHY_SCC_B_TO_DRV_B_5_DP")
	)
	(segment
		(start 280.636726 -238.694468)
		(end 280.29662 -238.694468)
		(width 0.127)
		(layer "B.Cu")
		(net "PHY_SCC_B_TO_DRV_B_5_DP")
	)
	(segment
		(start 279.428448 -237.648496)
		(end 267.042392 -237.648496)
		(width 0.127)
		(layer "B.Cu")
		(net "PHY_SCC_B_TO_DRV_B_5_DP")
	)
	(arc
		(start 280.082752 -238.3028)
		(mid 279.891111 -237.840137)
		(end 279.428448 -237.648496)
		(width 0.127)
		(layer "B.Cu")
		(net "PHY_SCC_B_TO_DRV_B_5_DP")
	)
	(arc
		(start 280.29662 -238.694468)
		(mid 280.145392 -238.631828)
		(end 280.082752 -238.4806)
		(width 0.127)
		(layer "B.Cu")
		(net "PHY_SCC_B_TO_DRV_B_5_DP")
	)
	(arc
		(start 192.170304 -244.844824)
		(mid 192.075113 -244.805395)
		(end 192.035684 -244.710204)
		(width 0.127)
		(layer "B.Cu")
		(net "PHY_SCC_B_TO_DRV_B_5_DP")
	)
	(segment
		(start 190.492888 -245.219474)
		(end 190.873126 -245.219474)
		(width 0.127)
		(layer "F.Cu")
		(net "PHY_SCC_B_TO_DRV_B_5_DN")
	)
	(segment
		(start 190.873126 -245.219474)
		(end 190.955676 -245.136924)
		(width 0.127)
		(layer "F.Cu")
		(net "PHY_SCC_B_TO_DRV_B_5_DN")
	)
	(segment
		(start 190.955676 -245.136924)
		(end 191.87668 -245.136924)
		(width 0.127)
		(layer "F.Cu")
		(net "PHY_SCC_B_TO_DRV_B_5_DN")
	)
	(segment
		(start 192.035684 -245.295928)
		(end 192.035684 -245.562374)
		(width 0.127)
		(layer "F.Cu")
		(net "PHY_SCC_B_TO_DRV_B_5_DN")
	)
	(arc
		(start 191.87668 -245.136924)
		(mid 191.989113 -245.183495)
		(end 192.035684 -245.295928)
		(width 0.127)
		(layer "F.Cu")
		(net "PHY_SCC_B_TO_DRV_B_5_DN")
	)
	(segment
		(start 221.403418 -239.649254)
		(end 221.02572 -239.699038)
		(width 0.127)
		(layer "B.Cu")
		(net "PHY_SCC_B_TO_DRV_B_5_DN")
	)
	(segment
		(start 222.592138 -239.338358)
		(end 222.461074 -239.509554)
		(width 0.127)
		(layer "B.Cu")
		(net "PHY_SCC_B_TO_DRV_B_5_DN")
	)
	(segment
		(start 192.035684 -245.281196)
		(end 192.035684 -245.562374)
		(width 0.127)
		(layer "B.Cu")
		(net "PHY_SCC_B_TO_DRV_B_5_DN")
	)
	(segment
		(start 222.461074 -239.509554)
		(end 222.083376 -239.559338)
		(width 0.127)
		(layer "B.Cu")
		(net "PHY_SCC_B_TO_DRV_B_5_DN")
	)
	(segment
		(start 222.083376 -239.559338)
		(end 221.912434 -239.428274)
		(width 0.127)
		(layer "B.Cu")
		(net "PHY_SCC_B_TO_DRV_B_5_DN")
	)
	(segment
		(start 222.969836 -239.288574)
		(end 222.592138 -239.338358)
		(width 0.127)
		(layer "B.Cu")
		(net "PHY_SCC_B_TO_DRV_B_5_DN")
	)
	(segment
		(start 279.428448 -237.940596)
		(end 267.073126 -237.940596)
		(width 0.127)
		(layer "B.Cu")
		(net "PHY_SCC_B_TO_DRV_B_5_DN")
	)
	(segment
		(start 223.649794 -239.198658)
		(end 223.51873 -239.3696)
		(width 0.127)
		(layer "B.Cu")
		(net "PHY_SCC_B_TO_DRV_B_5_DN")
	)
	(segment
		(start 219.797122 -239.707674)
		(end 214.338154 -240.429034)
		(width 0.127)
		(layer "B.Cu")
		(net "PHY_SCC_B_TO_DRV_B_5_DN")
	)
	(segment
		(start 267.073126 -237.940596)
		(end 262.963914 -238.814102)
		(width 0.127)
		(layer "B.Cu")
		(net "PHY_SCC_B_TO_DRV_B_5_DN")
	)
	(segment
		(start 214.338154 -240.429034)
		(end 192.994788 -245.136924)
		(width 0.127)
		(layer "B.Cu")
		(net "PHY_SCC_B_TO_DRV_B_5_DN")
	)
	(segment
		(start 221.912434 -239.428274)
		(end 221.534736 -239.478058)
		(width 0.127)
		(layer "B.Cu")
		(net "PHY_SCC_B_TO_DRV_B_5_DN")
	)
	(segment
		(start 279.236678 -238.694468)
		(end 279.576784 -238.694468)
		(width 0.127)
		(layer "B.Cu")
		(net "PHY_SCC_B_TO_DRV_B_5_DN")
	)
	(segment
		(start 220.47708 -239.618012)
		(end 220.346016 -239.788954)
		(width 0.127)
		(layer "B.Cu")
		(net "PHY_SCC_B_TO_DRV_B_5_DN")
	)
	(segment
		(start 279.790652 -238.4806)
		(end 279.790652 -238.3028)
		(width 0.127)
		(layer "B.Cu")
		(net "PHY_SCC_B_TO_DRV_B_5_DN")
	)
	(segment
		(start 220.346016 -239.788954)
		(end 219.968064 -239.838738)
		(width 0.127)
		(layer "B.Cu")
		(net "PHY_SCC_B_TO_DRV_B_5_DN")
	)
	(segment
		(start 262.963914 -238.814356)
		(end 258.764024 -239.706912)
		(width 0.127)
		(layer "B.Cu")
		(net "PHY_SCC_B_TO_DRV_B_5_DN")
	)
	(segment
		(start 223.141032 -239.419638)
		(end 222.969836 -239.288574)
		(width 0.127)
		(layer "B.Cu")
		(net "PHY_SCC_B_TO_DRV_B_5_DN")
	)
	(segment
		(start 220.854778 -239.567974)
		(end 220.47708 -239.618012)
		(width 0.127)
		(layer "B.Cu")
		(net "PHY_SCC_B_TO_DRV_B_5_DN")
	)
	(segment
		(start 221.02572 -239.699038)
		(end 220.854778 -239.567974)
		(width 0.127)
		(layer "B.Cu")
		(net "PHY_SCC_B_TO_DRV_B_5_DN")
	)
	(segment
		(start 243.830094 -236.53242)
		(end 223.649794 -239.198658)
		(width 0.127)
		(layer "B.Cu")
		(net "PHY_SCC_B_TO_DRV_B_5_DN")
	)
	(segment
		(start 262.963914 -238.814102)
		(end 262.963914 -238.814356)
		(width 0.127)
		(layer "B.Cu")
		(net "PHY_SCC_B_TO_DRV_B_5_DN")
	)
	(segment
		(start 258.764024 -239.706912)
		(end 243.830094 -236.53242)
		(width 0.127)
		(layer "B.Cu")
		(net "PHY_SCC_B_TO_DRV_B_5_DN")
	)
	(segment
		(start 221.534736 -239.478058)
		(end 221.403418 -239.649254)
		(width 0.127)
		(layer "B.Cu")
		(net "PHY_SCC_B_TO_DRV_B_5_DN")
	)
	(segment
		(start 192.994788 -245.136924)
		(end 192.179956 -245.136924)
		(width 0.127)
		(layer "B.Cu")
		(net "PHY_SCC_B_TO_DRV_B_5_DN")
	)
	(segment
		(start 223.51873 -239.3696)
		(end 223.141032 -239.419638)
		(width 0.127)
		(layer "B.Cu")
		(net "PHY_SCC_B_TO_DRV_B_5_DN")
	)
	(segment
		(start 219.968064 -239.838738)
		(end 219.797122 -239.707674)
		(width 0.127)
		(layer "B.Cu")
		(net "PHY_SCC_B_TO_DRV_B_5_DN")
	)
	(arc
		(start 279.576784 -238.694468)
		(mid 279.728012 -238.631828)
		(end 279.790652 -238.4806)
		(width 0.127)
		(layer "B.Cu")
		(net "PHY_SCC_B_TO_DRV_B_5_DN")
	)
	(arc
		(start 192.179956 -245.136924)
		(mid 192.07794 -245.17918)
		(end 192.035684 -245.281196)
		(width 0.127)
		(layer "B.Cu")
		(net "PHY_SCC_B_TO_DRV_B_5_DN")
	)
	(arc
		(start 279.790652 -238.3028)
		(mid 279.684565 -238.046683)
		(end 279.428448 -237.940596)
		(width 0.127)
		(layer "B.Cu")
		(net "PHY_SCC_B_TO_DRV_B_5_DN")
	)
	(segment
		(start 158.942786 -244.660674)
		(end 159.338772 -244.660674)
		(width 0.127)
		(layer "F.Cu")
		(net "PHY_SCC_B_TO_DRV_B_4_DP")
	)
	(segment
		(start 160.485582 -244.68582)
		(end 160.485582 -244.419374)
		(width 0.127)
		(layer "F.Cu")
		(net "PHY_SCC_B_TO_DRV_B_4_DP")
	)
	(segment
		(start 159.338772 -244.660674)
		(end 159.522922 -244.844824)
		(width 0.127)
		(layer "F.Cu")
		(net "PHY_SCC_B_TO_DRV_B_4_DP")
	)
	(segment
		(start 159.522922 -244.844824)
		(end 160.326578 -244.844824)
		(width 0.127)
		(layer "F.Cu")
		(net "PHY_SCC_B_TO_DRV_B_4_DP")
	)
	(arc
		(start 160.326578 -244.844824)
		(mid 160.439011 -244.798253)
		(end 160.485582 -244.68582)
		(width 0.127)
		(layer "F.Cu")
		(net "PHY_SCC_B_TO_DRV_B_4_DP")
	)
	(segment
		(start 279.636728 -236.89437)
		(end 279.296622 -236.89437)
		(width 0.127)
		(layer "B.Cu")
		(net "PHY_SCC_B_TO_DRV_B_4_DP")
	)
	(segment
		(start 267.933678 -235.848398)
		(end 258.706366 -237.809532)
		(width 0.127)
		(layer "B.Cu")
		(net "PHY_SCC_B_TO_DRV_B_4_DP")
	)
	(segment
		(start 279.082754 -236.680502)
		(end 279.082754 -236.502702)
		(width 0.127)
		(layer "B.Cu")
		(net "PHY_SCC_B_TO_DRV_B_4_DP")
	)
	(segment
		(start 278.42845 -235.848398)
		(end 267.933678 -235.848398)
		(width 0.127)
		(layer "B.Cu")
		(net "PHY_SCC_B_TO_DRV_B_4_DP")
	)
	(segment
		(start 160.485582 -244.710204)
		(end 160.485582 -244.419374)
		(width 0.127)
		(layer "B.Cu")
		(net "PHY_SCC_B_TO_DRV_B_4_DP")
	)
	(segment
		(start 161.93262 -244.844824)
		(end 160.620202 -244.844824)
		(width 0.127)
		(layer "B.Cu")
		(net "PHY_SCC_B_TO_DRV_B_4_DP")
	)
	(segment
		(start 182.707534 -242.001802)
		(end 161.93262 -244.844824)
		(width 0.127)
		(layer "B.Cu")
		(net "PHY_SCC_B_TO_DRV_B_4_DP")
	)
	(segment
		(start 230.570786 -231.829102)
		(end 182.707534 -242.001802)
		(width 0.127)
		(layer "B.Cu")
		(net "PHY_SCC_B_TO_DRV_B_4_DP")
	)
	(segment
		(start 258.706366 -237.809532)
		(end 230.570786 -231.829102)
		(width 0.127)
		(layer "B.Cu")
		(net "PHY_SCC_B_TO_DRV_B_4_DP")
	)
	(arc
		(start 279.082754 -236.502702)
		(mid 278.891113 -236.040039)
		(end 278.42845 -235.848398)
		(width 0.127)
		(layer "B.Cu")
		(net "PHY_SCC_B_TO_DRV_B_4_DP")
	)
	(arc
		(start 160.620202 -244.844824)
		(mid 160.525011 -244.805395)
		(end 160.485582 -244.710204)
		(width 0.127)
		(layer "B.Cu")
		(net "PHY_SCC_B_TO_DRV_B_4_DP")
	)
	(arc
		(start 279.296622 -236.89437)
		(mid 279.145394 -236.83173)
		(end 279.082754 -236.680502)
		(width 0.127)
		(layer "B.Cu")
		(net "PHY_SCC_B_TO_DRV_B_4_DP")
	)
	(segment
		(start 159.323024 -245.219474)
		(end 159.405574 -245.136924)
		(width 0.127)
		(layer "F.Cu")
		(net "PHY_SCC_B_TO_DRV_B_4_DN")
	)
	(segment
		(start 158.942786 -245.219474)
		(end 159.323024 -245.219474)
		(width 0.127)
		(layer "F.Cu")
		(net "PHY_SCC_B_TO_DRV_B_4_DN")
	)
	(segment
		(start 159.405574 -245.136924)
		(end 160.326578 -245.136924)
		(width 0.127)
		(layer "F.Cu")
		(net "PHY_SCC_B_TO_DRV_B_4_DN")
	)
	(segment
		(start 160.485582 -245.295928)
		(end 160.485582 -245.562374)
		(width 0.127)
		(layer "F.Cu")
		(net "PHY_SCC_B_TO_DRV_B_4_DN")
	)
	(arc
		(start 160.326578 -245.136924)
		(mid 160.439011 -245.183495)
		(end 160.485582 -245.295928)
		(width 0.127)
		(layer "F.Cu")
		(net "PHY_SCC_B_TO_DRV_B_4_DN")
	)
	(segment
		(start 218.942666 -234.599226)
		(end 218.570048 -234.678474)
		(width 0.127)
		(layer "B.Cu")
		(net "PHY_SCC_B_TO_DRV_B_4_DN")
	)
	(segment
		(start 182.757826 -242.289838)
		(end 161.952686 -245.136924)
		(width 0.127)
		(layer "B.Cu")
		(net "PHY_SCC_B_TO_DRV_B_4_DN")
	)
	(segment
		(start 278.23668 -236.89437)
		(end 278.576786 -236.89437)
		(width 0.127)
		(layer "B.Cu")
		(net "PHY_SCC_B_TO_DRV_B_4_DN")
	)
	(segment
		(start 161.952686 -245.136924)
		(end 160.629854 -245.136924)
		(width 0.127)
		(layer "B.Cu")
		(net "PHY_SCC_B_TO_DRV_B_4_DN")
	)
	(segment
		(start 230.570786 -232.127806)
		(end 219.61348 -234.456732)
		(width 0.127)
		(layer "B.Cu")
		(net "PHY_SCC_B_TO_DRV_B_4_DN")
	)
	(segment
		(start 160.485582 -245.281196)
		(end 160.485582 -245.562374)
		(width 0.127)
		(layer "B.Cu")
		(net "PHY_SCC_B_TO_DRV_B_4_DN")
	)
	(segment
		(start 215.81237 -235.264452)
		(end 182.757826 -242.289838)
		(width 0.127)
		(layer "B.Cu")
		(net "PHY_SCC_B_TO_DRV_B_4_DN")
	)
	(segment
		(start 215.992964 -235.382054)
		(end 215.81237 -235.264452)
		(width 0.127)
		(layer "B.Cu")
		(net "PHY_SCC_B_TO_DRV_B_4_DN")
	)
	(segment
		(start 219.123514 -234.716574)
		(end 218.942666 -234.599226)
		(width 0.127)
		(layer "B.Cu")
		(net "PHY_SCC_B_TO_DRV_B_4_DN")
	)
	(segment
		(start 217.526616 -234.900216)
		(end 217.409268 -235.081064)
		(width 0.127)
		(layer "B.Cu")
		(net "PHY_SCC_B_TO_DRV_B_4_DN")
	)
	(segment
		(start 278.42845 -236.140498)
		(end 267.964412 -236.140498)
		(width 0.127)
		(layer "B.Cu")
		(net "PHY_SCC_B_TO_DRV_B_4_DN")
	)
	(segment
		(start 217.036396 -235.160058)
		(end 216.855802 -235.04271)
		(width 0.127)
		(layer "B.Cu")
		(net "PHY_SCC_B_TO_DRV_B_4_DN")
	)
	(segment
		(start 219.496132 -234.637326)
		(end 219.123514 -234.716574)
		(width 0.127)
		(layer "B.Cu")
		(net "PHY_SCC_B_TO_DRV_B_4_DN")
	)
	(segment
		(start 216.855802 -235.04271)
		(end 216.483184 -235.121958)
		(width 0.127)
		(layer "B.Cu")
		(net "PHY_SCC_B_TO_DRV_B_4_DN")
	)
	(segment
		(start 216.365582 -235.302806)
		(end 215.992964 -235.382054)
		(width 0.127)
		(layer "B.Cu")
		(net "PHY_SCC_B_TO_DRV_B_4_DN")
	)
	(segment
		(start 218.080082 -234.938316)
		(end 217.899234 -234.820968)
		(width 0.127)
		(layer "B.Cu")
		(net "PHY_SCC_B_TO_DRV_B_4_DN")
	)
	(segment
		(start 258.706366 -238.108236)
		(end 230.570786 -232.127806)
		(width 0.127)
		(layer "B.Cu")
		(net "PHY_SCC_B_TO_DRV_B_4_DN")
	)
	(segment
		(start 278.790654 -236.680502)
		(end 278.790654 -236.502702)
		(width 0.127)
		(layer "B.Cu")
		(net "PHY_SCC_B_TO_DRV_B_4_DN")
	)
	(segment
		(start 218.4527 -234.859068)
		(end 218.080082 -234.938316)
		(width 0.127)
		(layer "B.Cu")
		(net "PHY_SCC_B_TO_DRV_B_4_DN")
	)
	(segment
		(start 218.570048 -234.678474)
		(end 218.4527 -234.859068)
		(width 0.127)
		(layer "B.Cu")
		(net "PHY_SCC_B_TO_DRV_B_4_DN")
	)
	(segment
		(start 217.409268 -235.081064)
		(end 217.036396 -235.160058)
		(width 0.127)
		(layer "B.Cu")
		(net "PHY_SCC_B_TO_DRV_B_4_DN")
	)
	(segment
		(start 267.964412 -236.140498)
		(end 258.706366 -238.108236)
		(width 0.127)
		(layer "B.Cu")
		(net "PHY_SCC_B_TO_DRV_B_4_DN")
	)
	(segment
		(start 217.899234 -234.820968)
		(end 217.526616 -234.900216)
		(width 0.127)
		(layer "B.Cu")
		(net "PHY_SCC_B_TO_DRV_B_4_DN")
	)
	(segment
		(start 216.483184 -235.121958)
		(end 216.365582 -235.302806)
		(width 0.127)
		(layer "B.Cu")
		(net "PHY_SCC_B_TO_DRV_B_4_DN")
	)
	(segment
		(start 219.61348 -234.456732)
		(end 219.496132 -234.637326)
		(width 0.127)
		(layer "B.Cu")
		(net "PHY_SCC_B_TO_DRV_B_4_DN")
	)
	(arc
		(start 278.790654 -236.502702)
		(mid 278.684567 -236.246585)
		(end 278.42845 -236.140498)
		(width 0.127)
		(layer "B.Cu")
		(net "PHY_SCC_B_TO_DRV_B_4_DN")
	)
	(arc
		(start 278.576786 -236.89437)
		(mid 278.728014 -236.83173)
		(end 278.790654 -236.680502)
		(width 0.127)
		(layer "B.Cu")
		(net "PHY_SCC_B_TO_DRV_B_4_DN")
	)
	(arc
		(start 160.629854 -245.136924)
		(mid 160.527838 -245.17918)
		(end 160.485582 -245.281196)
		(width 0.127)
		(layer "B.Cu")
		(net "PHY_SCC_B_TO_DRV_B_4_DN")
	)
	(segment
		(start 478.693988 -14.740636)
		(end 477.887538 -14.740636)
		(width 0.127)
		(layer "F.Cu")
		(net "PHY_SCC_B_TO_DRV_B_35_DP")
	)
	(segment
		(start 479.105214 -14.660626)
		(end 478.773998 -14.660626)
		(width 0.127)
		(layer "F.Cu")
		(net "PHY_SCC_B_TO_DRV_B_35_DP")
	)
	(segment
		(start 477.887538 -14.740636)
		(end 477.682052 -14.53515)
		(width 0.127)
		(layer "F.Cu")
		(net "PHY_SCC_B_TO_DRV_B_35_DP")
	)
	(segment
		(start 478.773998 -14.660626)
		(end 478.693988 -14.740636)
		(width 0.127)
		(layer "F.Cu")
		(net "PHY_SCC_B_TO_DRV_B_35_DP")
	)
	(segment
		(start 477.847152 -13.6271)
		(end 478.107502 -13.6271)
		(width 0.127)
		(layer "F.Cu")
		(net "PHY_SCC_B_TO_DRV_B_35_DP")
	)
	(segment
		(start 477.682052 -14.53515)
		(end 477.682052 -13.7922)
		(width 0.127)
		(layer "F.Cu")
		(net "PHY_SCC_B_TO_DRV_B_35_DP")
	)
	(arc
		(start 477.682052 -13.7922)
		(mid 477.730409 -13.675457)
		(end 477.847152 -13.6271)
		(width 0.127)
		(layer "F.Cu")
		(net "PHY_SCC_B_TO_DRV_B_35_DP")
	)
	(segment
		(start 280.082752 -184.5056)
		(end 280.082752 -184.2262)
		(width 0.127)
		(layer "B.Cu")
		(net "PHY_SCC_B_TO_DRV_B_35_DP")
	)
	(segment
		(start 477.682052 -15.7226)
		(end 477.682052 -13.782548)
		(width 0.127)
		(layer "B.Cu")
		(net "PHY_SCC_B_TO_DRV_B_35_DP")
	)
	(segment
		(start 294.740838 -182.617364)
		(end 302.07077 -177.85715)
		(width 0.127)
		(layer "B.Cu")
		(net "PHY_SCC_B_TO_DRV_B_35_DP")
	)
	(segment
		(start 395.7955 -51.5366)
		(end 396.115032 -51.329082)
		(width 0.127)
		(layer "B.Cu")
		(net "PHY_SCC_B_TO_DRV_B_35_DP")
	)
	(segment
		(start 423.87393 -33.302194)
		(end 467.423754 -24.044656)
		(width 0.127)
		(layer "B.Cu")
		(net "PHY_SCC_B_TO_DRV_B_35_DP")
	)
	(segment
		(start 477.8375 -13.6271)
		(end 478.107502 -13.6271)
		(width 0.127)
		(layer "B.Cu")
		(net "PHY_SCC_B_TO_DRV_B_35_DP")
	)
	(segment
		(start 346.882212 -83.301332)
		(end 393.431014 -53.07203)
		(width 0.127)
		(layer "B.Cu")
		(net "PHY_SCC_B_TO_DRV_B_35_DP")
	)
	(segment
		(start 394.855954 -52.328318)
		(end 394.900912 -52.117498)
		(width 0.127)
		(layer "B.Cu")
		(net "PHY_SCC_B_TO_DRV_B_35_DP")
	)
	(segment
		(start 302.07077 -177.85715)
		(end 309.69712 -166.11346)
		(width 0.127)
		(layer "B.Cu")
		(net "PHY_SCC_B_TO_DRV_B_35_DP")
	)
	(segment
		(start 393.961366 -52.90947)
		(end 394.00607 -52.69865)
		(width 0.127)
		(layer "B.Cu")
		(net "PHY_SCC_B_TO_DRV_B_35_DP")
	)
	(segment
		(start 396.690342 -50.955448)
		(end 423.87393 -33.302194)
		(width 0.127)
		(layer "B.Cu")
		(net "PHY_SCC_B_TO_DRV_B_35_DP")
	)
	(segment
		(start 467.423754 -24.044656)
		(end 476.703644 -17.06245)
		(width 0.127)
		(layer "B.Cu")
		(net "PHY_SCC_B_TO_DRV_B_35_DP")
	)
	(segment
		(start 396.115032 -51.329082)
		(end 396.325852 -51.373786)
		(width 0.127)
		(layer "B.Cu")
		(net "PHY_SCC_B_TO_DRV_B_35_DP")
	)
	(segment
		(start 396.325852 -51.373786)
		(end 396.645384 -51.166268)
		(width 0.127)
		(layer "B.Cu")
		(net "PHY_SCC_B_TO_DRV_B_35_DP")
	)
	(segment
		(start 317.773812 -128.124204)
		(end 346.882212 -83.301332)
		(width 0.127)
		(layer "B.Cu")
		(net "PHY_SCC_B_TO_DRV_B_35_DP")
	)
	(segment
		(start 393.431014 -53.07203)
		(end 393.641834 -53.116988)
		(width 0.127)
		(layer "B.Cu")
		(net "PHY_SCC_B_TO_DRV_B_35_DP")
	)
	(segment
		(start 280.368248 -183.940704)
		(end 288.515552 -183.940704)
		(width 0.127)
		(layer "B.Cu")
		(net "PHY_SCC_B_TO_DRV_B_35_DP")
	)
	(segment
		(start 394.325602 -52.491132)
		(end 394.536422 -52.535836)
		(width 0.127)
		(layer "B.Cu")
		(net "PHY_SCC_B_TO_DRV_B_35_DP")
	)
	(segment
		(start 395.750796 -51.74742)
		(end 395.7955 -51.5366)
		(width 0.127)
		(layer "B.Cu")
		(net "PHY_SCC_B_TO_DRV_B_35_DP")
	)
	(segment
		(start 394.900912 -52.117498)
		(end 395.220444 -51.90998)
		(width 0.127)
		(layer "B.Cu")
		(net "PHY_SCC_B_TO_DRV_B_35_DP")
	)
	(segment
		(start 394.00607 -52.69865)
		(end 394.325602 -52.491132)
		(width 0.127)
		(layer "B.Cu")
		(net "PHY_SCC_B_TO_DRV_B_35_DP")
	)
	(segment
		(start 476.703644 -17.06245)
		(end 477.682052 -15.7226)
		(width 0.127)
		(layer "B.Cu")
		(net "PHY_SCC_B_TO_DRV_B_35_DP")
	)
	(segment
		(start 395.431264 -51.954938)
		(end 395.750796 -51.74742)
		(width 0.127)
		(layer "B.Cu")
		(net "PHY_SCC_B_TO_DRV_B_35_DP")
	)
	(segment
		(start 395.220444 -51.90998)
		(end 395.431264 -51.954938)
		(width 0.127)
		(layer "B.Cu")
		(net "PHY_SCC_B_TO_DRV_B_35_DP")
	)
	(segment
		(start 394.536422 -52.535836)
		(end 394.855954 -52.328318)
		(width 0.127)
		(layer "B.Cu")
		(net "PHY_SCC_B_TO_DRV_B_35_DP")
	)
	(segment
		(start 393.641834 -53.116988)
		(end 393.961366 -52.90947)
		(width 0.127)
		(layer "B.Cu")
		(net "PHY_SCC_B_TO_DRV_B_35_DP")
	)
	(segment
		(start 280.636726 -184.694576)
		(end 280.271728 -184.694576)
		(width 0.127)
		(layer "B.Cu")
		(net "PHY_SCC_B_TO_DRV_B_35_DP")
	)
	(segment
		(start 288.515552 -183.940704)
		(end 294.740838 -182.617364)
		(width 0.127)
		(layer "B.Cu")
		(net "PHY_SCC_B_TO_DRV_B_35_DP")
	)
	(segment
		(start 396.645384 -51.166268)
		(end 396.690342 -50.955448)
		(width 0.127)
		(layer "B.Cu")
		(net "PHY_SCC_B_TO_DRV_B_35_DP")
	)
	(segment
		(start 309.69712 -166.11346)
		(end 317.773812 -128.124204)
		(width 0.127)
		(layer "B.Cu")
		(net "PHY_SCC_B_TO_DRV_B_35_DP")
	)
	(arc
		(start 477.682052 -13.782548)
		(mid 477.727582 -13.67263)
		(end 477.8375 -13.6271)
		(width 0.127)
		(layer "B.Cu")
		(net "PHY_SCC_B_TO_DRV_B_35_DP")
	)
	(arc
		(start 280.271728 -184.694576)
		(mid 280.138102 -184.639226)
		(end 280.082752 -184.5056)
		(width 0.127)
		(layer "B.Cu")
		(net "PHY_SCC_B_TO_DRV_B_35_DP")
	)
	(arc
		(start 280.082752 -184.2262)
		(mid 280.166372 -184.024324)
		(end 280.368248 -183.940704)
		(width 0.127)
		(layer "B.Cu")
		(net "PHY_SCC_B_TO_DRV_B_35_DP")
	)
	(segment
		(start 477.76638 -15.032736)
		(end 477.389952 -14.656308)
		(width 0.127)
		(layer "F.Cu")
		(net "PHY_SCC_B_TO_DRV_B_35_DN")
	)
	(segment
		(start 478.773998 -15.219426)
		(end 478.587308 -15.032736)
		(width 0.127)
		(layer "F.Cu")
		(net "PHY_SCC_B_TO_DRV_B_35_DN")
	)
	(segment
		(start 477.224852 -13.6271)
		(end 476.964502 -13.6271)
		(width 0.127)
		(layer "F.Cu")
		(net "PHY_SCC_B_TO_DRV_B_35_DN")
	)
	(segment
		(start 477.389952 -14.656308)
		(end 477.389952 -13.7922)
		(width 0.127)
		(layer "F.Cu")
		(net "PHY_SCC_B_TO_DRV_B_35_DN")
	)
	(segment
		(start 478.587308 -15.032736)
		(end 477.76638 -15.032736)
		(width 0.127)
		(layer "F.Cu")
		(net "PHY_SCC_B_TO_DRV_B_35_DN")
	)
	(segment
		(start 479.105214 -15.219426)
		(end 478.773998 -15.219426)
		(width 0.127)
		(layer "F.Cu")
		(net "PHY_SCC_B_TO_DRV_B_35_DN")
	)
	(arc
		(start 477.389952 -13.7922)
		(mid 477.341595 -13.675457)
		(end 477.224852 -13.6271)
		(width 0.127)
		(layer "F.Cu")
		(net "PHY_SCC_B_TO_DRV_B_35_DN")
	)
	(segment
		(start 476.493078 -16.854932)
		(end 477.389952 -15.627096)
		(width 0.127)
		(layer "B.Cu")
		(net "PHY_SCC_B_TO_DRV_B_35_DN")
	)
	(segment
		(start 279.790652 -184.5056)
		(end 279.790652 -184.2262)
		(width 0.127)
		(layer "B.Cu")
		(net "PHY_SCC_B_TO_DRV_B_35_DN")
	)
	(segment
		(start 280.368248 -183.648604)
		(end 288.484818 -183.648604)
		(width 0.127)
		(layer "B.Cu")
		(net "PHY_SCC_B_TO_DRV_B_35_DN")
	)
	(segment
		(start 279.236678 -184.694576)
		(end 279.601676 -184.694576)
		(width 0.127)
		(layer "B.Cu")
		(net "PHY_SCC_B_TO_DRV_B_35_DN")
	)
	(segment
		(start 477.2279 -13.6271)
		(end 476.964502 -13.6271)
		(width 0.127)
		(layer "B.Cu")
		(net "PHY_SCC_B_TO_DRV_B_35_DN")
	)
	(segment
		(start 294.627046 -182.34279)
		(end 301.859442 -177.645822)
		(width 0.127)
		(layer "B.Cu")
		(net "PHY_SCC_B_TO_DRV_B_35_DN")
	)
	(segment
		(start 301.859442 -177.645822)
		(end 309.422546 -165.999668)
		(width 0.127)
		(layer "B.Cu")
		(net "PHY_SCC_B_TO_DRV_B_35_DN")
	)
	(segment
		(start 288.484818 -183.648604)
		(end 294.627046 -182.34279)
		(width 0.127)
		(layer "B.Cu")
		(net "PHY_SCC_B_TO_DRV_B_35_DN")
	)
	(segment
		(start 317.499238 -128.010412)
		(end 346.670884 -83.090004)
		(width 0.127)
		(layer "B.Cu")
		(net "PHY_SCC_B_TO_DRV_B_35_DN")
	)
	(segment
		(start 346.670884 -83.090004)
		(end 423.760138 -33.02762)
		(width 0.127)
		(layer "B.Cu")
		(net "PHY_SCC_B_TO_DRV_B_35_DN")
	)
	(segment
		(start 467.299802 -23.772368)
		(end 476.493078 -16.854932)
		(width 0.127)
		(layer "B.Cu")
		(net "PHY_SCC_B_TO_DRV_B_35_DN")
	)
	(segment
		(start 309.422546 -165.999668)
		(end 317.499238 -128.010412)
		(width 0.127)
		(layer "B.Cu")
		(net "PHY_SCC_B_TO_DRV_B_35_DN")
	)
	(segment
		(start 477.389952 -15.627096)
		(end 477.389952 -13.789152)
		(width 0.127)
		(layer "B.Cu")
		(net "PHY_SCC_B_TO_DRV_B_35_DN")
	)
	(segment
		(start 423.760138 -33.02762)
		(end 467.299802 -23.772368)
		(width 0.127)
		(layer "B.Cu")
		(net "PHY_SCC_B_TO_DRV_B_35_DN")
	)
	(arc
		(start 477.389952 -13.789152)
		(mid 477.342488 -13.674564)
		(end 477.2279 -13.6271)
		(width 0.127)
		(layer "B.Cu")
		(net "PHY_SCC_B_TO_DRV_B_35_DN")
	)
	(arc
		(start 279.601676 -184.694576)
		(mid 279.735302 -184.639226)
		(end 279.790652 -184.5056)
		(width 0.127)
		(layer "B.Cu")
		(net "PHY_SCC_B_TO_DRV_B_35_DN")
	)
	(arc
		(start 279.790652 -184.2262)
		(mid 279.959826 -183.817778)
		(end 280.368248 -183.648604)
		(width 0.127)
		(layer "B.Cu")
		(net "PHY_SCC_B_TO_DRV_B_35_DN")
	)
	(segment
		(start 446.13195 -14.53515)
		(end 446.13195 -13.78585)
		(width 0.127)
		(layer "F.Cu")
		(net "PHY_SCC_B_TO_DRV_B_34_DP")
	)
	(segment
		(start 447.555112 -14.660626)
		(end 447.223896 -14.660626)
		(width 0.127)
		(layer "F.Cu")
		(net "PHY_SCC_B_TO_DRV_B_34_DP")
	)
	(segment
		(start 446.2907 -13.6271)
		(end 446.5574 -13.6271)
		(width 0.127)
		(layer "F.Cu")
		(net "PHY_SCC_B_TO_DRV_B_34_DP")
	)
	(segment
		(start 447.223896 -14.660626)
		(end 447.166746 -14.717776)
		(width 0.127)
		(layer "F.Cu")
		(net "PHY_SCC_B_TO_DRV_B_34_DP")
	)
	(segment
		(start 446.314576 -14.717776)
		(end 446.13195 -14.53515)
		(width 0.127)
		(layer "F.Cu")
		(net "PHY_SCC_B_TO_DRV_B_34_DP")
	)
	(segment
		(start 447.166746 -14.717776)
		(end 446.314576 -14.717776)
		(width 0.127)
		(layer "F.Cu")
		(net "PHY_SCC_B_TO_DRV_B_34_DP")
	)
	(arc
		(start 446.13195 -13.78585)
		(mid 446.178447 -13.673597)
		(end 446.2907 -13.6271)
		(width 0.127)
		(layer "F.Cu")
		(net "PHY_SCC_B_TO_DRV_B_34_DP")
	)
	(segment
		(start 364.056422 -69.45757)
		(end 364.281212 -69.505322)
		(width 0.127)
		(layer "B.Cu")
		(net "PHY_SCC_B_TO_DRV_B_34_DP")
	)
	(segment
		(start 300.42104 -176.163478)
		(end 307.747924 -164.881052)
		(width 0.127)
		(layer "B.Cu")
		(net "PHY_SCC_B_TO_DRV_B_34_DP")
	)
	(segment
		(start 365.193072 -68.913248)
		(end 365.512604 -68.705984)
		(width 0.127)
		(layer "B.Cu")
		(net "PHY_SCC_B_TO_DRV_B_34_DP")
	)
	(segment
		(start 364.968282 -68.865496)
		(end 365.193072 -68.913248)
		(width 0.127)
		(layer "B.Cu")
		(net "PHY_SCC_B_TO_DRV_B_34_DP")
	)
	(segment
		(start 446.13195 -14.737334)
		(end 446.13195 -13.78585)
		(width 0.127)
		(layer "B.Cu")
		(net "PHY_SCC_B_TO_DRV_B_34_DP")
	)
	(segment
		(start 363.369606 -70.097396)
		(end 363.689138 -69.890132)
		(width 0.127)
		(layer "B.Cu")
		(net "PHY_SCC_B_TO_DRV_B_34_DP")
	)
	(segment
		(start 363.689138 -69.890132)
		(end 363.73689 -69.665088)
		(width 0.127)
		(layer "B.Cu")
		(net "PHY_SCC_B_TO_DRV_B_34_DP")
	)
	(segment
		(start 345.059254 -81.794096)
		(end 363.144816 -70.049644)
		(width 0.127)
		(layer "B.Cu")
		(net "PHY_SCC_B_TO_DRV_B_34_DP")
	)
	(segment
		(start 446.2907 -13.6271)
		(end 446.5574 -13.6271)
		(width 0.127)
		(layer "B.Cu")
		(net "PHY_SCC_B_TO_DRV_B_34_DP")
	)
	(segment
		(start 279.082754 -182.705502)
		(end 279.082754 -182.426102)
		(width 0.127)
		(layer "B.Cu")
		(net "PHY_SCC_B_TO_DRV_B_34_DP")
	)
	(segment
		(start 315.847984 -126.77521)
		(end 345.059254 -81.794096)
		(width 0.127)
		(layer "B.Cu")
		(net "PHY_SCC_B_TO_DRV_B_34_DP")
	)
	(segment
		(start 366.424464 -68.11391)
		(end 366.472216 -67.888866)
		(width 0.127)
		(layer "B.Cu")
		(net "PHY_SCC_B_TO_DRV_B_34_DP")
	)
	(segment
		(start 365.560356 -68.48094)
		(end 365.879888 -68.273422)
		(width 0.127)
		(layer "B.Cu")
		(net "PHY_SCC_B_TO_DRV_B_34_DP")
	)
	(segment
		(start 365.512604 -68.705984)
		(end 365.560356 -68.48094)
		(width 0.127)
		(layer "B.Cu")
		(net "PHY_SCC_B_TO_DRV_B_34_DP")
	)
	(segment
		(start 279.636728 -182.894478)
		(end 279.27173 -182.894478)
		(width 0.127)
		(layer "B.Cu")
		(net "PHY_SCC_B_TO_DRV_B_34_DP")
	)
	(segment
		(start 292.24986 -181.470808)
		(end 300.42104 -176.163478)
		(width 0.127)
		(layer "B.Cu")
		(net "PHY_SCC_B_TO_DRV_B_34_DP")
	)
	(segment
		(start 446.06845 -15.036292)
		(end 446.13195 -14.737334)
		(width 0.127)
		(layer "B.Cu")
		(net "PHY_SCC_B_TO_DRV_B_34_DP")
	)
	(segment
		(start 279.36825 -182.140606)
		(end 288.473896 -182.140606)
		(width 0.127)
		(layer "B.Cu")
		(net "PHY_SCC_B_TO_DRV_B_34_DP")
	)
	(segment
		(start 307.747924 -164.881052)
		(end 315.847984 -126.77521)
		(width 0.127)
		(layer "B.Cu")
		(net "PHY_SCC_B_TO_DRV_B_34_DP")
	)
	(segment
		(start 365.879888 -68.273422)
		(end 366.104932 -68.321174)
		(width 0.127)
		(layer "B.Cu")
		(net "PHY_SCC_B_TO_DRV_B_34_DP")
	)
	(segment
		(start 363.144816 -70.049644)
		(end 363.369606 -70.097396)
		(width 0.127)
		(layer "B.Cu")
		(net "PHY_SCC_B_TO_DRV_B_34_DP")
	)
	(segment
		(start 364.600744 -69.298058)
		(end 364.64875 -69.073014)
		(width 0.127)
		(layer "B.Cu")
		(net "PHY_SCC_B_TO_DRV_B_34_DP")
	)
	(segment
		(start 366.104932 -68.321174)
		(end 366.424464 -68.11391)
		(width 0.127)
		(layer "B.Cu")
		(net "PHY_SCC_B_TO_DRV_B_34_DP")
	)
	(segment
		(start 364.64875 -69.073014)
		(end 364.968282 -68.865496)
		(width 0.127)
		(layer "B.Cu")
		(net "PHY_SCC_B_TO_DRV_B_34_DP")
	)
	(segment
		(start 445.38646 -16.642842)
		(end 446.06845 -15.036292)
		(width 0.127)
		(layer "B.Cu")
		(net "PHY_SCC_B_TO_DRV_B_34_DP")
	)
	(segment
		(start 288.473896 -182.140606)
		(end 292.24986 -181.470808)
		(width 0.127)
		(layer "B.Cu")
		(net "PHY_SCC_B_TO_DRV_B_34_DP")
	)
	(segment
		(start 363.73689 -69.665088)
		(end 364.056422 -69.45757)
		(width 0.127)
		(layer "B.Cu")
		(net "PHY_SCC_B_TO_DRV_B_34_DP")
	)
	(segment
		(start 364.281212 -69.505322)
		(end 364.600744 -69.298058)
		(width 0.127)
		(layer "B.Cu")
		(net "PHY_SCC_B_TO_DRV_B_34_DP")
	)
	(segment
		(start 366.472216 -67.888866)
		(end 445.38646 -16.642842)
		(width 0.127)
		(layer "B.Cu")
		(net "PHY_SCC_B_TO_DRV_B_34_DP")
	)
	(arc
		(start 279.27173 -182.894478)
		(mid 279.138104 -182.839128)
		(end 279.082754 -182.705502)
		(width 0.127)
		(layer "B.Cu")
		(net "PHY_SCC_B_TO_DRV_B_34_DP")
	)
	(arc
		(start 279.082754 -182.426102)
		(mid 279.166374 -182.224226)
		(end 279.36825 -182.140606)
		(width 0.127)
		(layer "B.Cu")
		(net "PHY_SCC_B_TO_DRV_B_34_DP")
	)
	(arc
		(start 446.13195 -13.78585)
		(mid 446.178447 -13.673597)
		(end 446.2907 -13.6271)
		(width 0.127)
		(layer "B.Cu")
		(net "PHY_SCC_B_TO_DRV_B_34_DP")
	)
	(segment
		(start 447.223896 -15.219426)
		(end 447.014346 -15.009876)
		(width 0.127)
		(layer "F.Cu")
		(net "PHY_SCC_B_TO_DRV_B_34_DN")
	)
	(segment
		(start 446.193418 -15.009876)
		(end 445.83985 -14.656308)
		(width 0.127)
		(layer "F.Cu")
		(net "PHY_SCC_B_TO_DRV_B_34_DN")
	)
	(segment
		(start 447.014346 -15.009876)
		(end 446.193418 -15.009876)
		(width 0.127)
		(layer "F.Cu")
		(net "PHY_SCC_B_TO_DRV_B_34_DN")
	)
	(segment
		(start 447.555112 -15.219426)
		(end 447.223896 -15.219426)
		(width 0.127)
		(layer "F.Cu")
		(net "PHY_SCC_B_TO_DRV_B_34_DN")
	)
	(segment
		(start 445.83985 -14.656308)
		(end 445.83985 -13.78585)
		(width 0.127)
		(layer "F.Cu")
		(net "PHY_SCC_B_TO_DRV_B_34_DN")
	)
	(segment
		(start 445.6811 -13.6271)
		(end 445.4144 -13.6271)
		(width 0.127)
		(layer "F.Cu")
		(net "PHY_SCC_B_TO_DRV_B_34_DN")
	)
	(arc
		(start 445.83985 -13.78585)
		(mid 445.793353 -13.673597)
		(end 445.6811 -13.6271)
		(width 0.127)
		(layer "F.Cu")
		(net "PHY_SCC_B_TO_DRV_B_34_DN")
	)
	(segment
		(start 445.152272 -16.446246)
		(end 445.788542 -14.9479)
		(width 0.127)
		(layer "B.Cu")
		(net "PHY_SCC_B_TO_DRV_B_34_DN")
	)
	(segment
		(start 394.999718 -49.014888)
		(end 394.999972 -49.014634)
		(width 0.127)
		(layer "B.Cu")
		(net "PHY_SCC_B_TO_DRV_B_34_DN")
	)
	(segment
		(start 315.57341 -126.661418)
		(end 344.847926 -81.582768)
		(width 0.127)
		(layer "B.Cu")
		(net "PHY_SCC_B_TO_DRV_B_34_DN")
	)
	(segment
		(start 288.447988 -181.848506)
		(end 292.140386 -181.19344)
		(width 0.127)
		(layer "B.Cu")
		(net "PHY_SCC_B_TO_DRV_B_34_DN")
	)
	(segment
		(start 292.140386 -181.19344)
		(end 300.209712 -175.95215)
		(width 0.127)
		(layer "B.Cu")
		(net "PHY_SCC_B_TO_DRV_B_34_DN")
	)
	(segment
		(start 445.788542 -14.9479)
		(end 445.83985 -14.7066)
		(width 0.127)
		(layer "B.Cu")
		(net "PHY_SCC_B_TO_DRV_B_34_DN")
	)
	(segment
		(start 344.847926 -81.582768)
		(end 394.999464 -49.014888)
		(width 0.127)
		(layer "B.Cu")
		(net "PHY_SCC_B_TO_DRV_B_34_DN")
	)
	(segment
		(start 394.999464 -49.014888)
		(end 394.999718 -49.014888)
		(width 0.127)
		(layer "B.Cu")
		(net "PHY_SCC_B_TO_DRV_B_34_DN")
	)
	(segment
		(start 394.999972 -49.014634)
		(end 445.152272 -16.446246)
		(width 0.127)
		(layer "B.Cu")
		(net "PHY_SCC_B_TO_DRV_B_34_DN")
	)
	(segment
		(start 278.790654 -182.705502)
		(end 278.790654 -182.426102)
		(width 0.127)
		(layer "B.Cu")
		(net "PHY_SCC_B_TO_DRV_B_34_DN")
	)
	(segment
		(start 445.83985 -14.7066)
		(end 445.83985 -13.78585)
		(width 0.127)
		(layer "B.Cu")
		(net "PHY_SCC_B_TO_DRV_B_34_DN")
	)
	(segment
		(start 279.36825 -181.848506)
		(end 288.447988 -181.848506)
		(width 0.127)
		(layer "B.Cu")
		(net "PHY_SCC_B_TO_DRV_B_34_DN")
	)
	(segment
		(start 445.6811 -13.6271)
		(end 445.4144 -13.6271)
		(width 0.127)
		(layer "B.Cu")
		(net "PHY_SCC_B_TO_DRV_B_34_DN")
	)
	(segment
		(start 278.23668 -182.894478)
		(end 278.601678 -182.894478)
		(width 0.127)
		(layer "B.Cu")
		(net "PHY_SCC_B_TO_DRV_B_34_DN")
	)
	(segment
		(start 307.47335 -164.76726)
		(end 315.57341 -126.661418)
		(width 0.127)
		(layer "B.Cu")
		(net "PHY_SCC_B_TO_DRV_B_34_DN")
	)
	(segment
		(start 300.209712 -175.95215)
		(end 307.47335 -164.76726)
		(width 0.127)
		(layer "B.Cu")
		(net "PHY_SCC_B_TO_DRV_B_34_DN")
	)
	(arc
		(start 445.83985 -13.78585)
		(mid 445.793353 -13.673597)
		(end 445.6811 -13.6271)
		(width 0.127)
		(layer "B.Cu")
		(net "PHY_SCC_B_TO_DRV_B_34_DN")
	)
	(arc
		(start 278.601678 -182.894478)
		(mid 278.735304 -182.839128)
		(end 278.790654 -182.705502)
		(width 0.127)
		(layer "B.Cu")
		(net "PHY_SCC_B_TO_DRV_B_34_DN")
	)
	(arc
		(start 278.790654 -182.426102)
		(mid 278.959828 -182.01768)
		(end 279.36825 -181.848506)
		(width 0.127)
		(layer "B.Cu")
		(net "PHY_SCC_B_TO_DRV_B_34_DN")
	)
	(segment
		(start 414.790128 -14.743176)
		(end 414.582102 -14.53515)
		(width 0.127)
		(layer "F.Cu")
		(net "PHY_SCC_B_TO_DRV_B_33_DP")
	)
	(segment
		(start 414.737804 -13.6271)
		(end 415.007552 -13.6271)
		(width 0.127)
		(layer "F.Cu")
		(net "PHY_SCC_B_TO_DRV_B_33_DP")
	)
	(segment
		(start 415.674048 -14.660626)
		(end 415.591498 -14.743176)
		(width 0.127)
		(layer "F.Cu")
		(net "PHY_SCC_B_TO_DRV_B_33_DP")
	)
	(segment
		(start 415.591498 -14.743176)
		(end 414.790128 -14.743176)
		(width 0.127)
		(layer "F.Cu")
		(net "PHY_SCC_B_TO_DRV_B_33_DP")
	)
	(segment
		(start 414.582102 -14.53515)
		(end 414.582102 -13.782802)
		(width 0.127)
		(layer "F.Cu")
		(net "PHY_SCC_B_TO_DRV_B_33_DP")
	)
	(segment
		(start 416.005264 -14.660626)
		(end 415.674048 -14.660626)
		(width 0.127)
		(layer "F.Cu")
		(net "PHY_SCC_B_TO_DRV_B_33_DP")
	)
	(arc
		(start 414.582102 -13.782802)
		(mid 414.627706 -13.672704)
		(end 414.737804 -13.6271)
		(width 0.127)
		(layer "F.Cu")
		(net "PHY_SCC_B_TO_DRV_B_33_DP")
	)
	(segment
		(start 297.162474 -176.432718)
		(end 306.309268 -162.348164)
		(width 0.127)
		(layer "B.Cu")
		(net "PHY_SCC_B_TO_DRV_B_33_DP")
	)
	(segment
		(start 376.628152 -59.229498)
		(end 376.675904 -59.004454)
		(width 0.127)
		(layer "B.Cu")
		(net "PHY_SCC_B_TO_DRV_B_33_DP")
	)
	(segment
		(start 376.675904 -59.004454)
		(end 376.995436 -58.796936)
		(width 0.127)
		(layer "B.Cu")
		(net "PHY_SCC_B_TO_DRV_B_33_DP")
	)
	(segment
		(start 288.625534 -180.340508)
		(end 292.370002 -179.544726)
		(width 0.127)
		(layer "B.Cu")
		(net "PHY_SCC_B_TO_DRV_B_33_DP")
	)
	(segment
		(start 280.636726 -181.09438)
		(end 280.271728 -181.09438)
		(width 0.127)
		(layer "B.Cu")
		(net "PHY_SCC_B_TO_DRV_B_33_DP")
	)
	(segment
		(start 394.56614 -47.386494)
		(end 406.4889 -37.700204)
		(width 0.127)
		(layer "B.Cu")
		(net "PHY_SCC_B_TO_DRV_B_33_DP")
	)
	(segment
		(start 280.368248 -180.340508)
		(end 288.625534 -180.340508)
		(width 0.127)
		(layer "B.Cu")
		(net "PHY_SCC_B_TO_DRV_B_33_DP")
	)
	(segment
		(start 409.183078 -33.245044)
		(end 414.582102 -14.80439)
		(width 0.127)
		(layer "B.Cu")
		(net "PHY_SCC_B_TO_DRV_B_33_DP")
	)
	(segment
		(start 414.737804 -13.6271)
		(end 415.007552 -13.6271)
		(width 0.127)
		(layer "B.Cu")
		(net "PHY_SCC_B_TO_DRV_B_33_DP")
	)
	(segment
		(start 376.995436 -58.796936)
		(end 377.220226 -58.844942)
		(width 0.127)
		(layer "B.Cu")
		(net "PHY_SCC_B_TO_DRV_B_33_DP")
	)
	(segment
		(start 374.4849 -60.621164)
		(end 374.804686 -60.413646)
		(width 0.127)
		(layer "B.Cu")
		(net "PHY_SCC_B_TO_DRV_B_33_DP")
	)
	(segment
		(start 375.17197 -59.981084)
		(end 375.39676 -60.02909)
		(width 0.127)
		(layer "B.Cu")
		(net "PHY_SCC_B_TO_DRV_B_33_DP")
	)
	(segment
		(start 292.370002 -179.544726)
		(end 297.162474 -176.432718)
		(width 0.127)
		(layer "B.Cu")
		(net "PHY_SCC_B_TO_DRV_B_33_DP")
	)
	(segment
		(start 406.4889 -37.700204)
		(end 409.183078 -33.245044)
		(width 0.127)
		(layer "B.Cu")
		(net "PHY_SCC_B_TO_DRV_B_33_DP")
	)
	(segment
		(start 377.58751 -58.41238)
		(end 394.56614 -47.386494)
		(width 0.127)
		(layer "B.Cu")
		(net "PHY_SCC_B_TO_DRV_B_33_DP")
	)
	(segment
		(start 306.309268 -162.348164)
		(end 314.082684 -125.775974)
		(width 0.127)
		(layer "B.Cu")
		(net "PHY_SCC_B_TO_DRV_B_33_DP")
	)
	(segment
		(start 376.30862 -59.437016)
		(end 376.628152 -59.229498)
		(width 0.127)
		(layer "B.Cu")
		(net "PHY_SCC_B_TO_DRV_B_33_DP")
	)
	(segment
		(start 375.716292 -59.821572)
		(end 375.764044 -59.596528)
		(width 0.127)
		(layer "B.Cu")
		(net "PHY_SCC_B_TO_DRV_B_33_DP")
	)
	(segment
		(start 280.082752 -180.905404)
		(end 280.082752 -180.626004)
		(width 0.127)
		(layer "B.Cu")
		(net "PHY_SCC_B_TO_DRV_B_33_DP")
	)
	(segment
		(start 343.420446 -80.600042)
		(end 374.26011 -60.573158)
		(width 0.127)
		(layer "B.Cu")
		(net "PHY_SCC_B_TO_DRV_B_33_DP")
	)
	(segment
		(start 374.852438 -60.188602)
		(end 375.17197 -59.981084)
		(width 0.127)
		(layer "B.Cu")
		(net "PHY_SCC_B_TO_DRV_B_33_DP")
	)
	(segment
		(start 374.804686 -60.413646)
		(end 374.852438 -60.188602)
		(width 0.127)
		(layer "B.Cu")
		(net "PHY_SCC_B_TO_DRV_B_33_DP")
	)
	(segment
		(start 314.082684 -125.775974)
		(end 343.420446 -80.600042)
		(width 0.127)
		(layer "B.Cu")
		(net "PHY_SCC_B_TO_DRV_B_33_DP")
	)
	(segment
		(start 375.764044 -59.596528)
		(end 376.083576 -59.38901)
		(width 0.127)
		(layer "B.Cu")
		(net "PHY_SCC_B_TO_DRV_B_33_DP")
	)
	(segment
		(start 374.26011 -60.573158)
		(end 374.4849 -60.621164)
		(width 0.127)
		(layer "B.Cu")
		(net "PHY_SCC_B_TO_DRV_B_33_DP")
	)
	(segment
		(start 375.39676 -60.02909)
		(end 375.716292 -59.821572)
		(width 0.127)
		(layer "B.Cu")
		(net "PHY_SCC_B_TO_DRV_B_33_DP")
	)
	(segment
		(start 376.083576 -59.38901)
		(end 376.30862 -59.437016)
		(width 0.127)
		(layer "B.Cu")
		(net "PHY_SCC_B_TO_DRV_B_33_DP")
	)
	(segment
		(start 377.220226 -58.844942)
		(end 377.539758 -58.637424)
		(width 0.127)
		(layer "B.Cu")
		(net "PHY_SCC_B_TO_DRV_B_33_DP")
	)
	(segment
		(start 414.582102 -14.80439)
		(end 414.582102 -13.782802)
		(width 0.127)
		(layer "B.Cu")
		(net "PHY_SCC_B_TO_DRV_B_33_DP")
	)
	(segment
		(start 377.539758 -58.637424)
		(end 377.58751 -58.41238)
		(width 0.127)
		(layer "B.Cu")
		(net "PHY_SCC_B_TO_DRV_B_33_DP")
	)
	(arc
		(start 280.082752 -180.626004)
		(mid 280.166372 -180.424128)
		(end 280.368248 -180.340508)
		(width 0.127)
		(layer "B.Cu")
		(net "PHY_SCC_B_TO_DRV_B_33_DP")
	)
	(arc
		(start 414.582102 -13.782802)
		(mid 414.627706 -13.672704)
		(end 414.737804 -13.6271)
		(width 0.127)
		(layer "B.Cu")
		(net "PHY_SCC_B_TO_DRV_B_33_DP")
	)
	(arc
		(start 280.271728 -181.09438)
		(mid 280.138102 -181.03903)
		(end 280.082752 -180.905404)
		(width 0.127)
		(layer "B.Cu")
		(net "PHY_SCC_B_TO_DRV_B_33_DP")
	)
	(segment
		(start 415.674048 -15.219426)
		(end 415.489898 -15.035276)
		(width 0.127)
		(layer "F.Cu")
		(net "PHY_SCC_B_TO_DRV_B_33_DN")
	)
	(segment
		(start 414.66897 -15.035276)
		(end 414.290002 -14.656308)
		(width 0.127)
		(layer "F.Cu")
		(net "PHY_SCC_B_TO_DRV_B_33_DN")
	)
	(segment
		(start 416.005264 -15.219426)
		(end 415.674048 -15.219426)
		(width 0.127)
		(layer "F.Cu")
		(net "PHY_SCC_B_TO_DRV_B_33_DN")
	)
	(segment
		(start 415.489898 -15.035276)
		(end 414.66897 -15.035276)
		(width 0.127)
		(layer "F.Cu")
		(net "PHY_SCC_B_TO_DRV_B_33_DN")
	)
	(segment
		(start 414.1343 -13.6271)
		(end 413.864552 -13.6271)
		(width 0.127)
		(layer "F.Cu")
		(net "PHY_SCC_B_TO_DRV_B_33_DN")
	)
	(segment
		(start 414.290002 -14.656308)
		(end 414.290002 -13.782802)
		(width 0.127)
		(layer "F.Cu")
		(net "PHY_SCC_B_TO_DRV_B_33_DN")
	)
	(arc
		(start 414.290002 -13.782802)
		(mid 414.244398 -13.672704)
		(end 414.1343 -13.6271)
		(width 0.127)
		(layer "F.Cu")
		(net "PHY_SCC_B_TO_DRV_B_33_DN")
	)
	(segment
		(start 280.368248 -180.048408)
		(end 288.5948 -180.048408)
		(width 0.127)
		(layer "B.Cu")
		(net "PHY_SCC_B_TO_DRV_B_33_DN")
	)
	(segment
		(start 279.790652 -180.905404)
		(end 279.790652 -180.626004)
		(width 0.127)
		(layer "B.Cu")
		(net "PHY_SCC_B_TO_DRV_B_33_DN")
	)
	(segment
		(start 313.80811 -125.662182)
		(end 343.209118 -80.388714)
		(width 0.127)
		(layer "B.Cu")
		(net "PHY_SCC_B_TO_DRV_B_33_DN")
	)
	(segment
		(start 414.1343 -13.6271)
		(end 413.864552 -13.6271)
		(width 0.127)
		(layer "B.Cu")
		(net "PHY_SCC_B_TO_DRV_B_33_DN")
	)
	(segment
		(start 406.265126 -37.505386)
		(end 408.91333 -33.126426)
		(width 0.127)
		(layer "B.Cu")
		(net "PHY_SCC_B_TO_DRV_B_33_DN")
	)
	(segment
		(start 292.25621 -179.270152)
		(end 296.951146 -176.22139)
		(width 0.127)
		(layer "B.Cu")
		(net "PHY_SCC_B_TO_DRV_B_33_DN")
	)
	(segment
		(start 279.236678 -181.09438)
		(end 279.601676 -181.09438)
		(width 0.127)
		(layer "B.Cu")
		(net "PHY_SCC_B_TO_DRV_B_33_DN")
	)
	(segment
		(start 288.5948 -180.048408)
		(end 292.25621 -179.270152)
		(width 0.127)
		(layer "B.Cu")
		(net "PHY_SCC_B_TO_DRV_B_33_DN")
	)
	(segment
		(start 394.393928 -47.15002)
		(end 406.265126 -37.505386)
		(width 0.127)
		(layer "B.Cu")
		(net "PHY_SCC_B_TO_DRV_B_33_DN")
	)
	(segment
		(start 414.290002 -14.76248)
		(end 414.290002 -13.782802)
		(width 0.127)
		(layer "B.Cu")
		(net "PHY_SCC_B_TO_DRV_B_33_DN")
	)
	(segment
		(start 306.034694 -162.234372)
		(end 313.80811 -125.662182)
		(width 0.127)
		(layer "B.Cu")
		(net "PHY_SCC_B_TO_DRV_B_33_DN")
	)
	(segment
		(start 408.91333 -33.126426)
		(end 414.290002 -14.76248)
		(width 0.127)
		(layer "B.Cu")
		(net "PHY_SCC_B_TO_DRV_B_33_DN")
	)
	(segment
		(start 296.951146 -176.22139)
		(end 306.034694 -162.234372)
		(width 0.127)
		(layer "B.Cu")
		(net "PHY_SCC_B_TO_DRV_B_33_DN")
	)
	(segment
		(start 343.209118 -80.388714)
		(end 394.393928 -47.15002)
		(width 0.127)
		(layer "B.Cu")
		(net "PHY_SCC_B_TO_DRV_B_33_DN")
	)
	(arc
		(start 414.290002 -13.782802)
		(mid 414.244398 -13.672704)
		(end 414.1343 -13.6271)
		(width 0.127)
		(layer "B.Cu")
		(net "PHY_SCC_B_TO_DRV_B_33_DN")
	)
	(arc
		(start 279.790652 -180.626004)
		(mid 279.959826 -180.217582)
		(end 280.368248 -180.048408)
		(width 0.127)
		(layer "B.Cu")
		(net "PHY_SCC_B_TO_DRV_B_33_DN")
	)
	(arc
		(start 279.601676 -181.09438)
		(mid 279.735302 -181.03903)
		(end 279.790652 -180.905404)
		(width 0.127)
		(layer "B.Cu")
		(net "PHY_SCC_B_TO_DRV_B_33_DN")
	)
	(segment
		(start 384.079496 -14.705076)
		(end 383.201926 -14.705076)
		(width 0.127)
		(layer "F.Cu")
		(net "PHY_SCC_B_TO_DRV_B_32_DP")
	)
	(segment
		(start 383.1844 -13.6271)
		(end 383.45745 -13.6271)
		(width 0.127)
		(layer "F.Cu")
		(net "PHY_SCC_B_TO_DRV_B_32_DP")
	)
	(segment
		(start 383.032 -14.53515)
		(end 383.032 -13.7795)
		(width 0.127)
		(layer "F.Cu")
		(net "PHY_SCC_B_TO_DRV_B_32_DP")
	)
	(segment
		(start 384.455162 -14.660626)
		(end 384.123946 -14.660626)
		(width 0.127)
		(layer "F.Cu")
		(net "PHY_SCC_B_TO_DRV_B_32_DP")
	)
	(segment
		(start 384.123946 -14.660626)
		(end 384.079496 -14.705076)
		(width 0.127)
		(layer "F.Cu")
		(net "PHY_SCC_B_TO_DRV_B_32_DP")
	)
	(segment
		(start 383.201926 -14.705076)
		(end 383.032 -14.53515)
		(width 0.127)
		(layer "F.Cu")
		(net "PHY_SCC_B_TO_DRV_B_32_DP")
	)
	(arc
		(start 383.032 -13.7795)
		(mid 383.076637 -13.671737)
		(end 383.1844 -13.6271)
		(width 0.127)
		(layer "F.Cu")
		(net "PHY_SCC_B_TO_DRV_B_32_DP")
	)
	(segment
		(start 379.645164 -20.79117)
		(end 379.597412 -20.56638)
		(width 0.127)
		(layer "B.Cu")
		(net "PHY_SCC_B_TO_DRV_B_32_DP")
	)
	(segment
		(start 378.413264 -22.389846)
		(end 378.620782 -22.070314)
		(width 0.127)
		(layer "B.Cu")
		(net "PHY_SCC_B_TO_DRV_B_32_DP")
	)
	(segment
		(start 379.437646 -21.110702)
		(end 379.645164 -20.79117)
		(width 0.127)
		(layer "B.Cu")
		(net "PHY_SCC_B_TO_DRV_B_32_DP")
	)
	(segment
		(start 294.623236 -176.092612)
		(end 304.315622 -161.167826)
		(width 0.127)
		(layer "B.Cu")
		(net "PHY_SCC_B_TO_DRV_B_32_DP")
	)
	(segment
		(start 379.005338 -21.47824)
		(end 379.212856 -21.158708)
		(width 0.127)
		(layer "B.Cu")
		(net "PHY_SCC_B_TO_DRV_B_32_DP")
	)
	(segment
		(start 379.597412 -20.56638)
		(end 379.80493 -20.246848)
		(width 0.127)
		(layer "B.Cu")
		(net "PHY_SCC_B_TO_DRV_B_32_DP")
	)
	(segment
		(start 291.902896 -177.859182)
		(end 294.623236 -176.092612)
		(width 0.127)
		(layer "B.Cu")
		(net "PHY_SCC_B_TO_DRV_B_32_DP")
	)
	(segment
		(start 378.845572 -22.022562)
		(end 379.05309 -21.70303)
		(width 0.127)
		(layer "B.Cu")
		(net "PHY_SCC_B_TO_DRV_B_32_DP")
	)
	(segment
		(start 379.80493 -20.246848)
		(end 380.02972 -20.199096)
		(width 0.127)
		(layer "B.Cu")
		(net "PHY_SCC_B_TO_DRV_B_32_DP")
	)
	(segment
		(start 378.461016 -22.614636)
		(end 378.413264 -22.389846)
		(width 0.127)
		(layer "B.Cu")
		(net "PHY_SCC_B_TO_DRV_B_32_DP")
	)
	(segment
		(start 279.36825 -178.540664)
		(end 288.717482 -178.540664)
		(width 0.127)
		(layer "B.Cu")
		(net "PHY_SCC_B_TO_DRV_B_32_DP")
	)
	(segment
		(start 379.05309 -21.70303)
		(end 379.005338 -21.47824)
		(width 0.127)
		(layer "B.Cu")
		(net "PHY_SCC_B_TO_DRV_B_32_DP")
	)
	(segment
		(start 379.212856 -21.158708)
		(end 379.437646 -21.110702)
		(width 0.127)
		(layer "B.Cu")
		(net "PHY_SCC_B_TO_DRV_B_32_DP")
	)
	(segment
		(start 383.032 -15.277592)
		(end 383.032 -13.7795)
		(width 0.127)
		(layer "B.Cu")
		(net "PHY_SCC_B_TO_DRV_B_32_DP")
	)
	(segment
		(start 380.02972 -20.199096)
		(end 380.237238 -19.879564)
		(width 0.127)
		(layer "B.Cu")
		(net "PHY_SCC_B_TO_DRV_B_32_DP")
	)
	(segment
		(start 378.620782 -22.070314)
		(end 378.845572 -22.022562)
		(width 0.127)
		(layer "B.Cu")
		(net "PHY_SCC_B_TO_DRV_B_32_DP")
	)
	(segment
		(start 279.082754 -179.10556)
		(end 279.082754 -178.82616)
		(width 0.127)
		(layer "B.Cu")
		(net "PHY_SCC_B_TO_DRV_B_32_DP")
	)
	(segment
		(start 380.237238 -19.879564)
		(end 380.189486 -19.654774)
		(width 0.127)
		(layer "B.Cu")
		(net "PHY_SCC_B_TO_DRV_B_32_DP")
	)
	(segment
		(start 380.189486 -19.654774)
		(end 383.032 -15.277592)
		(width 0.127)
		(layer "B.Cu")
		(net "PHY_SCC_B_TO_DRV_B_32_DP")
	)
	(segment
		(start 312.113168 -124.483622)
		(end 378.028708 -22.982174)
		(width 0.127)
		(layer "B.Cu")
		(net "PHY_SCC_B_TO_DRV_B_32_DP")
	)
	(segment
		(start 383.1844 -13.6271)
		(end 383.45745 -13.6271)
		(width 0.127)
		(layer "B.Cu")
		(net "PHY_SCC_B_TO_DRV_B_32_DP")
	)
	(segment
		(start 279.636728 -179.294536)
		(end 279.27173 -179.294536)
		(width 0.127)
		(layer "B.Cu")
		(net "PHY_SCC_B_TO_DRV_B_32_DP")
	)
	(segment
		(start 304.315622 -161.167826)
		(end 312.113168 -124.483622)
		(width 0.127)
		(layer "B.Cu")
		(net "PHY_SCC_B_TO_DRV_B_32_DP")
	)
	(segment
		(start 378.028708 -22.982174)
		(end 378.253498 -22.934168)
		(width 0.127)
		(layer "B.Cu")
		(net "PHY_SCC_B_TO_DRV_B_32_DP")
	)
	(segment
		(start 288.717482 -178.540664)
		(end 291.902896 -177.859182)
		(width 0.127)
		(layer "B.Cu")
		(net "PHY_SCC_B_TO_DRV_B_32_DP")
	)
	(segment
		(start 378.253498 -22.934168)
		(end 378.461016 -22.614636)
		(width 0.127)
		(layer "B.Cu")
		(net "PHY_SCC_B_TO_DRV_B_32_DP")
	)
	(arc
		(start 383.032 -13.7795)
		(mid 383.076637 -13.671737)
		(end 383.1844 -13.6271)
		(width 0.127)
		(layer "B.Cu")
		(net "PHY_SCC_B_TO_DRV_B_32_DP")
	)
	(arc
		(start 279.27173 -179.294536)
		(mid 279.138104 -179.239186)
		(end 279.082754 -179.10556)
		(width 0.127)
		(layer "B.Cu")
		(net "PHY_SCC_B_TO_DRV_B_32_DP")
	)
	(arc
		(start 279.082754 -178.82616)
		(mid 279.166374 -178.624284)
		(end 279.36825 -178.540664)
		(width 0.127)
		(layer "B.Cu")
		(net "PHY_SCC_B_TO_DRV_B_32_DP")
	)
	(segment
		(start 382.5875 -13.6271)
		(end 382.31445 -13.6271)
		(width 0.127)
		(layer "F.Cu")
		(net "PHY_SCC_B_TO_DRV_B_32_DN")
	)
	(segment
		(start 382.7399 -14.656308)
		(end 382.7399 -13.7795)
		(width 0.127)
		(layer "F.Cu")
		(net "PHY_SCC_B_TO_DRV_B_32_DN")
	)
	(segment
		(start 383.901696 -14.997176)
		(end 383.080768 -14.997176)
		(width 0.127)
		(layer "F.Cu")
		(net "PHY_SCC_B_TO_DRV_B_32_DN")
	)
	(segment
		(start 383.080768 -14.997176)
		(end 382.7399 -14.656308)
		(width 0.127)
		(layer "F.Cu")
		(net "PHY_SCC_B_TO_DRV_B_32_DN")
	)
	(segment
		(start 384.123946 -15.219426)
		(end 383.901696 -14.997176)
		(width 0.127)
		(layer "F.Cu")
		(net "PHY_SCC_B_TO_DRV_B_32_DN")
	)
	(segment
		(start 384.455162 -15.219426)
		(end 384.123946 -15.219426)
		(width 0.127)
		(layer "F.Cu")
		(net "PHY_SCC_B_TO_DRV_B_32_DN")
	)
	(arc
		(start 382.7399 -13.7795)
		(mid 382.695263 -13.671737)
		(end 382.5875 -13.6271)
		(width 0.127)
		(layer "F.Cu")
		(net "PHY_SCC_B_TO_DRV_B_32_DN")
	)
	(segment
		(start 279.36825 -178.248564)
		(end 288.686494 -178.248564)
		(width 0.127)
		(layer "B.Cu")
		(net "PHY_SCC_B_TO_DRV_B_32_DN")
	)
	(segment
		(start 294.411908 -175.881284)
		(end 304.041048 -161.054034)
		(width 0.127)
		(layer "B.Cu")
		(net "PHY_SCC_B_TO_DRV_B_32_DN")
	)
	(segment
		(start 288.686494 -178.248564)
		(end 291.78885 -177.584608)
		(width 0.127)
		(layer "B.Cu")
		(net "PHY_SCC_B_TO_DRV_B_32_DN")
	)
	(segment
		(start 382.7399 -15.190978)
		(end 382.7399 -13.7795)
		(width 0.127)
		(layer "B.Cu")
		(net "PHY_SCC_B_TO_DRV_B_32_DN")
	)
	(segment
		(start 304.041048 -161.054034)
		(end 311.838594 -124.36983)
		(width 0.127)
		(layer "B.Cu")
		(net "PHY_SCC_B_TO_DRV_B_32_DN")
	)
	(segment
		(start 311.838594 -124.36983)
		(end 382.7399 -15.190978)
		(width 0.127)
		(layer "B.Cu")
		(net "PHY_SCC_B_TO_DRV_B_32_DN")
	)
	(segment
		(start 291.78885 -177.584608)
		(end 294.411908 -175.881284)
		(width 0.127)
		(layer "B.Cu")
		(net "PHY_SCC_B_TO_DRV_B_32_DN")
	)
	(segment
		(start 278.790654 -179.10556)
		(end 278.790654 -178.82616)
		(width 0.127)
		(layer "B.Cu")
		(net "PHY_SCC_B_TO_DRV_B_32_DN")
	)
	(segment
		(start 382.5875 -13.6271)
		(end 382.31445 -13.6271)
		(width 0.127)
		(layer "B.Cu")
		(net "PHY_SCC_B_TO_DRV_B_32_DN")
	)
	(segment
		(start 278.23668 -179.294536)
		(end 278.601678 -179.294536)
		(width 0.127)
		(layer "B.Cu")
		(net "PHY_SCC_B_TO_DRV_B_32_DN")
	)
	(arc
		(start 278.790654 -178.82616)
		(mid 278.959828 -178.417738)
		(end 279.36825 -178.248564)
		(width 0.127)
		(layer "B.Cu")
		(net "PHY_SCC_B_TO_DRV_B_32_DN")
	)
	(arc
		(start 278.601678 -179.294536)
		(mid 278.735304 -179.239186)
		(end 278.790654 -179.10556)
		(width 0.127)
		(layer "B.Cu")
		(net "PHY_SCC_B_TO_DRV_B_32_DN")
	)
	(arc
		(start 382.7399 -13.7795)
		(mid 382.695263 -13.671737)
		(end 382.5875 -13.6271)
		(width 0.127)
		(layer "B.Cu")
		(net "PHY_SCC_B_TO_DRV_B_32_DN")
	)
	(segment
		(start 351.6757 -14.728698)
		(end 351.482152 -14.53515)
		(width 0.127)
		(layer "F.Cu")
		(net "PHY_SCC_B_TO_DRV_B_31_DP")
	)
	(segment
		(start 352.905314 -14.660626)
		(end 352.574098 -14.660626)
		(width 0.127)
		(layer "F.Cu")
		(net "PHY_SCC_B_TO_DRV_B_31_DP")
	)
	(segment
		(start 351.656904 -13.6271)
		(end 351.907602 -13.6271)
		(width 0.127)
		(layer "F.Cu")
		(net "PHY_SCC_B_TO_DRV_B_31_DP")
	)
	(segment
		(start 352.506026 -14.728698)
		(end 351.6757 -14.728698)
		(width 0.127)
		(layer "F.Cu")
		(net "PHY_SCC_B_TO_DRV_B_31_DP")
	)
	(segment
		(start 352.574098 -14.660626)
		(end 352.506026 -14.728698)
		(width 0.127)
		(layer "F.Cu")
		(net "PHY_SCC_B_TO_DRV_B_31_DP")
	)
	(segment
		(start 351.482152 -14.53515)
		(end 351.482152 -13.801852)
		(width 0.127)
		(layer "F.Cu")
		(net "PHY_SCC_B_TO_DRV_B_31_DP")
	)
	(arc
		(start 351.482152 -13.801852)
		(mid 351.533336 -13.678284)
		(end 351.656904 -13.6271)
		(width 0.127)
		(layer "F.Cu")
		(net "PHY_SCC_B_TO_DRV_B_31_DP")
	)
	(segment
		(start 334.532732 -85.53577)
		(end 334.739996 -85.216238)
		(width 0.127)
		(layer "B.Cu")
		(net "PHY_SCC_B_TO_DRV_B_31_DP")
	)
	(segment
		(start 335.124806 -84.624164)
		(end 335.332324 -84.304632)
		(width 0.127)
		(layer "B.Cu")
		(net "PHY_SCC_B_TO_DRV_B_31_DP")
	)
	(segment
		(start 335.924398 -83.393026)
		(end 335.876646 -83.167982)
		(width 0.127)
		(layer "B.Cu")
		(net "PHY_SCC_B_TO_DRV_B_31_DP")
	)
	(segment
		(start 351.656904 -13.6271)
		(end 351.907602 -13.6271)
		(width 0.127)
		(layer "B.Cu")
		(net "PHY_SCC_B_TO_DRV_B_31_DP")
	)
	(segment
		(start 302.415702 -160.61182)
		(end 310.605678 -122.080782)
		(width 0.127)
		(layer "B.Cu")
		(net "PHY_SCC_B_TO_DRV_B_31_DP")
	)
	(segment
		(start 280.368248 -176.740566)
		(end 288.449766 -176.740566)
		(width 0.127)
		(layer "B.Cu")
		(net "PHY_SCC_B_TO_DRV_B_31_DP")
	)
	(segment
		(start 334.307688 -85.583776)
		(end 334.532732 -85.53577)
		(width 0.127)
		(layer "B.Cu")
		(net "PHY_SCC_B_TO_DRV_B_31_DP")
	)
	(segment
		(start 351.482152 -15.405608)
		(end 351.482152 -13.801852)
		(width 0.127)
		(layer "B.Cu")
		(net "PHY_SCC_B_TO_DRV_B_31_DP")
	)
	(segment
		(start 334.899762 -84.671916)
		(end 335.124806 -84.624164)
		(width 0.127)
		(layer "B.Cu")
		(net "PHY_SCC_B_TO_DRV_B_31_DP")
	)
	(segment
		(start 334.692244 -84.991448)
		(end 334.899762 -84.671916)
		(width 0.127)
		(layer "B.Cu")
		(net "PHY_SCC_B_TO_DRV_B_31_DP")
	)
	(segment
		(start 280.636726 -177.494438)
		(end 280.271728 -177.494438)
		(width 0.127)
		(layer "B.Cu")
		(net "PHY_SCC_B_TO_DRV_B_31_DP")
	)
	(segment
		(start 335.491836 -83.76031)
		(end 335.71688 -83.712558)
		(width 0.127)
		(layer "B.Cu")
		(net "PHY_SCC_B_TO_DRV_B_31_DP")
	)
	(segment
		(start 334.10017 -85.903308)
		(end 334.307688 -85.583776)
		(width 0.127)
		(layer "B.Cu")
		(net "PHY_SCC_B_TO_DRV_B_31_DP")
	)
	(segment
		(start 334.147922 -86.128098)
		(end 334.10017 -85.903308)
		(width 0.127)
		(layer "B.Cu")
		(net "PHY_SCC_B_TO_DRV_B_31_DP")
	)
	(segment
		(start 310.605678 -122.080782)
		(end 333.715614 -86.495382)
		(width 0.127)
		(layer "B.Cu")
		(net "PHY_SCC_B_TO_DRV_B_31_DP")
	)
	(segment
		(start 288.449766 -176.740566)
		(end 290.971986 -176.204626)
		(width 0.127)
		(layer "B.Cu")
		(net "PHY_SCC_B_TO_DRV_B_31_DP")
	)
	(segment
		(start 345.160854 -56.59247)
		(end 351.482152 -15.405608)
		(width 0.127)
		(layer "B.Cu")
		(net "PHY_SCC_B_TO_DRV_B_31_DP")
	)
	(segment
		(start 335.332324 -84.304632)
		(end 335.284318 -84.079842)
		(width 0.127)
		(layer "B.Cu")
		(net "PHY_SCC_B_TO_DRV_B_31_DP")
	)
	(segment
		(start 290.971986 -176.204626)
		(end 293.247826 -174.72914)
		(width 0.127)
		(layer "B.Cu")
		(net "PHY_SCC_B_TO_DRV_B_31_DP")
	)
	(segment
		(start 333.940404 -86.44763)
		(end 334.147922 -86.128098)
		(width 0.127)
		(layer "B.Cu")
		(net "PHY_SCC_B_TO_DRV_B_31_DP")
	)
	(segment
		(start 335.284318 -84.079842)
		(end 335.491836 -83.76031)
		(width 0.127)
		(layer "B.Cu")
		(net "PHY_SCC_B_TO_DRV_B_31_DP")
	)
	(segment
		(start 293.247826 -174.72914)
		(end 302.415702 -160.61182)
		(width 0.127)
		(layer "B.Cu")
		(net "PHY_SCC_B_TO_DRV_B_31_DP")
	)
	(segment
		(start 280.082752 -177.305462)
		(end 280.082752 -177.026062)
		(width 0.127)
		(layer "B.Cu")
		(net "PHY_SCC_B_TO_DRV_B_31_DP")
	)
	(segment
		(start 334.739996 -85.216238)
		(end 334.692244 -84.991448)
		(width 0.127)
		(layer "B.Cu")
		(net "PHY_SCC_B_TO_DRV_B_31_DP")
	)
	(segment
		(start 335.876646 -83.167982)
		(end 337.460844 -80.728566)
		(width 0.127)
		(layer "B.Cu")
		(net "PHY_SCC_B_TO_DRV_B_31_DP")
	)
	(segment
		(start 337.460844 -80.728566)
		(end 345.160854 -56.59247)
		(width 0.127)
		(layer "B.Cu")
		(net "PHY_SCC_B_TO_DRV_B_31_DP")
	)
	(segment
		(start 333.715614 -86.495382)
		(end 333.940404 -86.44763)
		(width 0.127)
		(layer "B.Cu")
		(net "PHY_SCC_B_TO_DRV_B_31_DP")
	)
	(segment
		(start 335.71688 -83.712558)
		(end 335.924398 -83.393026)
		(width 0.127)
		(layer "B.Cu")
		(net "PHY_SCC_B_TO_DRV_B_31_DP")
	)
	(arc
		(start 280.271728 -177.494438)
		(mid 280.138102 -177.439088)
		(end 280.082752 -177.305462)
		(width 0.127)
		(layer "B.Cu")
		(net "PHY_SCC_B_TO_DRV_B_31_DP")
	)
	(arc
		(start 351.482152 -13.801852)
		(mid 351.533336 -13.678284)
		(end 351.656904 -13.6271)
		(width 0.127)
		(layer "B.Cu")
		(net "PHY_SCC_B_TO_DRV_B_31_DP")
	)
	(arc
		(start 280.082752 -177.026062)
		(mid 280.166372 -176.824186)
		(end 280.368248 -176.740566)
		(width 0.127)
		(layer "B.Cu")
		(net "PHY_SCC_B_TO_DRV_B_31_DP")
	)
	(segment
		(start 352.905314 -15.219426)
		(end 352.574098 -15.219426)
		(width 0.127)
		(layer "F.Cu")
		(net "PHY_SCC_B_TO_DRV_B_31_DN")
	)
	(segment
		(start 351.554542 -15.020798)
		(end 351.190052 -14.656308)
		(width 0.127)
		(layer "F.Cu")
		(net "PHY_SCC_B_TO_DRV_B_31_DN")
	)
	(segment
		(start 352.37547 -15.020798)
		(end 351.554542 -15.020798)
		(width 0.127)
		(layer "F.Cu")
		(net "PHY_SCC_B_TO_DRV_B_31_DN")
	)
	(segment
		(start 352.574098 -15.219426)
		(end 352.37547 -15.020798)
		(width 0.127)
		(layer "F.Cu")
		(net "PHY_SCC_B_TO_DRV_B_31_DN")
	)
	(segment
		(start 351.0153 -13.6271)
		(end 350.764602 -13.6271)
		(width 0.127)
		(layer "F.Cu")
		(net "PHY_SCC_B_TO_DRV_B_31_DN")
	)
	(segment
		(start 351.190052 -14.656308)
		(end 351.190052 -13.801852)
		(width 0.127)
		(layer "F.Cu")
		(net "PHY_SCC_B_TO_DRV_B_31_DN")
	)
	(arc
		(start 351.190052 -13.801852)
		(mid 351.138868 -13.678284)
		(end 351.0153 -13.6271)
		(width 0.127)
		(layer "F.Cu")
		(net "PHY_SCC_B_TO_DRV_B_31_DN")
	)
	(segment
		(start 293.036752 -174.517812)
		(end 302.141128 -160.498028)
		(width 0.127)
		(layer "B.Cu")
		(net "PHY_SCC_B_TO_DRV_B_31_DN")
	)
	(segment
		(start 279.790652 -177.305462)
		(end 279.790652 -177.026062)
		(width 0.127)
		(layer "B.Cu")
		(net "PHY_SCC_B_TO_DRV_B_31_DN")
	)
	(segment
		(start 280.368248 -176.448466)
		(end 288.419032 -176.448466)
		(width 0.127)
		(layer "B.Cu")
		(net "PHY_SCC_B_TO_DRV_B_31_DN")
	)
	(segment
		(start 302.141128 -160.498028)
		(end 310.331104 -121.96699)
		(width 0.127)
		(layer "B.Cu")
		(net "PHY_SCC_B_TO_DRV_B_31_DN")
	)
	(segment
		(start 290.858448 -175.930052)
		(end 293.036752 -174.517812)
		(width 0.127)
		(layer "B.Cu")
		(net "PHY_SCC_B_TO_DRV_B_31_DN")
	)
	(segment
		(start 288.419032 -176.448466)
		(end 290.858448 -175.930052)
		(width 0.127)
		(layer "B.Cu")
		(net "PHY_SCC_B_TO_DRV_B_31_DN")
	)
	(segment
		(start 337.194398 -80.602328)
		(end 344.875612 -56.525414)
		(width 0.127)
		(layer "B.Cu")
		(net "PHY_SCC_B_TO_DRV_B_31_DN")
	)
	(segment
		(start 351.0153 -13.6271)
		(end 350.764602 -13.6271)
		(width 0.127)
		(layer "B.Cu")
		(net "PHY_SCC_B_TO_DRV_B_31_DN")
	)
	(segment
		(start 351.190052 -15.383256)
		(end 351.190052 -13.801852)
		(width 0.127)
		(layer "B.Cu")
		(net "PHY_SCC_B_TO_DRV_B_31_DN")
	)
	(segment
		(start 279.236678 -177.494438)
		(end 279.601676 -177.494438)
		(width 0.127)
		(layer "B.Cu")
		(net "PHY_SCC_B_TO_DRV_B_31_DN")
	)
	(segment
		(start 344.875612 -56.525414)
		(end 351.190052 -15.383256)
		(width 0.127)
		(layer "B.Cu")
		(net "PHY_SCC_B_TO_DRV_B_31_DN")
	)
	(segment
		(start 310.331104 -121.96699)
		(end 337.194398 -80.602328)
		(width 0.127)
		(layer "B.Cu")
		(net "PHY_SCC_B_TO_DRV_B_31_DN")
	)
	(arc
		(start 279.790652 -177.026062)
		(mid 279.959826 -176.61764)
		(end 280.368248 -176.448466)
		(width 0.127)
		(layer "B.Cu")
		(net "PHY_SCC_B_TO_DRV_B_31_DN")
	)
	(arc
		(start 351.190052 -13.801852)
		(mid 351.138868 -13.678284)
		(end 351.0153 -13.6271)
		(width 0.127)
		(layer "B.Cu")
		(net "PHY_SCC_B_TO_DRV_B_31_DN")
	)
	(arc
		(start 279.601676 -177.494438)
		(mid 279.735302 -177.439088)
		(end 279.790652 -177.305462)
		(width 0.127)
		(layer "B.Cu")
		(net "PHY_SCC_B_TO_DRV_B_31_DN")
	)
	(segment
		(start 319.93205 -14.53515)
		(end 319.93205 -13.79855)
		(width 0.127)
		(layer "F.Cu")
		(net "PHY_SCC_B_TO_DRV_B_30_DP")
	)
	(segment
		(start 320.916046 -14.768576)
		(end 320.165476 -14.768576)
		(width 0.127)
		(layer "F.Cu")
		(net "PHY_SCC_B_TO_DRV_B_30_DP")
	)
	(segment
		(start 321.023996 -14.660626)
		(end 320.916046 -14.768576)
		(width 0.127)
		(layer "F.Cu")
		(net "PHY_SCC_B_TO_DRV_B_30_DP")
	)
	(segment
		(start 320.1035 -13.6271)
		(end 320.3575 -13.6271)
		(width 0.127)
		(layer "F.Cu")
		(net "PHY_SCC_B_TO_DRV_B_30_DP")
	)
	(segment
		(start 320.165476 -14.768576)
		(end 319.93205 -14.53515)
		(width 0.127)
		(layer "F.Cu")
		(net "PHY_SCC_B_TO_DRV_B_30_DP")
	)
	(segment
		(start 321.355212 -14.660626)
		(end 321.023996 -14.660626)
		(width 0.127)
		(layer "F.Cu")
		(net "PHY_SCC_B_TO_DRV_B_30_DP")
	)
	(arc
		(start 319.93205 -13.79855)
		(mid 319.982267 -13.677317)
		(end 320.1035 -13.6271)
		(width 0.127)
		(layer "F.Cu")
		(net "PHY_SCC_B_TO_DRV_B_30_DP")
	)
	(segment
		(start 320.1035 -13.6271)
		(end 320.3575 -13.6271)
		(width 0.127)
		(layer "B.Cu")
		(net "PHY_SCC_B_TO_DRV_B_30_DP")
	)
	(segment
		(start 300.50994 -159.824674)
		(end 306.408582 -132.052314)
		(width 0.127)
		(layer "B.Cu")
		(net "PHY_SCC_B_TO_DRV_B_30_DP")
	)
	(segment
		(start 306.668424 -131.562094)
		(end 306.551076 -131.3815)
		(width 0.127)
		(layer "B.Cu")
		(net "PHY_SCC_B_TO_DRV_B_30_DP")
	)
	(segment
		(start 307.111654 -129.47523)
		(end 306.994306 -129.294382)
		(width 0.127)
		(layer "B.Cu")
		(net "PHY_SCC_B_TO_DRV_B_30_DP")
	)
	(segment
		(start 307.254148 -128.804416)
		(end 307.333396 -128.431544)
		(width 0.127)
		(layer "B.Cu")
		(net "PHY_SCC_B_TO_DRV_B_30_DP")
	)
	(segment
		(start 307.333396 -128.431544)
		(end 307.216048 -128.25095)
		(width 0.127)
		(layer "B.Cu")
		(net "PHY_SCC_B_TO_DRV_B_30_DP")
	)
	(segment
		(start 306.551076 -131.3815)
		(end 306.630324 -131.008882)
		(width 0.127)
		(layer "B.Cu")
		(net "PHY_SCC_B_TO_DRV_B_30_DP")
	)
	(segment
		(start 306.810918 -130.89128)
		(end 306.890166 -130.518662)
		(width 0.127)
		(layer "B.Cu")
		(net "PHY_SCC_B_TO_DRV_B_30_DP")
	)
	(segment
		(start 288.050478 -174.940722)
		(end 290.336732 -174.455074)
		(width 0.127)
		(layer "B.Cu")
		(net "PHY_SCC_B_TO_DRV_B_30_DP")
	)
	(segment
		(start 306.994306 -129.294382)
		(end 307.073554 -128.921764)
		(width 0.127)
		(layer "B.Cu")
		(net "PHY_SCC_B_TO_DRV_B_30_DP")
	)
	(segment
		(start 279.36825 -174.940722)
		(end 288.050478 -174.940722)
		(width 0.127)
		(layer "B.Cu")
		(net "PHY_SCC_B_TO_DRV_B_30_DP")
	)
	(segment
		(start 306.851812 -129.965196)
		(end 307.03266 -129.847848)
		(width 0.127)
		(layer "B.Cu")
		(net "PHY_SCC_B_TO_DRV_B_30_DP")
	)
	(segment
		(start 279.636728 -175.694594)
		(end 279.27173 -175.694594)
		(width 0.127)
		(layer "B.Cu")
		(net "PHY_SCC_B_TO_DRV_B_30_DP")
	)
	(segment
		(start 312.988706 -101.068886)
		(end 319.93205 -15.638018)
		(width 0.127)
		(layer "B.Cu")
		(net "PHY_SCC_B_TO_DRV_B_30_DP")
	)
	(segment
		(start 307.03266 -129.847848)
		(end 307.111654 -129.47523)
		(width 0.127)
		(layer "B.Cu")
		(net "PHY_SCC_B_TO_DRV_B_30_DP")
	)
	(segment
		(start 306.408582 -132.052314)
		(end 306.58943 -131.934966)
		(width 0.127)
		(layer "B.Cu")
		(net "PHY_SCC_B_TO_DRV_B_30_DP")
	)
	(segment
		(start 306.58943 -131.934966)
		(end 306.668424 -131.562094)
		(width 0.127)
		(layer "B.Cu")
		(net "PHY_SCC_B_TO_DRV_B_30_DP")
	)
	(segment
		(start 279.082754 -175.505618)
		(end 279.082754 -175.226218)
		(width 0.127)
		(layer "B.Cu")
		(net "PHY_SCC_B_TO_DRV_B_30_DP")
	)
	(segment
		(start 306.890166 -130.518662)
		(end 306.772818 -130.338068)
		(width 0.127)
		(layer "B.Cu")
		(net "PHY_SCC_B_TO_DRV_B_30_DP")
	)
	(segment
		(start 307.216048 -128.25095)
		(end 312.988706 -101.068886)
		(width 0.127)
		(layer "B.Cu")
		(net "PHY_SCC_B_TO_DRV_B_30_DP")
	)
	(segment
		(start 290.336732 -174.455074)
		(end 291.499544 -173.699678)
		(width 0.127)
		(layer "B.Cu")
		(net "PHY_SCC_B_TO_DRV_B_30_DP")
	)
	(segment
		(start 306.772818 -130.338068)
		(end 306.851812 -129.965196)
		(width 0.127)
		(layer "B.Cu")
		(net "PHY_SCC_B_TO_DRV_B_30_DP")
	)
	(segment
		(start 291.499544 -173.699678)
		(end 300.50994 -159.824674)
		(width 0.127)
		(layer "B.Cu")
		(net "PHY_SCC_B_TO_DRV_B_30_DP")
	)
	(segment
		(start 307.073554 -128.921764)
		(end 307.254148 -128.804416)
		(width 0.127)
		(layer "B.Cu")
		(net "PHY_SCC_B_TO_DRV_B_30_DP")
	)
	(segment
		(start 306.630324 -131.008882)
		(end 306.810918 -130.89128)
		(width 0.127)
		(layer "B.Cu")
		(net "PHY_SCC_B_TO_DRV_B_30_DP")
	)
	(segment
		(start 319.93205 -15.638018)
		(end 319.93205 -13.79855)
		(width 0.127)
		(layer "B.Cu")
		(net "PHY_SCC_B_TO_DRV_B_30_DP")
	)
	(arc
		(start 279.082754 -175.226218)
		(mid 279.166374 -175.024342)
		(end 279.36825 -174.940722)
		(width 0.127)
		(layer "B.Cu")
		(net "PHY_SCC_B_TO_DRV_B_30_DP")
	)
	(arc
		(start 319.93205 -13.79855)
		(mid 319.982267 -13.677317)
		(end 320.1035 -13.6271)
		(width 0.127)
		(layer "B.Cu")
		(net "PHY_SCC_B_TO_DRV_B_30_DP")
	)
	(arc
		(start 279.27173 -175.694594)
		(mid 279.138104 -175.639244)
		(end 279.082754 -175.505618)
		(width 0.127)
		(layer "B.Cu")
		(net "PHY_SCC_B_TO_DRV_B_30_DP")
	)
	(segment
		(start 319.4685 -13.6271)
		(end 319.2145 -13.6271)
		(width 0.127)
		(layer "F.Cu")
		(net "PHY_SCC_B_TO_DRV_B_30_DN")
	)
	(segment
		(start 321.023996 -15.219426)
		(end 320.865246 -15.060676)
		(width 0.127)
		(layer "F.Cu")
		(net "PHY_SCC_B_TO_DRV_B_30_DN")
	)
	(segment
		(start 320.044318 -15.060676)
		(end 319.63995 -14.656308)
		(width 0.127)
		(layer "F.Cu")
		(net "PHY_SCC_B_TO_DRV_B_30_DN")
	)
	(segment
		(start 320.865246 -15.060676)
		(end 320.044318 -15.060676)
		(width 0.127)
		(layer "F.Cu")
		(net "PHY_SCC_B_TO_DRV_B_30_DN")
	)
	(segment
		(start 321.355212 -15.219426)
		(end 321.023996 -15.219426)
		(width 0.127)
		(layer "F.Cu")
		(net "PHY_SCC_B_TO_DRV_B_30_DN")
	)
	(segment
		(start 319.63995 -14.656308)
		(end 319.63995 -13.79855)
		(width 0.127)
		(layer "F.Cu")
		(net "PHY_SCC_B_TO_DRV_B_30_DN")
	)
	(arc
		(start 319.63995 -13.79855)
		(mid 319.589733 -13.677317)
		(end 319.4685 -13.6271)
		(width 0.127)
		(layer "F.Cu")
		(net "PHY_SCC_B_TO_DRV_B_30_DN")
	)
	(segment
		(start 279.36825 -174.648622)
		(end 288.019744 -174.648622)
		(width 0.127)
		(layer "B.Cu")
		(net "PHY_SCC_B_TO_DRV_B_30_DN")
	)
	(segment
		(start 278.23668 -175.694594)
		(end 278.601678 -175.694594)
		(width 0.127)
		(layer "B.Cu")
		(net "PHY_SCC_B_TO_DRV_B_30_DN")
	)
	(segment
		(start 278.790654 -175.505618)
		(end 278.790654 -175.226218)
		(width 0.127)
		(layer "B.Cu")
		(net "PHY_SCC_B_TO_DRV_B_30_DN")
	)
	(segment
		(start 288.019744 -174.648622)
		(end 290.22294 -174.1805)
		(width 0.127)
		(layer "B.Cu")
		(net "PHY_SCC_B_TO_DRV_B_30_DN")
	)
	(segment
		(start 319.63995 -15.62608)
		(end 319.63995 -13.79855)
		(width 0.127)
		(layer "B.Cu")
		(net "PHY_SCC_B_TO_DRV_B_30_DN")
	)
	(segment
		(start 291.288216 -173.48835)
		(end 300.235366 -159.711136)
		(width 0.127)
		(layer "B.Cu")
		(net "PHY_SCC_B_TO_DRV_B_30_DN")
	)
	(segment
		(start 312.698892 -101.026468)
		(end 319.63995 -15.62608)
		(width 0.127)
		(layer "B.Cu")
		(net "PHY_SCC_B_TO_DRV_B_30_DN")
	)
	(segment
		(start 290.22294 -174.1805)
		(end 291.288216 -173.48835)
		(width 0.127)
		(layer "B.Cu")
		(net "PHY_SCC_B_TO_DRV_B_30_DN")
	)
	(segment
		(start 319.4685 -13.6271)
		(end 319.2145 -13.6271)
		(width 0.127)
		(layer "B.Cu")
		(net "PHY_SCC_B_TO_DRV_B_30_DN")
	)
	(segment
		(start 300.235366 -159.711136)
		(end 312.698892 -101.026468)
		(width 0.127)
		(layer "B.Cu")
		(net "PHY_SCC_B_TO_DRV_B_30_DN")
	)
	(arc
		(start 319.63995 -13.79855)
		(mid 319.589733 -13.677317)
		(end 319.4685 -13.6271)
		(width 0.127)
		(layer "B.Cu")
		(net "PHY_SCC_B_TO_DRV_B_30_DN")
	)
	(arc
		(start 278.790654 -175.226218)
		(mid 278.959828 -174.817796)
		(end 279.36825 -174.648622)
		(width 0.127)
		(layer "B.Cu")
		(net "PHY_SCC_B_TO_DRV_B_30_DN")
	)
	(arc
		(start 278.601678 -175.694594)
		(mid 278.735304 -175.639244)
		(end 278.790654 -175.505618)
		(width 0.127)
		(layer "B.Cu")
		(net "PHY_SCC_B_TO_DRV_B_30_DN")
	)
	(segment
		(start 128.93548 -244.68582)
		(end 128.93548 -244.419374)
		(width 0.127)
		(layer "F.Cu")
		(net "PHY_SCC_B_TO_DRV_B_3_DP")
	)
	(segment
		(start 127.78867 -244.660674)
		(end 127.97282 -244.844824)
		(width 0.127)
		(layer "F.Cu")
		(net "PHY_SCC_B_TO_DRV_B_3_DP")
	)
	(segment
		(start 127.392684 -244.660674)
		(end 127.78867 -244.660674)
		(width 0.127)
		(layer "F.Cu")
		(net "PHY_SCC_B_TO_DRV_B_3_DP")
	)
	(segment
		(start 127.97282 -244.844824)
		(end 128.776476 -244.844824)
		(width 0.127)
		(layer "F.Cu")
		(net "PHY_SCC_B_TO_DRV_B_3_DP")
	)
	(arc
		(start 128.776476 -244.844824)
		(mid 128.888909 -244.798253)
		(end 128.93548 -244.68582)
		(width 0.127)
		(layer "F.Cu")
		(net "PHY_SCC_B_TO_DRV_B_3_DP")
	)
	(segment
		(start 129.880106 -244.844062)
		(end 129.87782 -244.844316)
		(width 0.127)
		(layer "B.Cu")
		(net "PHY_SCC_B_TO_DRV_B_3_DP")
	)
	(segment
		(start 280.636726 -235.094526)
		(end 280.29662 -235.094526)
		(width 0.127)
		(layer "B.Cu")
		(net "PHY_SCC_B_TO_DRV_B_3_DP")
	)
	(segment
		(start 128.93548 -244.710204)
		(end 128.93548 -244.419374)
		(width 0.127)
		(layer "B.Cu")
		(net "PHY_SCC_B_TO_DRV_B_3_DP")
	)
	(segment
		(start 268.879574 -234.048554)
		(end 258.669028 -236.218476)
		(width 0.127)
		(layer "B.Cu")
		(net "PHY_SCC_B_TO_DRV_B_3_DP")
	)
	(segment
		(start 279.428448 -234.048554)
		(end 268.879574 -234.048554)
		(width 0.127)
		(layer "B.Cu")
		(net "PHY_SCC_B_TO_DRV_B_3_DP")
	)
	(segment
		(start 258.669028 -236.218476)
		(end 221.73057 -228.367336)
		(width 0.127)
		(layer "B.Cu")
		(net "PHY_SCC_B_TO_DRV_B_3_DP")
	)
	(segment
		(start 280.082752 -234.880658)
		(end 280.082752 -234.702858)
		(width 0.127)
		(layer "B.Cu")
		(net "PHY_SCC_B_TO_DRV_B_3_DP")
	)
	(segment
		(start 220.065092 -228.06025)
		(end 157.765242 -240.684304)
		(width 0.127)
		(layer "B.Cu")
		(net "PHY_SCC_B_TO_DRV_B_3_DP")
	)
	(segment
		(start 129.87655 -244.84457)
		(end 129.87655 -244.844824)
		(width 0.127)
		(layer "B.Cu")
		(net "PHY_SCC_B_TO_DRV_B_3_DP")
	)
	(segment
		(start 221.73057 -228.367336)
		(end 220.065092 -228.06025)
		(width 0.127)
		(layer "B.Cu")
		(net "PHY_SCC_B_TO_DRV_B_3_DP")
	)
	(segment
		(start 157.765242 -240.684304)
		(end 129.880106 -244.844062)
		(width 0.127)
		(layer "B.Cu")
		(net "PHY_SCC_B_TO_DRV_B_3_DP")
	)
	(segment
		(start 129.87655 -244.844824)
		(end 129.0701 -244.844824)
		(width 0.127)
		(layer "B.Cu")
		(net "PHY_SCC_B_TO_DRV_B_3_DP")
	)
	(segment
		(start 129.87782 -244.844316)
		(end 129.87655 -244.84457)
		(width 0.127)
		(layer "B.Cu")
		(net "PHY_SCC_B_TO_DRV_B_3_DP")
	)
	(arc
		(start 280.082752 -234.702858)
		(mid 279.891111 -234.240195)
		(end 279.428448 -234.048554)
		(width 0.127)
		(layer "B.Cu")
		(net "PHY_SCC_B_TO_DRV_B_3_DP")
	)
	(arc
		(start 280.29662 -235.094526)
		(mid 280.145392 -235.031886)
		(end 280.082752 -234.880658)
		(width 0.127)
		(layer "B.Cu")
		(net "PHY_SCC_B_TO_DRV_B_3_DP")
	)
	(arc
		(start 129.0701 -244.844824)
		(mid 128.974909 -244.805395)
		(end 128.93548 -244.710204)
		(width 0.127)
		(layer "B.Cu")
		(net "PHY_SCC_B_TO_DRV_B_3_DP")
	)
	(segment
		(start 127.772922 -245.219474)
		(end 127.855472 -245.136924)
		(width 0.127)
		(layer "F.Cu")
		(net "PHY_SCC_B_TO_DRV_B_3_DN")
	)
	(segment
		(start 128.93548 -245.295928)
		(end 128.93548 -245.562374)
		(width 0.127)
		(layer "F.Cu")
		(net "PHY_SCC_B_TO_DRV_B_3_DN")
	)
	(segment
		(start 127.855472 -245.136924)
		(end 128.776476 -245.136924)
		(width 0.127)
		(layer "F.Cu")
		(net "PHY_SCC_B_TO_DRV_B_3_DN")
	)
	(segment
		(start 127.392684 -245.219474)
		(end 127.772922 -245.219474)
		(width 0.127)
		(layer "F.Cu")
		(net "PHY_SCC_B_TO_DRV_B_3_DN")
	)
	(arc
		(start 128.776476 -245.136924)
		(mid 128.888909 -245.183495)
		(end 128.93548 -245.295928)
		(width 0.127)
		(layer "F.Cu")
		(net "PHY_SCC_B_TO_DRV_B_3_DN")
	)
	(segment
		(start 136.006078 -244.225826)
		(end 135.878062 -244.399054)
		(width 0.127)
		(layer "B.Cu")
		(net "PHY_SCC_B_TO_DRV_B_3_DN")
	)
	(segment
		(start 137.061194 -244.0686)
		(end 136.933178 -244.241828)
		(width 0.127)
		(layer "B.Cu")
		(net "PHY_SCC_B_TO_DRV_B_3_DN")
	)
	(segment
		(start 134.822692 -244.556534)
		(end 134.44601 -244.612668)
		(width 0.127)
		(layer "B.Cu")
		(net "PHY_SCC_B_TO_DRV_B_3_DN")
	)
	(segment
		(start 133.895846 -244.540786)
		(end 133.767576 -244.714014)
		(width 0.127)
		(layer "B.Cu")
		(net "PHY_SCC_B_TO_DRV_B_3_DN")
	)
	(segment
		(start 135.501126 -244.455442)
		(end 135.327898 -244.327172)
		(width 0.127)
		(layer "B.Cu")
		(net "PHY_SCC_B_TO_DRV_B_3_DN")
	)
	(segment
		(start 133.217666 -244.641878)
		(end 129.923286 -245.133368)
		(width 0.127)
		(layer "B.Cu")
		(net "PHY_SCC_B_TO_DRV_B_3_DN")
	)
	(segment
		(start 129.898394 -245.136924)
		(end 129.079752 -245.136924)
		(width 0.127)
		(layer "B.Cu")
		(net "PHY_SCC_B_TO_DRV_B_3_DN")
	)
	(segment
		(start 135.327898 -244.327172)
		(end 134.950962 -244.383306)
		(width 0.127)
		(layer "B.Cu")
		(net "PHY_SCC_B_TO_DRV_B_3_DN")
	)
	(segment
		(start 258.669028 -236.51718)
		(end 221.673674 -228.654102)
		(width 0.127)
		(layer "B.Cu")
		(net "PHY_SCC_B_TO_DRV_B_3_DN")
	)
	(segment
		(start 134.272782 -244.484398)
		(end 133.895846 -244.540786)
		(width 0.127)
		(layer "B.Cu")
		(net "PHY_SCC_B_TO_DRV_B_3_DN")
	)
	(segment
		(start 268.910308 -234.340654)
		(end 258.669028 -236.51718)
		(width 0.127)
		(layer "B.Cu")
		(net "PHY_SCC_B_TO_DRV_B_3_DN")
	)
	(segment
		(start 279.790652 -234.880658)
		(end 279.790652 -234.702858)
		(width 0.127)
		(layer "B.Cu")
		(net "PHY_SCC_B_TO_DRV_B_3_DN")
	)
	(segment
		(start 128.93548 -245.281196)
		(end 128.93548 -245.562374)
		(width 0.127)
		(layer "B.Cu")
		(net "PHY_SCC_B_TO_DRV_B_3_DN")
	)
	(segment
		(start 279.236678 -235.094526)
		(end 279.576784 -235.094526)
		(width 0.127)
		(layer "B.Cu")
		(net "PHY_SCC_B_TO_DRV_B_3_DN")
	)
	(segment
		(start 221.673674 -228.654102)
		(end 220.067632 -228.357938)
		(width 0.127)
		(layer "B.Cu")
		(net "PHY_SCC_B_TO_DRV_B_3_DN")
	)
	(segment
		(start 134.44601 -244.612668)
		(end 134.272782 -244.484398)
		(width 0.127)
		(layer "B.Cu")
		(net "PHY_SCC_B_TO_DRV_B_3_DN")
	)
	(segment
		(start 133.767576 -244.714014)
		(end 133.390894 -244.770148)
		(width 0.127)
		(layer "B.Cu")
		(net "PHY_SCC_B_TO_DRV_B_3_DN")
	)
	(segment
		(start 133.390894 -244.770148)
		(end 133.217666 -244.641878)
		(width 0.127)
		(layer "B.Cu")
		(net "PHY_SCC_B_TO_DRV_B_3_DN")
	)
	(segment
		(start 279.428448 -234.340654)
		(end 268.910308 -234.340654)
		(width 0.127)
		(layer "B.Cu")
		(net "PHY_SCC_B_TO_DRV_B_3_DN")
	)
	(segment
		(start 135.878062 -244.399054)
		(end 135.501126 -244.455442)
		(width 0.127)
		(layer "B.Cu")
		(net "PHY_SCC_B_TO_DRV_B_3_DN")
	)
	(segment
		(start 220.067632 -228.357938)
		(end 157.815788 -240.97234)
		(width 0.127)
		(layer "B.Cu")
		(net "PHY_SCC_B_TO_DRV_B_3_DN")
	)
	(segment
		(start 136.556242 -244.297962)
		(end 136.383014 -244.169692)
		(width 0.127)
		(layer "B.Cu")
		(net "PHY_SCC_B_TO_DRV_B_3_DN")
	)
	(segment
		(start 157.815788 -240.97234)
		(end 137.061194 -244.0686)
		(width 0.127)
		(layer "B.Cu")
		(net "PHY_SCC_B_TO_DRV_B_3_DN")
	)
	(segment
		(start 129.923286 -245.133368)
		(end 129.919222 -245.133876)
		(width 0.127)
		(layer "B.Cu")
		(net "PHY_SCC_B_TO_DRV_B_3_DN")
	)
	(segment
		(start 136.383014 -244.169692)
		(end 136.006078 -244.225826)
		(width 0.127)
		(layer "B.Cu")
		(net "PHY_SCC_B_TO_DRV_B_3_DN")
	)
	(segment
		(start 129.919222 -245.133876)
		(end 129.898394 -245.136924)
		(width 0.127)
		(layer "B.Cu")
		(net "PHY_SCC_B_TO_DRV_B_3_DN")
	)
	(segment
		(start 136.933178 -244.241828)
		(end 136.556242 -244.297962)
		(width 0.127)
		(layer "B.Cu")
		(net "PHY_SCC_B_TO_DRV_B_3_DN")
	)
	(segment
		(start 134.950962 -244.383306)
		(end 134.822692 -244.556534)
		(width 0.127)
		(layer "B.Cu")
		(net "PHY_SCC_B_TO_DRV_B_3_DN")
	)
	(arc
		(start 279.790652 -234.702858)
		(mid 279.684565 -234.446741)
		(end 279.428448 -234.340654)
		(width 0.127)
		(layer "B.Cu")
		(net "PHY_SCC_B_TO_DRV_B_3_DN")
	)
	(arc
		(start 279.576784 -235.094526)
		(mid 279.728012 -235.031886)
		(end 279.790652 -234.880658)
		(width 0.127)
		(layer "B.Cu")
		(net "PHY_SCC_B_TO_DRV_B_3_DN")
	)
	(arc
		(start 129.079752 -245.136924)
		(mid 128.977736 -245.17918)
		(end 128.93548 -245.281196)
		(width 0.127)
		(layer "B.Cu")
		(net "PHY_SCC_B_TO_DRV_B_3_DN")
	)
	(segment
		(start 192.035684 -14.685772)
		(end 192.035684 -14.419326)
		(width 0.127)
		(layer "F.Cu")
		(net "PHY_SCC_B_TO_DRV_B_29_DP")
	)
	(segment
		(start 191.073024 -14.844776)
		(end 191.87668 -14.844776)
		(width 0.127)
		(layer "F.Cu")
		(net "PHY_SCC_B_TO_DRV_B_29_DP")
	)
	(segment
		(start 190.492888 -14.660626)
		(end 190.888874 -14.660626)
		(width 0.127)
		(layer "F.Cu")
		(net "PHY_SCC_B_TO_DRV_B_29_DP")
	)
	(segment
		(start 190.888874 -14.660626)
		(end 191.073024 -14.844776)
		(width 0.127)
		(layer "F.Cu")
		(net "PHY_SCC_B_TO_DRV_B_29_DP")
	)
	(arc
		(start 191.87668 -14.844776)
		(mid 191.989113 -14.798205)
		(end 192.035684 -14.685772)
		(width 0.127)
		(layer "F.Cu")
		(net "PHY_SCC_B_TO_DRV_B_29_DP")
	)
	(segment
		(start 202.251818 -124.201936)
		(end 198.72071 -118.76405)
		(width 0.127)
		(layer "B.Cu")
		(net "PHY_SCC_B_TO_DRV_B_29_DP")
	)
	(segment
		(start 268.744954 -180.781706)
		(end 253.698756 -157.612588)
		(width 0.127)
		(layer "B.Cu")
		(net "PHY_SCC_B_TO_DRV_B_29_DP")
	)
	(segment
		(start 193.26098 -15.345664)
		(end 193.072258 -15.055342)
		(width 0.127)
		(layer "B.Cu")
		(net "PHY_SCC_B_TO_DRV_B_29_DP")
	)
	(segment
		(start 198.72071 -118.76405)
		(end 196.235066 -107.070144)
		(width 0.127)
		(layer "B.Cu")
		(net "PHY_SCC_B_TO_DRV_B_29_DP")
	)
	(segment
		(start 253.698756 -157.612588)
		(end 202.251818 -124.201936)
		(width 0.127)
		(layer "B.Cu")
		(net "PHY_SCC_B_TO_DRV_B_29_DP")
	)
	(segment
		(start 196.235066 -107.070144)
		(end 199.27951 -92.746068)
		(width 0.127)
		(layer "B.Cu")
		(net "PHY_SCC_B_TO_DRV_B_29_DP")
	)
	(segment
		(start 279.082754 -186.280552)
		(end 279.082754 -186.102752)
		(width 0.127)
		(layer "B.Cu")
		(net "PHY_SCC_B_TO_DRV_B_29_DP")
	)
	(segment
		(start 192.035684 -14.710156)
		(end 192.035684 -14.419326)
		(width 0.127)
		(layer "B.Cu")
		(net "PHY_SCC_B_TO_DRV_B_29_DP")
	)
	(segment
		(start 192.748662 -14.844776)
		(end 192.170304 -14.844776)
		(width 0.127)
		(layer "B.Cu")
		(net "PHY_SCC_B_TO_DRV_B_29_DP")
	)
	(segment
		(start 199.27951 -92.746068)
		(end 188.377322 -41.453816)
		(width 0.127)
		(layer "B.Cu")
		(net "PHY_SCC_B_TO_DRV_B_29_DP")
	)
	(segment
		(start 188.377322 -41.453816)
		(end 193.593974 -16.911574)
		(width 0.127)
		(layer "B.Cu")
		(net "PHY_SCC_B_TO_DRV_B_29_DP")
	)
	(segment
		(start 275.664676 -185.27522)
		(end 268.744954 -180.781706)
		(width 0.127)
		(layer "B.Cu")
		(net "PHY_SCC_B_TO_DRV_B_29_DP")
	)
	(segment
		(start 193.072258 -15.055342)
		(end 192.748662 -14.844776)
		(width 0.127)
		(layer "B.Cu")
		(net "PHY_SCC_B_TO_DRV_B_29_DP")
	)
	(segment
		(start 278.42845 -185.448448)
		(end 276.479 -185.448448)
		(width 0.127)
		(layer "B.Cu")
		(net "PHY_SCC_B_TO_DRV_B_29_DP")
	)
	(segment
		(start 279.636728 -186.49442)
		(end 279.296622 -186.49442)
		(width 0.127)
		(layer "B.Cu")
		(net "PHY_SCC_B_TO_DRV_B_29_DP")
	)
	(segment
		(start 276.479 -185.448448)
		(end 275.664676 -185.27522)
		(width 0.127)
		(layer "B.Cu")
		(net "PHY_SCC_B_TO_DRV_B_29_DP")
	)
	(segment
		(start 193.593974 -16.911574)
		(end 193.26098 -15.345664)
		(width 0.127)
		(layer "B.Cu")
		(net "PHY_SCC_B_TO_DRV_B_29_DP")
	)
	(arc
		(start 279.296622 -186.49442)
		(mid 279.145394 -186.43178)
		(end 279.082754 -186.280552)
		(width 0.127)
		(layer "B.Cu")
		(net "PHY_SCC_B_TO_DRV_B_29_DP")
	)
	(arc
		(start 192.170304 -14.844776)
		(mid 192.075113 -14.805347)
		(end 192.035684 -14.710156)
		(width 0.127)
		(layer "B.Cu")
		(net "PHY_SCC_B_TO_DRV_B_29_DP")
	)
	(arc
		(start 279.082754 -186.102752)
		(mid 278.891113 -185.640089)
		(end 278.42845 -185.448448)
		(width 0.127)
		(layer "B.Cu")
		(net "PHY_SCC_B_TO_DRV_B_29_DP")
	)
	(segment
		(start 192.035684 -15.29588)
		(end 192.035684 -15.562326)
		(width 0.127)
		(layer "F.Cu")
		(net "PHY_SCC_B_TO_DRV_B_29_DN")
	)
	(segment
		(start 190.873126 -15.219426)
		(end 190.955676 -15.136876)
		(width 0.127)
		(layer "F.Cu")
		(net "PHY_SCC_B_TO_DRV_B_29_DN")
	)
	(segment
		(start 190.492888 -15.219426)
		(end 190.873126 -15.219426)
		(width 0.127)
		(layer "F.Cu")
		(net "PHY_SCC_B_TO_DRV_B_29_DN")
	)
	(segment
		(start 190.955676 -15.136876)
		(end 191.87668 -15.136876)
		(width 0.127)
		(layer "F.Cu")
		(net "PHY_SCC_B_TO_DRV_B_29_DN")
	)
	(arc
		(start 191.87668 -15.136876)
		(mid 191.989113 -15.183447)
		(end 192.035684 -15.29588)
		(width 0.127)
		(layer "F.Cu")
		(net "PHY_SCC_B_TO_DRV_B_29_DN")
	)
	(segment
		(start 278.23668 -186.49442)
		(end 278.576786 -186.49442)
		(width 0.127)
		(layer "B.Cu")
		(net "PHY_SCC_B_TO_DRV_B_29_DN")
	)
	(segment
		(start 278.790654 -186.280552)
		(end 278.790654 -186.102752)
		(width 0.127)
		(layer "B.Cu")
		(net "PHY_SCC_B_TO_DRV_B_29_DN")
	)
	(segment
		(start 191.36487 -56.915558)
		(end 191.184276 -56.79821)
		(width 0.127)
		(layer "B.Cu")
		(net "PHY_SCC_B_TO_DRV_B_29_DN")
	)
	(segment
		(start 192.86093 -15.26667)
		(end 192.661794 -15.136876)
		(width 0.127)
		(layer "B.Cu")
		(net "PHY_SCC_B_TO_DRV_B_29_DN")
	)
	(segment
		(start 190.883286 -55.38216)
		(end 191.000634 -55.201312)
		(width 0.127)
		(layer "B.Cu")
		(net "PHY_SCC_B_TO_DRV_B_29_DN")
	)
	(segment
		(start 191.184276 -56.79821)
		(end 191.105028 -56.425592)
		(width 0.127)
		(layer "B.Cu")
		(net "PHY_SCC_B_TO_DRV_B_29_DN")
	)
	(segment
		(start 191.105028 -56.425592)
		(end 191.222376 -56.244744)
		(width 0.127)
		(layer "B.Cu")
		(net "PHY_SCC_B_TO_DRV_B_29_DN")
	)
	(segment
		(start 268.533626 -180.993034)
		(end 253.487428 -157.823916)
		(width 0.127)
		(layer "B.Cu")
		(net "PHY_SCC_B_TO_DRV_B_29_DN")
	)
	(segment
		(start 193.29527 -16.911574)
		(end 192.986406 -15.459456)
		(width 0.127)
		(layer "B.Cu")
		(net "PHY_SCC_B_TO_DRV_B_29_DN")
	)
	(segment
		(start 192.661794 -15.136876)
		(end 192.179956 -15.136876)
		(width 0.127)
		(layer "B.Cu")
		(net "PHY_SCC_B_TO_DRV_B_29_DN")
	)
	(segment
		(start 192.035684 -15.281148)
		(end 192.035684 -15.562326)
		(width 0.127)
		(layer "B.Cu")
		(net "PHY_SCC_B_TO_DRV_B_29_DN")
	)
	(segment
		(start 202.04049 -124.413264)
		(end 198.446136 -118.877842)
		(width 0.127)
		(layer "B.Cu")
		(net "PHY_SCC_B_TO_DRV_B_29_DN")
	)
	(segment
		(start 191.222376 -56.244744)
		(end 191.143128 -55.872126)
		(width 0.127)
		(layer "B.Cu")
		(net "PHY_SCC_B_TO_DRV_B_29_DN")
	)
	(segment
		(start 190.66129 -54.338728)
		(end 190.778638 -54.15788)
		(width 0.127)
		(layer "B.Cu")
		(net "PHY_SCC_B_TO_DRV_B_29_DN")
	)
	(segment
		(start 191.32677 -57.469024)
		(end 191.444118 -57.28843)
		(width 0.127)
		(layer "B.Cu")
		(net "PHY_SCC_B_TO_DRV_B_29_DN")
	)
	(segment
		(start 191.444118 -57.28843)
		(end 191.36487 -56.915558)
		(width 0.127)
		(layer "B.Cu")
		(net "PHY_SCC_B_TO_DRV_B_29_DN")
	)
	(segment
		(start 190.96228 -55.754778)
		(end 190.883286 -55.38216)
		(width 0.127)
		(layer "B.Cu")
		(net "PHY_SCC_B_TO_DRV_B_29_DN")
	)
	(segment
		(start 276.448266 -185.740548)
		(end 275.550884 -185.549794)
		(width 0.127)
		(layer "B.Cu")
		(net "PHY_SCC_B_TO_DRV_B_29_DN")
	)
	(segment
		(start 191.586612 -57.959244)
		(end 191.406018 -57.841642)
		(width 0.127)
		(layer "B.Cu")
		(net "PHY_SCC_B_TO_DRV_B_29_DN")
	)
	(segment
		(start 192.986406 -15.459456)
		(end 192.86093 -15.26667)
		(width 0.127)
		(layer "B.Cu")
		(net "PHY_SCC_B_TO_DRV_B_29_DN")
	)
	(segment
		(start 191.143128 -55.872126)
		(end 190.96228 -55.754778)
		(width 0.127)
		(layer "B.Cu")
		(net "PHY_SCC_B_TO_DRV_B_29_DN")
	)
	(segment
		(start 278.42845 -185.740548)
		(end 276.448266 -185.740548)
		(width 0.127)
		(layer "B.Cu")
		(net "PHY_SCC_B_TO_DRV_B_29_DN")
	)
	(segment
		(start 190.921386 -54.828694)
		(end 190.740538 -54.711346)
		(width 0.127)
		(layer "B.Cu")
		(net "PHY_SCC_B_TO_DRV_B_29_DN")
	)
	(segment
		(start 198.980806 -92.746068)
		(end 191.586612 -57.959244)
		(width 0.127)
		(layer "B.Cu")
		(net "PHY_SCC_B_TO_DRV_B_29_DN")
	)
	(segment
		(start 190.699898 -29.121862)
		(end 193.29527 -16.911574)
		(width 0.127)
		(layer "B.Cu")
		(net "PHY_SCC_B_TO_DRV_B_29_DN")
	)
	(segment
		(start 195.936362 -107.070144)
		(end 198.980806 -92.746068)
		(width 0.127)
		(layer "B.Cu")
		(net "PHY_SCC_B_TO_DRV_B_29_DN")
	)
	(segment
		(start 275.550884 -185.549794)
		(end 268.533626 -180.993034)
		(width 0.127)
		(layer "B.Cu")
		(net "PHY_SCC_B_TO_DRV_B_29_DN")
	)
	(segment
		(start 190.778638 -54.15788)
		(end 188.078618 -41.453816)
		(width 0.127)
		(layer "B.Cu")
		(net "PHY_SCC_B_TO_DRV_B_29_DN")
	)
	(segment
		(start 198.446136 -118.877842)
		(end 195.936362 -107.070144)
		(width 0.127)
		(layer "B.Cu")
		(net "PHY_SCC_B_TO_DRV_B_29_DN")
	)
	(segment
		(start 188.078618 -41.453816)
		(end 190.699898 -29.121862)
		(width 0.127)
		(layer "B.Cu")
		(net "PHY_SCC_B_TO_DRV_B_29_DN")
	)
	(segment
		(start 191.406018 -57.841642)
		(end 191.32677 -57.469024)
		(width 0.127)
		(layer "B.Cu")
		(net "PHY_SCC_B_TO_DRV_B_29_DN")
	)
	(segment
		(start 253.487428 -157.823916)
		(end 202.04049 -124.413264)
		(width 0.127)
		(layer "B.Cu")
		(net "PHY_SCC_B_TO_DRV_B_29_DN")
	)
	(segment
		(start 191.000634 -55.201312)
		(end 190.921386 -54.828694)
		(width 0.127)
		(layer "B.Cu")
		(net "PHY_SCC_B_TO_DRV_B_29_DN")
	)
	(segment
		(start 190.740538 -54.711346)
		(end 190.66129 -54.338728)
		(width 0.127)
		(layer "B.Cu")
		(net "PHY_SCC_B_TO_DRV_B_29_DN")
	)
	(arc
		(start 192.179956 -15.136876)
		(mid 192.07794 -15.179132)
		(end 192.035684 -15.281148)
		(width 0.127)
		(layer "B.Cu")
		(net "PHY_SCC_B_TO_DRV_B_29_DN")
	)
	(arc
		(start 278.790654 -186.102752)
		(mid 278.684567 -185.846635)
		(end 278.42845 -185.740548)
		(width 0.127)
		(layer "B.Cu")
		(net "PHY_SCC_B_TO_DRV_B_29_DN")
	)
	(arc
		(start 278.576786 -186.49442)
		(mid 278.728014 -186.43178)
		(end 278.790654 -186.280552)
		(width 0.127)
		(layer "B.Cu")
		(net "PHY_SCC_B_TO_DRV_B_29_DN")
	)
	(segment
		(start 158.942786 -14.660626)
		(end 159.338772 -14.660626)
		(width 0.127)
		(layer "F.Cu")
		(net "PHY_SCC_B_TO_DRV_B_28_DP")
	)
	(segment
		(start 160.485582 -14.685772)
		(end 160.485582 -14.419326)
		(width 0.127)
		(layer "F.Cu")
		(net "PHY_SCC_B_TO_DRV_B_28_DP")
	)
	(segment
		(start 159.522922 -14.844776)
		(end 160.326578 -14.844776)
		(width 0.127)
		(layer "F.Cu")
		(net "PHY_SCC_B_TO_DRV_B_28_DP")
	)
	(segment
		(start 159.338772 -14.660626)
		(end 159.522922 -14.844776)
		(width 0.127)
		(layer "F.Cu")
		(net "PHY_SCC_B_TO_DRV_B_28_DP")
	)
	(arc
		(start 160.326578 -14.844776)
		(mid 160.439011 -14.798205)
		(end 160.485582 -14.685772)
		(width 0.127)
		(layer "F.Cu")
		(net "PHY_SCC_B_TO_DRV_B_28_DP")
	)
	(segment
		(start 162.737292 -16.28648)
		(end 162.081464 -15.276322)
		(width 0.127)
		(layer "B.Cu")
		(net "PHY_SCC_B_TO_DRV_B_28_DP")
	)
	(segment
		(start 162.081464 -15.276322)
		(end 161.470594 -14.879828)
		(width 0.127)
		(layer "B.Cu")
		(net "PHY_SCC_B_TO_DRV_B_28_DP")
	)
	(segment
		(start 280.082752 -188.08065)
		(end 280.082752 -187.90285)
		(width 0.127)
		(layer "B.Cu")
		(net "PHY_SCC_B_TO_DRV_B_28_DP")
	)
	(segment
		(start 267.800328 -182.268876)
		(end 252.45822 -158.645098)
		(width 0.127)
		(layer "B.Cu")
		(net "PHY_SCC_B_TO_DRV_B_28_DP")
	)
	(segment
		(start 280.636726 -188.294518)
		(end 280.29662 -188.294518)
		(width 0.127)
		(layer "B.Cu")
		(net "PHY_SCC_B_TO_DRV_B_28_DP")
	)
	(segment
		(start 180.509418 -99.898708)
		(end 162.737292 -16.28648)
		(width 0.127)
		(layer "B.Cu")
		(net "PHY_SCC_B_TO_DRV_B_28_DP")
	)
	(segment
		(start 161.305494 -14.844776)
		(end 160.620202 -14.844776)
		(width 0.127)
		(layer "B.Cu")
		(net "PHY_SCC_B_TO_DRV_B_28_DP")
	)
	(segment
		(start 279.428448 -187.248546)
		(end 276.6822 -187.248546)
		(width 0.127)
		(layer "B.Cu")
		(net "PHY_SCC_B_TO_DRV_B_28_DP")
	)
	(segment
		(start 194.000628 -120.675908)
		(end 180.509418 -99.898708)
		(width 0.127)
		(layer "B.Cu")
		(net "PHY_SCC_B_TO_DRV_B_28_DP")
	)
	(segment
		(start 274.878292 -186.86526)
		(end 267.800328 -182.268876)
		(width 0.127)
		(layer "B.Cu")
		(net "PHY_SCC_B_TO_DRV_B_28_DP")
	)
	(segment
		(start 252.45822 -158.645098)
		(end 194.000628 -120.675908)
		(width 0.127)
		(layer "B.Cu")
		(net "PHY_SCC_B_TO_DRV_B_28_DP")
	)
	(segment
		(start 276.6822 -187.248546)
		(end 274.878292 -186.86526)
		(width 0.127)
		(layer "B.Cu")
		(net "PHY_SCC_B_TO_DRV_B_28_DP")
	)
	(segment
		(start 160.485582 -14.710156)
		(end 160.485582 -14.419326)
		(width 0.127)
		(layer "B.Cu")
		(net "PHY_SCC_B_TO_DRV_B_28_DP")
	)
	(segment
		(start 161.470594 -14.879828)
		(end 161.305494 -14.844776)
		(width 0.127)
		(layer "B.Cu")
		(net "PHY_SCC_B_TO_DRV_B_28_DP")
	)
	(arc
		(start 280.29662 -188.294518)
		(mid 280.145392 -188.231878)
		(end 280.082752 -188.08065)
		(width 0.127)
		(layer "B.Cu")
		(net "PHY_SCC_B_TO_DRV_B_28_DP")
	)
	(arc
		(start 280.082752 -187.90285)
		(mid 279.891111 -187.440187)
		(end 279.428448 -187.248546)
		(width 0.127)
		(layer "B.Cu")
		(net "PHY_SCC_B_TO_DRV_B_28_DP")
	)
	(arc
		(start 160.620202 -14.844776)
		(mid 160.525011 -14.805347)
		(end 160.485582 -14.710156)
		(width 0.127)
		(layer "B.Cu")
		(net "PHY_SCC_B_TO_DRV_B_28_DP")
	)
	(segment
		(start 159.405574 -15.136876)
		(end 160.326578 -15.136876)
		(width 0.127)
		(layer "F.Cu")
		(net "PHY_SCC_B_TO_DRV_B_28_DN")
	)
	(segment
		(start 158.942786 -15.219426)
		(end 159.323024 -15.219426)
		(width 0.127)
		(layer "F.Cu")
		(net "PHY_SCC_B_TO_DRV_B_28_DN")
	)
	(segment
		(start 159.323024 -15.219426)
		(end 159.405574 -15.136876)
		(width 0.127)
		(layer "F.Cu")
		(net "PHY_SCC_B_TO_DRV_B_28_DN")
	)
	(segment
		(start 160.485582 -15.29588)
		(end 160.485582 -15.562326)
		(width 0.127)
		(layer "F.Cu")
		(net "PHY_SCC_B_TO_DRV_B_28_DN")
	)
	(arc
		(start 160.326578 -15.136876)
		(mid 160.439011 -15.183447)
		(end 160.485582 -15.29588)
		(width 0.127)
		(layer "F.Cu")
		(net "PHY_SCC_B_TO_DRV_B_28_DN")
	)
	(segment
		(start 180.234844 -100.0125)
		(end 163.67506 -22.103588)
		(width 0.127)
		(layer "B.Cu")
		(net "PHY_SCC_B_TO_DRV_B_28_DN")
	)
	(segment
		(start 161.274506 -15.136876)
		(end 160.629854 -15.136876)
		(width 0.127)
		(layer "B.Cu")
		(net "PHY_SCC_B_TO_DRV_B_28_DN")
	)
	(segment
		(start 163.453318 -21.060156)
		(end 163.27247 -20.942808)
		(width 0.127)
		(layer "B.Cu")
		(net "PHY_SCC_B_TO_DRV_B_28_DN")
	)
	(segment
		(start 162.462718 -16.400272)
		(end 161.870136 -15.48765)
		(width 0.127)
		(layer "B.Cu")
		(net "PHY_SCC_B_TO_DRV_B_28_DN")
	)
	(segment
		(start 163.231322 -20.016724)
		(end 163.050728 -19.899376)
		(width 0.127)
		(layer "B.Cu")
		(net "PHY_SCC_B_TO_DRV_B_28_DN")
	)
	(segment
		(start 163.494212 -21.98624)
		(end 163.414964 -21.613622)
		(width 0.127)
		(layer "B.Cu")
		(net "PHY_SCC_B_TO_DRV_B_28_DN")
	)
	(segment
		(start 163.67506 -22.103588)
		(end 163.494212 -21.98624)
		(width 0.127)
		(layer "B.Cu")
		(net "PHY_SCC_B_TO_DRV_B_28_DN")
	)
	(segment
		(start 163.31057 -20.389342)
		(end 163.231322 -20.016724)
		(width 0.127)
		(layer "B.Cu")
		(net "PHY_SCC_B_TO_DRV_B_28_DN")
	)
	(segment
		(start 252.246892 -158.856426)
		(end 193.7893 -120.887236)
		(width 0.127)
		(layer "B.Cu")
		(net "PHY_SCC_B_TO_DRV_B_28_DN")
	)
	(segment
		(start 279.790652 -188.08065)
		(end 279.790652 -187.90285)
		(width 0.127)
		(layer "B.Cu")
		(net "PHY_SCC_B_TO_DRV_B_28_DN")
	)
	(segment
		(start 162.749738 -18.483072)
		(end 162.867086 -18.302224)
		(width 0.127)
		(layer "B.Cu")
		(net "PHY_SCC_B_TO_DRV_B_28_DN")
	)
	(segment
		(start 163.088828 -19.34591)
		(end 163.00958 -18.973038)
		(width 0.127)
		(layer "B.Cu")
		(net "PHY_SCC_B_TO_DRV_B_28_DN")
	)
	(segment
		(start 163.27247 -20.942808)
		(end 163.193222 -20.57019)
		(width 0.127)
		(layer "B.Cu")
		(net "PHY_SCC_B_TO_DRV_B_28_DN")
	)
	(segment
		(start 162.97148 -19.526504)
		(end 163.088828 -19.34591)
		(width 0.127)
		(layer "B.Cu")
		(net "PHY_SCC_B_TO_DRV_B_28_DN")
	)
	(segment
		(start 276.651466 -187.540646)
		(end 274.7645 -187.139834)
		(width 0.127)
		(layer "B.Cu")
		(net "PHY_SCC_B_TO_DRV_B_28_DN")
	)
	(segment
		(start 163.414964 -21.613622)
		(end 163.532312 -21.432774)
		(width 0.127)
		(layer "B.Cu")
		(net "PHY_SCC_B_TO_DRV_B_28_DN")
	)
	(segment
		(start 163.050728 -19.899376)
		(end 162.97148 -19.526504)
		(width 0.127)
		(layer "B.Cu")
		(net "PHY_SCC_B_TO_DRV_B_28_DN")
	)
	(segment
		(start 279.236678 -188.294518)
		(end 279.576784 -188.294518)
		(width 0.127)
		(layer "B.Cu")
		(net "PHY_SCC_B_TO_DRV_B_28_DN")
	)
	(segment
		(start 161.356802 -15.154402)
		(end 161.274506 -15.136876)
		(width 0.127)
		(layer "B.Cu")
		(net "PHY_SCC_B_TO_DRV_B_28_DN")
	)
	(segment
		(start 162.867086 -18.302224)
		(end 162.462718 -16.400272)
		(width 0.127)
		(layer "B.Cu")
		(net "PHY_SCC_B_TO_DRV_B_28_DN")
	)
	(segment
		(start 193.7893 -120.887236)
		(end 180.234844 -100.0125)
		(width 0.127)
		(layer "B.Cu")
		(net "PHY_SCC_B_TO_DRV_B_28_DN")
	)
	(segment
		(start 274.7645 -187.139834)
		(end 267.589 -182.480204)
		(width 0.127)
		(layer "B.Cu")
		(net "PHY_SCC_B_TO_DRV_B_28_DN")
	)
	(segment
		(start 163.532312 -21.432774)
		(end 163.453318 -21.060156)
		(width 0.127)
		(layer "B.Cu")
		(net "PHY_SCC_B_TO_DRV_B_28_DN")
	)
	(segment
		(start 279.428448 -187.540646)
		(end 276.651466 -187.540646)
		(width 0.127)
		(layer "B.Cu")
		(net "PHY_SCC_B_TO_DRV_B_28_DN")
	)
	(segment
		(start 161.870136 -15.48765)
		(end 161.356802 -15.154402)
		(width 0.127)
		(layer "B.Cu")
		(net "PHY_SCC_B_TO_DRV_B_28_DN")
	)
	(segment
		(start 163.00958 -18.973038)
		(end 162.828732 -18.85569)
		(width 0.127)
		(layer "B.Cu")
		(net "PHY_SCC_B_TO_DRV_B_28_DN")
	)
	(segment
		(start 160.485582 -15.281148)
		(end 160.485582 -15.562326)
		(width 0.127)
		(layer "B.Cu")
		(net "PHY_SCC_B_TO_DRV_B_28_DN")
	)
	(segment
		(start 162.828732 -18.85569)
		(end 162.749738 -18.483072)
		(width 0.127)
		(layer "B.Cu")
		(net "PHY_SCC_B_TO_DRV_B_28_DN")
	)
	(segment
		(start 267.589 -182.480204)
		(end 252.246892 -158.856426)
		(width 0.127)
		(layer "B.Cu")
		(net "PHY_SCC_B_TO_DRV_B_28_DN")
	)
	(segment
		(start 163.193222 -20.57019)
		(end 163.31057 -20.389342)
		(width 0.127)
		(layer "B.Cu")
		(net "PHY_SCC_B_TO_DRV_B_28_DN")
	)
	(arc
		(start 160.629854 -15.136876)
		(mid 160.527838 -15.179132)
		(end 160.485582 -15.281148)
		(width 0.127)
		(layer "B.Cu")
		(net "PHY_SCC_B_TO_DRV_B_28_DN")
	)
	(arc
		(start 279.576784 -188.294518)
		(mid 279.728012 -188.231878)
		(end 279.790652 -188.08065)
		(width 0.127)
		(layer "B.Cu")
		(net "PHY_SCC_B_TO_DRV_B_28_DN")
	)
	(arc
		(start 279.790652 -187.90285)
		(mid 279.684565 -187.646733)
		(end 279.428448 -187.540646)
		(width 0.127)
		(layer "B.Cu")
		(net "PHY_SCC_B_TO_DRV_B_28_DN")
	)
	(segment
		(start 127.78867 -14.660626)
		(end 127.97282 -14.844776)
		(width 0.127)
		(layer "F.Cu")
		(net "PHY_SCC_B_TO_DRV_B_27_DP")
	)
	(segment
		(start 127.97282 -14.844776)
		(end 128.776476 -14.844776)
		(width 0.127)
		(layer "F.Cu")
		(net "PHY_SCC_B_TO_DRV_B_27_DP")
	)
	(segment
		(start 127.392684 -14.660626)
		(end 127.78867 -14.660626)
		(width 0.127)
		(layer "F.Cu")
		(net "PHY_SCC_B_TO_DRV_B_27_DP")
	)
	(segment
		(start 128.93548 -14.685772)
		(end 128.93548 -14.419326)
		(width 0.127)
		(layer "F.Cu")
		(net "PHY_SCC_B_TO_DRV_B_27_DP")
	)
	(arc
		(start 128.776476 -14.844776)
		(mid 128.888909 -14.798205)
		(end 128.93548 -14.685772)
		(width 0.127)
		(layer "F.Cu")
		(net "PHY_SCC_B_TO_DRV_B_27_DP")
	)
	(segment
		(start 266.789408 -183.688482)
		(end 251.174504 -159.64408)
		(width 0.127)
		(layer "B.Cu")
		(net "PHY_SCC_B_TO_DRV_B_27_DP")
	)
	(segment
		(start 129.733802 -14.844776)
		(end 129.0701 -14.844776)
		(width 0.127)
		(layer "B.Cu")
		(net "PHY_SCC_B_TO_DRV_B_27_DP")
	)
	(segment
		(start 279.082754 -189.880494)
		(end 279.082754 -189.702694)
		(width 0.127)
		(layer "B.Cu")
		(net "PHY_SCC_B_TO_DRV_B_27_DP")
	)
	(segment
		(start 279.636728 -190.094362)
		(end 279.296622 -190.094362)
		(width 0.127)
		(layer "B.Cu")
		(net "PHY_SCC_B_TO_DRV_B_27_DP")
	)
	(segment
		(start 165.99789 -104.325674)
		(end 143.002254 -68.914264)
		(width 0.127)
		(layer "B.Cu")
		(net "PHY_SCC_B_TO_DRV_B_27_DP")
	)
	(segment
		(start 143.002254 -68.914264)
		(end 132.098542 -17.613122)
		(width 0.127)
		(layer "B.Cu")
		(net "PHY_SCC_B_TO_DRV_B_27_DP")
	)
	(segment
		(start 276.6822 -189.04839)
		(end 274.24507 -188.53023)
		(width 0.127)
		(layer "B.Cu")
		(net "PHY_SCC_B_TO_DRV_B_27_DP")
	)
	(segment
		(start 128.93548 -14.710156)
		(end 128.93548 -14.419326)
		(width 0.127)
		(layer "B.Cu")
		(net "PHY_SCC_B_TO_DRV_B_27_DP")
	)
	(segment
		(start 130.011678 -14.903704)
		(end 129.733802 -14.844776)
		(width 0.127)
		(layer "B.Cu")
		(net "PHY_SCC_B_TO_DRV_B_27_DP")
	)
	(segment
		(start 278.42845 -189.04839)
		(end 276.6822 -189.04839)
		(width 0.127)
		(layer "B.Cu")
		(net "PHY_SCC_B_TO_DRV_B_27_DP")
	)
	(segment
		(start 274.24507 -188.53023)
		(end 266.789408 -183.688482)
		(width 0.127)
		(layer "B.Cu")
		(net "PHY_SCC_B_TO_DRV_B_27_DP")
	)
	(segment
		(start 132.098542 -17.613122)
		(end 130.576066 -15.269972)
		(width 0.127)
		(layer "B.Cu")
		(net "PHY_SCC_B_TO_DRV_B_27_DP")
	)
	(segment
		(start 251.174504 -159.64408)
		(end 165.99789 -104.325674)
		(width 0.127)
		(layer "B.Cu")
		(net "PHY_SCC_B_TO_DRV_B_27_DP")
	)
	(segment
		(start 130.576066 -15.269972)
		(end 130.011678 -14.903704)
		(width 0.127)
		(layer "B.Cu")
		(net "PHY_SCC_B_TO_DRV_B_27_DP")
	)
	(arc
		(start 129.0701 -14.844776)
		(mid 128.974909 -14.805347)
		(end 128.93548 -14.710156)
		(width 0.127)
		(layer "B.Cu")
		(net "PHY_SCC_B_TO_DRV_B_27_DP")
	)
	(arc
		(start 279.296622 -190.094362)
		(mid 279.145394 -190.031722)
		(end 279.082754 -189.880494)
		(width 0.127)
		(layer "B.Cu")
		(net "PHY_SCC_B_TO_DRV_B_27_DP")
	)
	(arc
		(start 279.082754 -189.702694)
		(mid 278.891113 -189.240031)
		(end 278.42845 -189.04839)
		(width 0.127)
		(layer "B.Cu")
		(net "PHY_SCC_B_TO_DRV_B_27_DP")
	)
	(segment
		(start 127.772922 -15.219426)
		(end 127.855472 -15.136876)
		(width 0.127)
		(layer "F.Cu")
		(net "PHY_SCC_B_TO_DRV_B_27_DN")
	)
	(segment
		(start 127.855472 -15.136876)
		(end 128.776476 -15.136876)
		(width 0.127)
		(layer "F.Cu")
		(net "PHY_SCC_B_TO_DRV_B_27_DN")
	)
	(segment
		(start 127.392684 -15.219426)
		(end 127.772922 -15.219426)
		(width 0.127)
		(layer "F.Cu")
		(net "PHY_SCC_B_TO_DRV_B_27_DN")
	)
	(segment
		(start 128.93548 -15.29588)
		(end 128.93548 -15.562326)
		(width 0.127)
		(layer "F.Cu")
		(net "PHY_SCC_B_TO_DRV_B_27_DN")
	)
	(arc
		(start 128.776476 -15.136876)
		(mid 128.888909 -15.183447)
		(end 128.93548 -15.29588)
		(width 0.127)
		(layer "F.Cu")
		(net "PHY_SCC_B_TO_DRV_B_27_DN")
	)
	(segment
		(start 276.651466 -189.34049)
		(end 274.131278 -188.804804)
		(width 0.127)
		(layer "B.Cu")
		(net "PHY_SCC_B_TO_DRV_B_27_DN")
	)
	(segment
		(start 146.08937 -74.484484)
		(end 145.881852 -74.164952)
		(width 0.127)
		(layer "B.Cu")
		(net "PHY_SCC_B_TO_DRV_B_27_DN")
	)
	(segment
		(start 145.508218 -73.589896)
		(end 145.3007 -73.270364)
		(width 0.127)
		(layer "B.Cu")
		(net "PHY_SCC_B_TO_DRV_B_27_DN")
	)
	(segment
		(start 146.30019 -74.529442)
		(end 146.08937 -74.484484)
		(width 0.127)
		(layer "B.Cu")
		(net "PHY_SCC_B_TO_DRV_B_27_DN")
	)
	(segment
		(start 146.881088 -75.42403)
		(end 146.670268 -75.379326)
		(width 0.127)
		(layer "B.Cu")
		(net "PHY_SCC_B_TO_DRV_B_27_DN")
	)
	(segment
		(start 146.46275 -75.059794)
		(end 146.507708 -74.848974)
		(width 0.127)
		(layer "B.Cu")
		(net "PHY_SCC_B_TO_DRV_B_27_DN")
	)
	(segment
		(start 128.93548 -15.281148)
		(end 128.93548 -15.562326)
		(width 0.127)
		(layer "B.Cu")
		(net "PHY_SCC_B_TO_DRV_B_27_DN")
	)
	(segment
		(start 145.3007 -73.270364)
		(end 145.345658 -73.059544)
		(width 0.127)
		(layer "B.Cu")
		(net "PHY_SCC_B_TO_DRV_B_27_DN")
	)
	(segment
		(start 146.670268 -75.379326)
		(end 146.46275 -75.059794)
		(width 0.127)
		(layer "B.Cu")
		(net "PHY_SCC_B_TO_DRV_B_27_DN")
	)
	(segment
		(start 147.25142 -76.273914)
		(end 147.043902 -75.954382)
		(width 0.127)
		(layer "B.Cu")
		(net "PHY_SCC_B_TO_DRV_B_27_DN")
	)
	(segment
		(start 145.881852 -74.164952)
		(end 145.926556 -73.954132)
		(width 0.127)
		(layer "B.Cu")
		(net "PHY_SCC_B_TO_DRV_B_27_DN")
	)
	(segment
		(start 145.926556 -73.954132)
		(end 145.719038 -73.6346)
		(width 0.127)
		(layer "B.Cu")
		(net "PHY_SCC_B_TO_DRV_B_27_DN")
	)
	(segment
		(start 266.57808 -183.89981)
		(end 250.963176 -159.855408)
		(width 0.127)
		(layer "B.Cu")
		(net "PHY_SCC_B_TO_DRV_B_27_DN")
	)
	(segment
		(start 146.507708 -74.848974)
		(end 146.30019 -74.529442)
		(width 0.127)
		(layer "B.Cu")
		(net "PHY_SCC_B_TO_DRV_B_27_DN")
	)
	(segment
		(start 147.088606 -75.743562)
		(end 146.881088 -75.42403)
		(width 0.127)
		(layer "B.Cu")
		(net "PHY_SCC_B_TO_DRV_B_27_DN")
	)
	(segment
		(start 145.345658 -73.059544)
		(end 142.72768 -69.028056)
		(width 0.127)
		(layer "B.Cu")
		(net "PHY_SCC_B_TO_DRV_B_27_DN")
	)
	(segment
		(start 129.897886 -15.178278)
		(end 129.703068 -15.136876)
		(width 0.127)
		(layer "B.Cu")
		(net "PHY_SCC_B_TO_DRV_B_27_DN")
	)
	(segment
		(start 131.823968 -17.726914)
		(end 130.364992 -15.4813)
		(width 0.127)
		(layer "B.Cu")
		(net "PHY_SCC_B_TO_DRV_B_27_DN")
	)
	(segment
		(start 129.703068 -15.136876)
		(end 129.079752 -15.136876)
		(width 0.127)
		(layer "B.Cu")
		(net "PHY_SCC_B_TO_DRV_B_27_DN")
	)
	(segment
		(start 147.46224 -76.318618)
		(end 147.25142 -76.273914)
		(width 0.127)
		(layer "B.Cu")
		(net "PHY_SCC_B_TO_DRV_B_27_DN")
	)
	(segment
		(start 278.790654 -189.880494)
		(end 278.790654 -189.702694)
		(width 0.127)
		(layer "B.Cu")
		(net "PHY_SCC_B_TO_DRV_B_27_DN")
	)
	(segment
		(start 145.719038 -73.6346)
		(end 145.508218 -73.589896)
		(width 0.127)
		(layer "B.Cu")
		(net "PHY_SCC_B_TO_DRV_B_27_DN")
	)
	(segment
		(start 274.131278 -188.804804)
		(end 266.57808 -183.89981)
		(width 0.127)
		(layer "B.Cu")
		(net "PHY_SCC_B_TO_DRV_B_27_DN")
	)
	(segment
		(start 165.786562 -104.537002)
		(end 147.46224 -76.318618)
		(width 0.127)
		(layer "B.Cu")
		(net "PHY_SCC_B_TO_DRV_B_27_DN")
	)
	(segment
		(start 250.963176 -159.855408)
		(end 165.786562 -104.537002)
		(width 0.127)
		(layer "B.Cu")
		(net "PHY_SCC_B_TO_DRV_B_27_DN")
	)
	(segment
		(start 142.72768 -69.028056)
		(end 131.823968 -17.726914)
		(width 0.127)
		(layer "B.Cu")
		(net "PHY_SCC_B_TO_DRV_B_27_DN")
	)
	(segment
		(start 278.23668 -190.094362)
		(end 278.576786 -190.094362)
		(width 0.127)
		(layer "B.Cu")
		(net "PHY_SCC_B_TO_DRV_B_27_DN")
	)
	(segment
		(start 130.364992 -15.4813)
		(end 129.897886 -15.178278)
		(width 0.127)
		(layer "B.Cu")
		(net "PHY_SCC_B_TO_DRV_B_27_DN")
	)
	(segment
		(start 278.42845 -189.34049)
		(end 276.651466 -189.34049)
		(width 0.127)
		(layer "B.Cu")
		(net "PHY_SCC_B_TO_DRV_B_27_DN")
	)
	(segment
		(start 147.043902 -75.954382)
		(end 147.088606 -75.743562)
		(width 0.127)
		(layer "B.Cu")
		(net "PHY_SCC_B_TO_DRV_B_27_DN")
	)
	(arc
		(start 129.079752 -15.136876)
		(mid 128.977736 -15.179132)
		(end 128.93548 -15.281148)
		(width 0.127)
		(layer "B.Cu")
		(net "PHY_SCC_B_TO_DRV_B_27_DN")
	)
	(arc
		(start 278.790654 -189.702694)
		(mid 278.684567 -189.446577)
		(end 278.42845 -189.34049)
		(width 0.127)
		(layer "B.Cu")
		(net "PHY_SCC_B_TO_DRV_B_27_DN")
	)
	(arc
		(start 278.576786 -190.094362)
		(mid 278.728014 -190.031722)
		(end 278.790654 -189.880494)
		(width 0.127)
		(layer "B.Cu")
		(net "PHY_SCC_B_TO_DRV_B_27_DN")
	)
	(segment
		(start 96.238822 -14.660626)
		(end 96.422972 -14.844776)
		(width 0.127)
		(layer "F.Cu")
		(net "PHY_SCC_B_TO_DRV_B_26_DP")
	)
	(segment
		(start 97.385632 -14.685772)
		(end 97.385632 -14.419326)
		(width 0.127)
		(layer "F.Cu")
		(net "PHY_SCC_B_TO_DRV_B_26_DP")
	)
	(segment
		(start 96.422972 -14.844776)
		(end 97.226628 -14.844776)
		(width 0.127)
		(layer "F.Cu")
		(net "PHY_SCC_B_TO_DRV_B_26_DP")
	)
	(segment
		(start 95.842836 -14.660626)
		(end 96.238822 -14.660626)
		(width 0.127)
		(layer "F.Cu")
		(net "PHY_SCC_B_TO_DRV_B_26_DP")
	)
	(arc
		(start 97.226628 -14.844776)
		(mid 97.339061 -14.798205)
		(end 97.385632 -14.685772)
		(width 0.127)
		(layer "F.Cu")
		(net "PHY_SCC_B_TO_DRV_B_26_DP")
	)
	(segment
		(start 264.949178 -184.528968)
		(end 249.188224 -160.26003)
		(width 0.127)
		(layer "B.Cu")
		(net "PHY_SCC_B_TO_DRV_B_26_DP")
	)
	(segment
		(start 99.326446 -15.370556)
		(end 98.652838 -14.932914)
		(width 0.127)
		(layer "B.Cu")
		(net "PHY_SCC_B_TO_DRV_B_26_DP")
	)
	(segment
		(start 280.636726 -191.89446)
		(end 280.29662 -191.89446)
		(width 0.127)
		(layer "B.Cu")
		(net "PHY_SCC_B_TO_DRV_B_26_DP")
	)
	(segment
		(start 102.479856 -29.426662)
		(end 99.572318 -15.749524)
		(width 0.127)
		(layer "B.Cu")
		(net "PHY_SCC_B_TO_DRV_B_26_DP")
	)
	(segment
		(start 98.652838 -14.932914)
		(end 98.237548 -14.844776)
		(width 0.127)
		(layer "B.Cu")
		(net "PHY_SCC_B_TO_DRV_B_26_DP")
	)
	(segment
		(start 276.6822 -190.848488)
		(end 273.706336 -190.216028)
		(width 0.127)
		(layer "B.Cu")
		(net "PHY_SCC_B_TO_DRV_B_26_DP")
	)
	(segment
		(start 99.572318 -15.749524)
		(end 99.326446 -15.370556)
		(width 0.127)
		(layer "B.Cu")
		(net "PHY_SCC_B_TO_DRV_B_26_DP")
	)
	(segment
		(start 279.428448 -190.848488)
		(end 276.6822 -190.848488)
		(width 0.127)
		(layer "B.Cu")
		(net "PHY_SCC_B_TO_DRV_B_26_DP")
	)
	(segment
		(start 273.706336 -190.216028)
		(end 264.949178 -184.528968)
		(width 0.127)
		(layer "B.Cu")
		(net "PHY_SCC_B_TO_DRV_B_26_DP")
	)
	(segment
		(start 280.082752 -191.680592)
		(end 280.082752 -191.502792)
		(width 0.127)
		(layer "B.Cu")
		(net "PHY_SCC_B_TO_DRV_B_26_DP")
	)
	(segment
		(start 97.385632 -14.710156)
		(end 97.385632 -14.419326)
		(width 0.127)
		(layer "B.Cu")
		(net "PHY_SCC_B_TO_DRV_B_26_DP")
	)
	(segment
		(start 249.188224 -160.26003)
		(end 142.40764 -90.910664)
		(width 0.127)
		(layer "B.Cu")
		(net "PHY_SCC_B_TO_DRV_B_26_DP")
	)
	(segment
		(start 142.40764 -90.910664)
		(end 102.479856 -29.426662)
		(width 0.127)
		(layer "B.Cu")
		(net "PHY_SCC_B_TO_DRV_B_26_DP")
	)
	(segment
		(start 98.237548 -14.844776)
		(end 97.520252 -14.844776)
		(width 0.127)
		(layer "B.Cu")
		(net "PHY_SCC_B_TO_DRV_B_26_DP")
	)
	(arc
		(start 280.082752 -191.502792)
		(mid 279.891111 -191.040129)
		(end 279.428448 -190.848488)
		(width 0.127)
		(layer "B.Cu")
		(net "PHY_SCC_B_TO_DRV_B_26_DP")
	)
	(arc
		(start 280.29662 -191.89446)
		(mid 280.145392 -191.83182)
		(end 280.082752 -191.680592)
		(width 0.127)
		(layer "B.Cu")
		(net "PHY_SCC_B_TO_DRV_B_26_DP")
	)
	(arc
		(start 97.520252 -14.844776)
		(mid 97.425061 -14.805347)
		(end 97.385632 -14.710156)
		(width 0.127)
		(layer "B.Cu")
		(net "PHY_SCC_B_TO_DRV_B_26_DP")
	)
	(segment
		(start 96.305624 -15.136876)
		(end 97.226628 -15.136876)
		(width 0.127)
		(layer "F.Cu")
		(net "PHY_SCC_B_TO_DRV_B_26_DN")
	)
	(segment
		(start 96.223074 -15.219426)
		(end 96.305624 -15.136876)
		(width 0.127)
		(layer "F.Cu")
		(net "PHY_SCC_B_TO_DRV_B_26_DN")
	)
	(segment
		(start 95.842836 -15.219426)
		(end 96.223074 -15.219426)
		(width 0.127)
		(layer "F.Cu")
		(net "PHY_SCC_B_TO_DRV_B_26_DN")
	)
	(segment
		(start 97.385632 -15.29588)
		(end 97.385632 -15.562326)
		(width 0.127)
		(layer "F.Cu")
		(net "PHY_SCC_B_TO_DRV_B_26_DN")
	)
	(arc
		(start 97.226628 -15.136876)
		(mid 97.339061 -15.183447)
		(end 97.385632 -15.29588)
		(width 0.127)
		(layer "F.Cu")
		(net "PHY_SCC_B_TO_DRV_B_26_DN")
	)
	(segment
		(start 98.539046 -15.207488)
		(end 98.206814 -15.136876)
		(width 0.127)
		(layer "B.Cu")
		(net "PHY_SCC_B_TO_DRV_B_26_DN")
	)
	(segment
		(start 99.859084 -19.236944)
		(end 99.976432 -19.056096)
		(width 0.127)
		(layer "B.Cu")
		(net "PHY_SCC_B_TO_DRV_B_26_DN")
	)
	(segment
		(start 98.206814 -15.136876)
		(end 97.529904 -15.136876)
		(width 0.127)
		(layer "B.Cu")
		(net "PHY_SCC_B_TO_DRV_B_26_DN")
	)
	(segment
		(start 99.938332 -19.609562)
		(end 99.859084 -19.236944)
		(width 0.127)
		(layer "B.Cu")
		(net "PHY_SCC_B_TO_DRV_B_26_DN")
	)
	(segment
		(start 279.428448 -191.140588)
		(end 276.651466 -191.140588)
		(width 0.127)
		(layer "B.Cu")
		(net "PHY_SCC_B_TO_DRV_B_26_DN")
	)
	(segment
		(start 264.73785 -184.740296)
		(end 248.976896 -160.471358)
		(width 0.127)
		(layer "B.Cu")
		(net "PHY_SCC_B_TO_DRV_B_26_DN")
	)
	(segment
		(start 100.42017 -21.14296)
		(end 100.340922 -20.770342)
		(width 0.127)
		(layer "B.Cu")
		(net "PHY_SCC_B_TO_DRV_B_26_DN")
	)
	(segment
		(start 279.236678 -191.89446)
		(end 279.576784 -191.89446)
		(width 0.127)
		(layer "B.Cu")
		(net "PHY_SCC_B_TO_DRV_B_26_DN")
	)
	(segment
		(start 100.080826 -20.280376)
		(end 100.198428 -20.099528)
		(width 0.127)
		(layer "B.Cu")
		(net "PHY_SCC_B_TO_DRV_B_26_DN")
	)
	(segment
		(start 100.524564 -22.36724)
		(end 100.641912 -22.186646)
		(width 0.127)
		(layer "B.Cu")
		(net "PHY_SCC_B_TO_DRV_B_26_DN")
	)
	(segment
		(start 99.297744 -15.863062)
		(end 99.115118 -15.58163)
		(width 0.127)
		(layer "B.Cu")
		(net "PHY_SCC_B_TO_DRV_B_26_DN")
	)
	(segment
		(start 100.11918 -19.72691)
		(end 99.938332 -19.609562)
		(width 0.127)
		(layer "B.Cu")
		(net "PHY_SCC_B_TO_DRV_B_26_DN")
	)
	(segment
		(start 100.641912 -22.186646)
		(end 100.562664 -21.813774)
		(width 0.127)
		(layer "B.Cu")
		(net "PHY_SCC_B_TO_DRV_B_26_DN")
	)
	(segment
		(start 102.205282 -29.540454)
		(end 100.78466 -22.85746)
		(width 0.127)
		(layer "B.Cu")
		(net "PHY_SCC_B_TO_DRV_B_26_DN")
	)
	(segment
		(start 99.976432 -19.056096)
		(end 99.297744 -15.863062)
		(width 0.127)
		(layer "B.Cu")
		(net "PHY_SCC_B_TO_DRV_B_26_DN")
	)
	(segment
		(start 100.78466 -22.85746)
		(end 100.603812 -22.739858)
		(width 0.127)
		(layer "B.Cu")
		(net "PHY_SCC_B_TO_DRV_B_26_DN")
	)
	(segment
		(start 100.302822 -21.323808)
		(end 100.42017 -21.14296)
		(width 0.127)
		(layer "B.Cu")
		(net "PHY_SCC_B_TO_DRV_B_26_DN")
	)
	(segment
		(start 279.790652 -191.680592)
		(end 279.790652 -191.502792)
		(width 0.127)
		(layer "B.Cu")
		(net "PHY_SCC_B_TO_DRV_B_26_DN")
	)
	(segment
		(start 100.340922 -20.770342)
		(end 100.160074 -20.652994)
		(width 0.127)
		(layer "B.Cu")
		(net "PHY_SCC_B_TO_DRV_B_26_DN")
	)
	(segment
		(start 248.976896 -160.471358)
		(end 142.196312 -91.121992)
		(width 0.127)
		(layer "B.Cu")
		(net "PHY_SCC_B_TO_DRV_B_26_DN")
	)
	(segment
		(start 276.651466 -191.140588)
		(end 273.592544 -190.490602)
		(width 0.127)
		(layer "B.Cu")
		(net "PHY_SCC_B_TO_DRV_B_26_DN")
	)
	(segment
		(start 97.385632 -15.281148)
		(end 97.385632 -15.562326)
		(width 0.127)
		(layer "B.Cu")
		(net "PHY_SCC_B_TO_DRV_B_26_DN")
	)
	(segment
		(start 100.38207 -21.696426)
		(end 100.302822 -21.323808)
		(width 0.127)
		(layer "B.Cu")
		(net "PHY_SCC_B_TO_DRV_B_26_DN")
	)
	(segment
		(start 273.592544 -190.490602)
		(end 264.73785 -184.740296)
		(width 0.127)
		(layer "B.Cu")
		(net "PHY_SCC_B_TO_DRV_B_26_DN")
	)
	(segment
		(start 100.603812 -22.739858)
		(end 100.524564 -22.36724)
		(width 0.127)
		(layer "B.Cu")
		(net "PHY_SCC_B_TO_DRV_B_26_DN")
	)
	(segment
		(start 99.115118 -15.58163)
		(end 98.539046 -15.207488)
		(width 0.127)
		(layer "B.Cu")
		(net "PHY_SCC_B_TO_DRV_B_26_DN")
	)
	(segment
		(start 100.198428 -20.099528)
		(end 100.11918 -19.72691)
		(width 0.127)
		(layer "B.Cu")
		(net "PHY_SCC_B_TO_DRV_B_26_DN")
	)
	(segment
		(start 100.160074 -20.652994)
		(end 100.080826 -20.280376)
		(width 0.127)
		(layer "B.Cu")
		(net "PHY_SCC_B_TO_DRV_B_26_DN")
	)
	(segment
		(start 142.196312 -91.121992)
		(end 102.205282 -29.540454)
		(width 0.127)
		(layer "B.Cu")
		(net "PHY_SCC_B_TO_DRV_B_26_DN")
	)
	(segment
		(start 100.562664 -21.813774)
		(end 100.38207 -21.696426)
		(width 0.127)
		(layer "B.Cu")
		(net "PHY_SCC_B_TO_DRV_B_26_DN")
	)
	(arc
		(start 279.790652 -191.502792)
		(mid 279.684565 -191.246675)
		(end 279.428448 -191.140588)
		(width 0.127)
		(layer "B.Cu")
		(net "PHY_SCC_B_TO_DRV_B_26_DN")
	)
	(arc
		(start 279.576784 -191.89446)
		(mid 279.728012 -191.83182)
		(end 279.790652 -191.680592)
		(width 0.127)
		(layer "B.Cu")
		(net "PHY_SCC_B_TO_DRV_B_26_DN")
	)
	(arc
		(start 97.529904 -15.136876)
		(mid 97.427888 -15.179132)
		(end 97.385632 -15.281148)
		(width 0.127)
		(layer "B.Cu")
		(net "PHY_SCC_B_TO_DRV_B_26_DN")
	)
	(segment
		(start 64.87287 -14.844776)
		(end 65.676526 -14.844776)
		(width 0.127)
		(layer "F.Cu")
		(net "PHY_SCC_B_TO_DRV_B_25_DP")
	)
	(segment
		(start 64.68872 -14.660626)
		(end 64.87287 -14.844776)
		(width 0.127)
		(layer "F.Cu")
		(net "PHY_SCC_B_TO_DRV_B_25_DP")
	)
	(segment
		(start 65.83553 -14.685772)
		(end 65.83553 -14.419326)
		(width 0.127)
		(layer "F.Cu")
		(net "PHY_SCC_B_TO_DRV_B_25_DP")
	)
	(segment
		(start 64.292734 -14.660626)
		(end 64.68872 -14.660626)
		(width 0.127)
		(layer "F.Cu")
		(net "PHY_SCC_B_TO_DRV_B_25_DP")
	)
	(arc
		(start 65.676526 -14.844776)
		(mid 65.788959 -14.798205)
		(end 65.83553 -14.685772)
		(width 0.127)
		(layer "F.Cu")
		(net "PHY_SCC_B_TO_DRV_B_25_DP")
	)
	(segment
		(start 68.200778 -15.19047)
		(end 66.563494 -14.844776)
		(width 0.127)
		(layer "B.Cu")
		(net "PHY_SCC_B_TO_DRV_B_25_DP")
	)
	(segment
		(start 103.357172 -38.011862)
		(end 68.200778 -15.19047)
		(width 0.127)
		(layer "B.Cu")
		(net "PHY_SCC_B_TO_DRV_B_25_DP")
	)
	(segment
		(start 273.5834 -191.989964)
		(end 263.847834 -185.667396)
		(width 0.127)
		(layer "B.Cu")
		(net "PHY_SCC_B_TO_DRV_B_25_DP")
	)
	(segment
		(start 136.41705 -88.91905)
		(end 103.357172 -38.011862)
		(width 0.127)
		(layer "B.Cu")
		(net "PHY_SCC_B_TO_DRV_B_25_DP")
	)
	(segment
		(start 276.6822 -192.648586)
		(end 273.5834 -191.989964)
		(width 0.127)
		(layer "B.Cu")
		(net "PHY_SCC_B_TO_DRV_B_25_DP")
	)
	(segment
		(start 248.134632 -161.471864)
		(end 136.41705 -88.91905)
		(width 0.127)
		(layer "B.Cu")
		(net "PHY_SCC_B_TO_DRV_B_25_DP")
	)
	(segment
		(start 278.42845 -192.648586)
		(end 276.6822 -192.648586)
		(width 0.127)
		(layer "B.Cu")
		(net "PHY_SCC_B_TO_DRV_B_25_DP")
	)
	(segment
		(start 65.83553 -14.710156)
		(end 65.83553 -14.419326)
		(width 0.127)
		(layer "B.Cu")
		(net "PHY_SCC_B_TO_DRV_B_25_DP")
	)
	(segment
		(start 66.563494 -14.844776)
		(end 65.97015 -14.844776)
		(width 0.127)
		(layer "B.Cu")
		(net "PHY_SCC_B_TO_DRV_B_25_DP")
	)
	(segment
		(start 279.082754 -193.48069)
		(end 279.082754 -193.30289)
		(width 0.127)
		(layer "B.Cu")
		(net "PHY_SCC_B_TO_DRV_B_25_DP")
	)
	(segment
		(start 279.636728 -193.694558)
		(end 279.296622 -193.694558)
		(width 0.127)
		(layer "B.Cu")
		(net "PHY_SCC_B_TO_DRV_B_25_DP")
	)
	(segment
		(start 263.847834 -185.667396)
		(end 248.134632 -161.471864)
		(width 0.127)
		(layer "B.Cu")
		(net "PHY_SCC_B_TO_DRV_B_25_DP")
	)
	(arc
		(start 279.082754 -193.30289)
		(mid 278.891113 -192.840227)
		(end 278.42845 -192.648586)
		(width 0.127)
		(layer "B.Cu")
		(net "PHY_SCC_B_TO_DRV_B_25_DP")
	)
	(arc
		(start 65.97015 -14.844776)
		(mid 65.874959 -14.805347)
		(end 65.83553 -14.710156)
		(width 0.127)
		(layer "B.Cu")
		(net "PHY_SCC_B_TO_DRV_B_25_DP")
	)
	(arc
		(start 279.296622 -193.694558)
		(mid 279.145394 -193.631918)
		(end 279.082754 -193.48069)
		(width 0.127)
		(layer "B.Cu")
		(net "PHY_SCC_B_TO_DRV_B_25_DP")
	)
	(segment
		(start 64.672972 -15.219426)
		(end 64.755522 -15.136876)
		(width 0.127)
		(layer "F.Cu")
		(net "PHY_SCC_B_TO_DRV_B_25_DN")
	)
	(segment
		(start 65.83553 -15.29588)
		(end 65.83553 -15.562326)
		(width 0.127)
		(layer "F.Cu")
		(net "PHY_SCC_B_TO_DRV_B_25_DN")
	)
	(segment
		(start 64.292734 -15.219426)
		(end 64.672972 -15.219426)
		(width 0.127)
		(layer "F.Cu")
		(net "PHY_SCC_B_TO_DRV_B_25_DN")
	)
	(segment
		(start 64.755522 -15.136876)
		(end 65.676526 -15.136876)
		(width 0.127)
		(layer "F.Cu")
		(net "PHY_SCC_B_TO_DRV_B_25_DN")
	)
	(arc
		(start 65.676526 -15.136876)
		(mid 65.788959 -15.183447)
		(end 65.83553 -15.29588)
		(width 0.127)
		(layer "F.Cu")
		(net "PHY_SCC_B_TO_DRV_B_25_DN")
	)
	(segment
		(start 278.790654 -193.48069)
		(end 278.790654 -193.30289)
		(width 0.127)
		(layer "B.Cu")
		(net "PHY_SCC_B_TO_DRV_B_25_DN")
	)
	(segment
		(start 247.923304 -161.683192)
		(end 136.205722 -89.130378)
		(width 0.127)
		(layer "B.Cu")
		(net "PHY_SCC_B_TO_DRV_B_25_DN")
	)
	(segment
		(start 132.453888 -83.633056)
		(end 132.246624 -83.313524)
		(width 0.127)
		(layer "B.Cu")
		(net "PHY_SCC_B_TO_DRV_B_25_DN")
	)
	(segment
		(start 68.08724 -15.465044)
		(end 66.53276 -15.136876)
		(width 0.127)
		(layer "B.Cu")
		(net "PHY_SCC_B_TO_DRV_B_25_DN")
	)
	(segment
		(start 136.205722 -89.130378)
		(end 132.664708 -83.67776)
		(width 0.127)
		(layer "B.Cu")
		(net "PHY_SCC_B_TO_DRV_B_25_DN")
	)
	(segment
		(start 131.87299 -82.738468)
		(end 131.665472 -82.418936)
		(width 0.127)
		(layer "B.Cu")
		(net "PHY_SCC_B_TO_DRV_B_25_DN")
	)
	(segment
		(start 130.71094 -80.949038)
		(end 130.503422 -80.629506)
		(width 0.127)
		(layer "B.Cu")
		(net "PHY_SCC_B_TO_DRV_B_25_DN")
	)
	(segment
		(start 278.42845 -192.940686)
		(end 276.651466 -192.940686)
		(width 0.127)
		(layer "B.Cu")
		(net "PHY_SCC_B_TO_DRV_B_25_DN")
	)
	(segment
		(start 131.292092 -81.843626)
		(end 131.084574 -81.524094)
		(width 0.127)
		(layer "B.Cu")
		(net "PHY_SCC_B_TO_DRV_B_25_DN")
	)
	(segment
		(start 65.83553 -15.281148)
		(end 65.83553 -15.562326)
		(width 0.127)
		(layer "B.Cu")
		(net "PHY_SCC_B_TO_DRV_B_25_DN")
	)
	(segment
		(start 130.548126 -80.418686)
		(end 103.145844 -38.22319)
		(width 0.127)
		(layer "B.Cu")
		(net "PHY_SCC_B_TO_DRV_B_25_DN")
	)
	(segment
		(start 273.469608 -192.264538)
		(end 263.636506 -185.878724)
		(width 0.127)
		(layer "B.Cu")
		(net "PHY_SCC_B_TO_DRV_B_25_DN")
	)
	(segment
		(start 132.664708 -83.67776)
		(end 132.453888 -83.633056)
		(width 0.127)
		(layer "B.Cu")
		(net "PHY_SCC_B_TO_DRV_B_25_DN")
	)
	(segment
		(start 66.53276 -15.136876)
		(end 65.979802 -15.136876)
		(width 0.127)
		(layer "B.Cu")
		(net "PHY_SCC_B_TO_DRV_B_25_DN")
	)
	(segment
		(start 276.651466 -192.940686)
		(end 273.469608 -192.264538)
		(width 0.127)
		(layer "B.Cu")
		(net "PHY_SCC_B_TO_DRV_B_25_DN")
	)
	(segment
		(start 131.665472 -82.418936)
		(end 131.710176 -82.208116)
		(width 0.127)
		(layer "B.Cu")
		(net "PHY_SCC_B_TO_DRV_B_25_DN")
	)
	(segment
		(start 130.92176 -80.993742)
		(end 130.71094 -80.949038)
		(width 0.127)
		(layer "B.Cu")
		(net "PHY_SCC_B_TO_DRV_B_25_DN")
	)
	(segment
		(start 131.710176 -82.208116)
		(end 131.502658 -81.888584)
		(width 0.127)
		(layer "B.Cu")
		(net "PHY_SCC_B_TO_DRV_B_25_DN")
	)
	(segment
		(start 103.145844 -38.22319)
		(end 68.08724 -15.465044)
		(width 0.127)
		(layer "B.Cu")
		(net "PHY_SCC_B_TO_DRV_B_25_DN")
	)
	(segment
		(start 263.636506 -185.878724)
		(end 247.923304 -161.683192)
		(width 0.127)
		(layer "B.Cu")
		(net "PHY_SCC_B_TO_DRV_B_25_DN")
	)
	(segment
		(start 131.502658 -81.888584)
		(end 131.292092 -81.843626)
		(width 0.127)
		(layer "B.Cu")
		(net "PHY_SCC_B_TO_DRV_B_25_DN")
	)
	(segment
		(start 132.291328 -83.102704)
		(end 132.08381 -82.783172)
		(width 0.127)
		(layer "B.Cu")
		(net "PHY_SCC_B_TO_DRV_B_25_DN")
	)
	(segment
		(start 131.129278 -81.313274)
		(end 130.92176 -80.993742)
		(width 0.127)
		(layer "B.Cu")
		(net "PHY_SCC_B_TO_DRV_B_25_DN")
	)
	(segment
		(start 131.084574 -81.524094)
		(end 131.129278 -81.313274)
		(width 0.127)
		(layer "B.Cu")
		(net "PHY_SCC_B_TO_DRV_B_25_DN")
	)
	(segment
		(start 132.08381 -82.783172)
		(end 131.87299 -82.738468)
		(width 0.127)
		(layer "B.Cu")
		(net "PHY_SCC_B_TO_DRV_B_25_DN")
	)
	(segment
		(start 278.23668 -193.694558)
		(end 278.576786 -193.694558)
		(width 0.127)
		(layer "B.Cu")
		(net "PHY_SCC_B_TO_DRV_B_25_DN")
	)
	(segment
		(start 132.246624 -83.313524)
		(end 132.291328 -83.102704)
		(width 0.127)
		(layer "B.Cu")
		(net "PHY_SCC_B_TO_DRV_B_25_DN")
	)
	(segment
		(start 130.503422 -80.629506)
		(end 130.548126 -80.418686)
		(width 0.127)
		(layer "B.Cu")
		(net "PHY_SCC_B_TO_DRV_B_25_DN")
	)
	(arc
		(start 278.576786 -193.694558)
		(mid 278.728014 -193.631918)
		(end 278.790654 -193.48069)
		(width 0.127)
		(layer "B.Cu")
		(net "PHY_SCC_B_TO_DRV_B_25_DN")
	)
	(arc
		(start 65.979802 -15.136876)
		(mid 65.877786 -15.179132)
		(end 65.83553 -15.281148)
		(width 0.127)
		(layer "B.Cu")
		(net "PHY_SCC_B_TO_DRV_B_25_DN")
	)
	(arc
		(start 278.790654 -193.30289)
		(mid 278.684567 -193.046773)
		(end 278.42845 -192.940686)
		(width 0.127)
		(layer "B.Cu")
		(net "PHY_SCC_B_TO_DRV_B_25_DN")
	)
	(segment
		(start 33.138872 -14.660626)
		(end 33.323022 -14.844776)
		(width 0.127)
		(layer "F.Cu")
		(net "PHY_SCC_B_TO_DRV_B_24_DP")
	)
	(segment
		(start 33.323022 -14.844776)
		(end 34.126678 -14.844776)
		(width 0.127)
		(layer "F.Cu")
		(net "PHY_SCC_B_TO_DRV_B_24_DP")
	)
	(segment
		(start 34.285682 -14.685772)
		(end 34.285682 -14.419326)
		(width 0.127)
		(layer "F.Cu")
		(net "PHY_SCC_B_TO_DRV_B_24_DP")
	)
	(segment
		(start 32.742886 -14.660626)
		(end 33.138872 -14.660626)
		(width 0.127)
		(layer "F.Cu")
		(net "PHY_SCC_B_TO_DRV_B_24_DP")
	)
	(arc
		(start 34.126678 -14.844776)
		(mid 34.239111 -14.798205)
		(end 34.285682 -14.685772)
		(width 0.127)
		(layer "F.Cu")
		(net "PHY_SCC_B_TO_DRV_B_24_DP")
	)
	(segment
		(start 34.285682 -14.710156)
		(end 34.285682 -14.419326)
		(width 0.127)
		(layer "B.Cu")
		(net "PHY_SCC_B_TO_DRV_B_24_DP")
	)
	(segment
		(start 279.428448 -194.44843)
		(end 276.6822 -194.44843)
		(width 0.127)
		(layer "B.Cu")
		(net "PHY_SCC_B_TO_DRV_B_24_DP")
	)
	(segment
		(start 49.965356 -24.984202)
		(end 37.706046 -17.021556)
		(width 0.127)
		(layer "B.Cu")
		(net "PHY_SCC_B_TO_DRV_B_24_DP")
	)
	(segment
		(start 111.128302 -56.388254)
		(end 68.998846 -29.029406)
		(width 0.127)
		(layer "B.Cu")
		(net "PHY_SCC_B_TO_DRV_B_24_DP")
	)
	(segment
		(start 246.383048 -162.25774)
		(end 131.38023 -87.573104)
		(width 0.127)
		(layer "B.Cu")
		(net "PHY_SCC_B_TO_DRV_B_24_DP")
	)
	(segment
		(start 68.998846 -29.029406)
		(end 49.965356 -24.984202)
		(width 0.127)
		(layer "B.Cu")
		(net "PHY_SCC_B_TO_DRV_B_24_DP")
	)
	(segment
		(start 276.6822 -194.44843)
		(end 273.381724 -193.746882)
		(width 0.127)
		(layer "B.Cu")
		(net "PHY_SCC_B_TO_DRV_B_24_DP")
	)
	(segment
		(start 280.636726 -195.494402)
		(end 280.29662 -195.494402)
		(width 0.127)
		(layer "B.Cu")
		(net "PHY_SCC_B_TO_DRV_B_24_DP")
	)
	(segment
		(start 37.706046 -17.021556)
		(end 36.914582 -15.802864)
		(width 0.127)
		(layer "B.Cu")
		(net "PHY_SCC_B_TO_DRV_B_24_DP")
	)
	(segment
		(start 273.381724 -193.746882)
		(end 262.056626 -186.392058)
		(width 0.127)
		(layer "B.Cu")
		(net "PHY_SCC_B_TO_DRV_B_24_DP")
	)
	(segment
		(start 131.38023 -87.573104)
		(end 111.128302 -56.388254)
		(width 0.127)
		(layer "B.Cu")
		(net "PHY_SCC_B_TO_DRV_B_24_DP")
	)
	(segment
		(start 35.561778 -14.924278)
		(end 35.188144 -14.844776)
		(width 0.127)
		(layer "B.Cu")
		(net "PHY_SCC_B_TO_DRV_B_24_DP")
	)
	(segment
		(start 35.188144 -14.844776)
		(end 34.420302 -14.844776)
		(width 0.127)
		(layer "B.Cu")
		(net "PHY_SCC_B_TO_DRV_B_24_DP")
	)
	(segment
		(start 280.082752 -195.280534)
		(end 280.082752 -195.102734)
		(width 0.127)
		(layer "B.Cu")
		(net "PHY_SCC_B_TO_DRV_B_24_DP")
	)
	(segment
		(start 262.056626 -186.392058)
		(end 246.383048 -162.25774)
		(width 0.127)
		(layer "B.Cu")
		(net "PHY_SCC_B_TO_DRV_B_24_DP")
	)
	(segment
		(start 36.914582 -15.802864)
		(end 35.561778 -14.924278)
		(width 0.127)
		(layer "B.Cu")
		(net "PHY_SCC_B_TO_DRV_B_24_DP")
	)
	(arc
		(start 34.420302 -14.844776)
		(mid 34.325111 -14.805347)
		(end 34.285682 -14.710156)
		(width 0.127)
		(layer "B.Cu")
		(net "PHY_SCC_B_TO_DRV_B_24_DP")
	)
	(arc
		(start 280.29662 -195.494402)
		(mid 280.145392 -195.431762)
		(end 280.082752 -195.280534)
		(width 0.127)
		(layer "B.Cu")
		(net "PHY_SCC_B_TO_DRV_B_24_DP")
	)
	(arc
		(start 280.082752 -195.102734)
		(mid 279.891111 -194.640071)
		(end 279.428448 -194.44843)
		(width 0.127)
		(layer "B.Cu")
		(net "PHY_SCC_B_TO_DRV_B_24_DP")
	)
	(segment
		(start 32.742886 -15.219426)
		(end 33.123124 -15.219426)
		(width 0.127)
		(layer "F.Cu")
		(net "PHY_SCC_B_TO_DRV_B_24_DN")
	)
	(segment
		(start 33.205674 -15.136876)
		(end 34.126678 -15.136876)
		(width 0.127)
		(layer "F.Cu")
		(net "PHY_SCC_B_TO_DRV_B_24_DN")
	)
	(segment
		(start 33.123124 -15.219426)
		(end 33.205674 -15.136876)
		(width 0.127)
		(layer "F.Cu")
		(net "PHY_SCC_B_TO_DRV_B_24_DN")
	)
	(segment
		(start 34.285682 -15.29588)
		(end 34.285682 -15.562326)
		(width 0.127)
		(layer "F.Cu")
		(net "PHY_SCC_B_TO_DRV_B_24_DN")
	)
	(arc
		(start 34.126678 -15.136876)
		(mid 34.239111 -15.183447)
		(end 34.285682 -15.29588)
		(width 0.127)
		(layer "F.Cu")
		(net "PHY_SCC_B_TO_DRV_B_24_DN")
	)
	(segment
		(start 279.428448 -194.74053)
		(end 276.651466 -194.74053)
		(width 0.127)
		(layer "B.Cu")
		(net "PHY_SCC_B_TO_DRV_B_24_DN")
	)
	(segment
		(start 38.369494 -17.982946)
		(end 38.32479 -17.772126)
		(width 0.127)
		(layer "B.Cu")
		(net "PHY_SCC_B_TO_DRV_B_24_DN")
	)
	(segment
		(start 276.651466 -194.74053)
		(end 273.267932 -194.021456)
		(width 0.127)
		(layer "B.Cu")
		(net "PHY_SCC_B_TO_DRV_B_24_DN")
	)
	(segment
		(start 279.790652 -195.280534)
		(end 279.790652 -195.102734)
		(width 0.127)
		(layer "B.Cu")
		(net "PHY_SCC_B_TO_DRV_B_24_DN")
	)
	(segment
		(start 37.494718 -17.232884)
		(end 36.703254 -16.014192)
		(width 0.127)
		(layer "B.Cu")
		(net "PHY_SCC_B_TO_DRV_B_24_DN")
	)
	(segment
		(start 38.32479 -17.772126)
		(end 37.494718 -17.232884)
		(width 0.127)
		(layer "B.Cu")
		(net "PHY_SCC_B_TO_DRV_B_24_DN")
	)
	(segment
		(start 39.583614 -18.771362)
		(end 39.264336 -18.563844)
		(width 0.127)
		(layer "B.Cu")
		(net "PHY_SCC_B_TO_DRV_B_24_DN")
	)
	(segment
		(start 40.113966 -18.934176)
		(end 39.794434 -18.726658)
		(width 0.127)
		(layer "B.Cu")
		(net "PHY_SCC_B_TO_DRV_B_24_DN")
	)
	(segment
		(start 35.157156 -15.136876)
		(end 34.429954 -15.136876)
		(width 0.127)
		(layer "B.Cu")
		(net "PHY_SCC_B_TO_DRV_B_24_DN")
	)
	(segment
		(start 36.703254 -16.014192)
		(end 35.447986 -15.198852)
		(width 0.127)
		(layer "B.Cu")
		(net "PHY_SCC_B_TO_DRV_B_24_DN")
	)
	(segment
		(start 34.285682 -15.281148)
		(end 34.285682 -15.562326)
		(width 0.127)
		(layer "B.Cu")
		(net "PHY_SCC_B_TO_DRV_B_24_DN")
	)
	(segment
		(start 38.689026 -18.190464)
		(end 38.369494 -17.982946)
		(width 0.127)
		(layer "B.Cu")
		(net "PHY_SCC_B_TO_DRV_B_24_DN")
	)
	(segment
		(start 41.583864 -19.888708)
		(end 41.373044 -19.933666)
		(width 0.127)
		(layer "B.Cu")
		(net "PHY_SCC_B_TO_DRV_B_24_DN")
	)
	(segment
		(start 39.794434 -18.726658)
		(end 39.583614 -18.771362)
		(width 0.127)
		(layer "B.Cu")
		(net "PHY_SCC_B_TO_DRV_B_24_DN")
	)
	(segment
		(start 49.851564 -25.258776)
		(end 41.583864 -19.888708)
		(width 0.127)
		(layer "B.Cu")
		(net "PHY_SCC_B_TO_DRV_B_24_DN")
	)
	(segment
		(start 68.885054 -29.30398)
		(end 49.851564 -25.258776)
		(width 0.127)
		(layer "B.Cu")
		(net "PHY_SCC_B_TO_DRV_B_24_DN")
	)
	(segment
		(start 131.168902 -87.784432)
		(end 110.916974 -56.599582)
		(width 0.127)
		(layer "B.Cu")
		(net "PHY_SCC_B_TO_DRV_B_24_DN")
	)
	(segment
		(start 35.447986 -15.198852)
		(end 35.157156 -15.136876)
		(width 0.127)
		(layer "B.Cu")
		(net "PHY_SCC_B_TO_DRV_B_24_DN")
	)
	(segment
		(start 110.916974 -56.599582)
		(end 68.885054 -29.30398)
		(width 0.127)
		(layer "B.Cu")
		(net "PHY_SCC_B_TO_DRV_B_24_DN")
	)
	(segment
		(start 40.478456 -19.352514)
		(end 40.158924 -19.144996)
		(width 0.127)
		(layer "B.Cu")
		(net "PHY_SCC_B_TO_DRV_B_24_DN")
	)
	(segment
		(start 40.158924 -19.144996)
		(end 40.113966 -18.934176)
		(width 0.127)
		(layer "B.Cu")
		(net "PHY_SCC_B_TO_DRV_B_24_DN")
	)
	(segment
		(start 41.053512 -19.726148)
		(end 41.008808 -19.515328)
		(width 0.127)
		(layer "B.Cu")
		(net "PHY_SCC_B_TO_DRV_B_24_DN")
	)
	(segment
		(start 40.689276 -19.30781)
		(end 40.478456 -19.352514)
		(width 0.127)
		(layer "B.Cu")
		(net "PHY_SCC_B_TO_DRV_B_24_DN")
	)
	(segment
		(start 39.219378 -18.353024)
		(end 38.899846 -18.145506)
		(width 0.127)
		(layer "B.Cu")
		(net "PHY_SCC_B_TO_DRV_B_24_DN")
	)
	(segment
		(start 273.267932 -194.021456)
		(end 261.845298 -186.603386)
		(width 0.127)
		(layer "B.Cu")
		(net "PHY_SCC_B_TO_DRV_B_24_DN")
	)
	(segment
		(start 38.899846 -18.145506)
		(end 38.689026 -18.190464)
		(width 0.127)
		(layer "B.Cu")
		(net "PHY_SCC_B_TO_DRV_B_24_DN")
	)
	(segment
		(start 39.264336 -18.563844)
		(end 39.219378 -18.353024)
		(width 0.127)
		(layer "B.Cu")
		(net "PHY_SCC_B_TO_DRV_B_24_DN")
	)
	(segment
		(start 261.845298 -186.603386)
		(end 246.17172 -162.469068)
		(width 0.127)
		(layer "B.Cu")
		(net "PHY_SCC_B_TO_DRV_B_24_DN")
	)
	(segment
		(start 279.236678 -195.494402)
		(end 279.576784 -195.494402)
		(width 0.127)
		(layer "B.Cu")
		(net "PHY_SCC_B_TO_DRV_B_24_DN")
	)
	(segment
		(start 41.373044 -19.933666)
		(end 41.053512 -19.726148)
		(width 0.127)
		(layer "B.Cu")
		(net "PHY_SCC_B_TO_DRV_B_24_DN")
	)
	(segment
		(start 246.17172 -162.469068)
		(end 131.168902 -87.784432)
		(width 0.127)
		(layer "B.Cu")
		(net "PHY_SCC_B_TO_DRV_B_24_DN")
	)
	(segment
		(start 41.008808 -19.515328)
		(end 40.689276 -19.30781)
		(width 0.127)
		(layer "B.Cu")
		(net "PHY_SCC_B_TO_DRV_B_24_DN")
	)
	(arc
		(start 279.790652 -195.102734)
		(mid 279.684565 -194.846617)
		(end 279.428448 -194.74053)
		(width 0.127)
		(layer "B.Cu")
		(net "PHY_SCC_B_TO_DRV_B_24_DN")
	)
	(arc
		(start 34.429954 -15.136876)
		(mid 34.327938 -15.179132)
		(end 34.285682 -15.281148)
		(width 0.127)
		(layer "B.Cu")
		(net "PHY_SCC_B_TO_DRV_B_24_DN")
	)
	(arc
		(start 279.576784 -195.494402)
		(mid 279.728012 -195.431762)
		(end 279.790652 -195.280534)
		(width 0.127)
		(layer "B.Cu")
		(net "PHY_SCC_B_TO_DRV_B_24_DN")
	)
	(segment
		(start 479.105214 -129.66065)
		(end 478.773998 -129.66065)
		(width 0.127)
		(layer "F.Cu")
		(net "PHY_SCC_B_TO_DRV_B_23_DP")
	)
	(segment
		(start 478.773998 -129.66065)
		(end 478.656904 -129.777744)
		(width 0.127)
		(layer "F.Cu")
		(net "PHY_SCC_B_TO_DRV_B_23_DP")
	)
	(segment
		(start 477.682052 -129.470912)
		(end 477.682052 -128.792224)
		(width 0.127)
		(layer "F.Cu")
		(net "PHY_SCC_B_TO_DRV_B_23_DP")
	)
	(segment
		(start 478.656904 -129.777744)
		(end 477.988884 -129.777744)
		(width 0.127)
		(layer "F.Cu")
		(net "PHY_SCC_B_TO_DRV_B_23_DP")
	)
	(segment
		(start 477.988884 -129.777744)
		(end 477.682052 -129.470912)
		(width 0.127)
		(layer "F.Cu")
		(net "PHY_SCC_B_TO_DRV_B_23_DP")
	)
	(segment
		(start 477.847152 -128.627124)
		(end 478.107502 -128.627124)
		(width 0.127)
		(layer "F.Cu")
		(net "PHY_SCC_B_TO_DRV_B_23_DP")
	)
	(arc
		(start 477.682052 -128.792224)
		(mid 477.730409 -128.675481)
		(end 477.847152 -128.627124)
		(width 0.127)
		(layer "F.Cu")
		(net "PHY_SCC_B_TO_DRV_B_23_DP")
	)
	(segment
		(start 280.636726 -206.294482)
		(end 280.230834 -206.294482)
		(width 0.127)
		(layer "B.Cu")
		(net "PHY_SCC_B_TO_DRV_B_23_DP")
	)
	(segment
		(start 343.031826 -196.6849)
		(end 365.485426 -182.103522)
		(width 0.127)
		(layer "B.Cu")
		(net "PHY_SCC_B_TO_DRV_B_23_DP")
	)
	(segment
		(start 367.804954 -180.778658)
		(end 367.849912 -180.567838)
		(width 0.127)
		(layer "B.Cu")
		(net "PHY_SCC_B_TO_DRV_B_23_DP")
	)
	(segment
		(start 477.682052 -129.791206)
		(end 477.682052 -128.774952)
		(width 0.127)
		(layer "B.Cu")
		(net "PHY_SCC_B_TO_DRV_B_23_DP")
	)
	(segment
		(start 368.699796 -180.19776)
		(end 368.7445 -179.98694)
		(width 0.127)
		(layer "B.Cu")
		(net "PHY_SCC_B_TO_DRV_B_23_DP")
	)
	(segment
		(start 366.015778 -181.940708)
		(end 366.060482 -181.729888)
		(width 0.127)
		(layer "B.Cu")
		(net "PHY_SCC_B_TO_DRV_B_23_DP")
	)
	(segment
		(start 365.485426 -182.103522)
		(end 365.696246 -182.148226)
		(width 0.127)
		(layer "B.Cu")
		(net "PHY_SCC_B_TO_DRV_B_23_DP")
	)
	(segment
		(start 367.849912 -180.567838)
		(end 368.169444 -180.36032)
		(width 0.127)
		(layer "B.Cu")
		(net "PHY_SCC_B_TO_DRV_B_23_DP")
	)
	(segment
		(start 367.485422 -180.986176)
		(end 367.804954 -180.778658)
		(width 0.127)
		(layer "B.Cu")
		(net "PHY_SCC_B_TO_DRV_B_23_DP")
	)
	(segment
		(start 301.363126 -205.54061)
		(end 343.031826 -196.6849)
		(width 0.127)
		(layer "B.Cu")
		(net "PHY_SCC_B_TO_DRV_B_23_DP")
	)
	(segment
		(start 365.696246 -182.148226)
		(end 366.015778 -181.940708)
		(width 0.127)
		(layer "B.Cu")
		(net "PHY_SCC_B_TO_DRV_B_23_DP")
	)
	(segment
		(start 477.82988 -128.627124)
		(end 478.107502 -128.627124)
		(width 0.127)
		(layer "B.Cu")
		(net "PHY_SCC_B_TO_DRV_B_23_DP")
	)
	(segment
		(start 366.380014 -181.52237)
		(end 366.590834 -181.567328)
		(width 0.127)
		(layer "B.Cu")
		(net "PHY_SCC_B_TO_DRV_B_23_DP")
	)
	(segment
		(start 427.786038 -141.645132)
		(end 475.780862 -131.443476)
		(width 0.127)
		(layer "B.Cu")
		(net "PHY_SCC_B_TO_DRV_B_23_DP")
	)
	(segment
		(start 368.169444 -180.36032)
		(end 368.380264 -180.405278)
		(width 0.127)
		(layer "B.Cu")
		(net "PHY_SCC_B_TO_DRV_B_23_DP")
	)
	(segment
		(start 477.212152 -130.51409)
		(end 477.682052 -129.791206)
		(width 0.127)
		(layer "B.Cu")
		(net "PHY_SCC_B_TO_DRV_B_23_DP")
	)
	(segment
		(start 368.380264 -180.405278)
		(end 368.699796 -180.19776)
		(width 0.127)
		(layer "B.Cu")
		(net "PHY_SCC_B_TO_DRV_B_23_DP")
	)
	(segment
		(start 280.307542 -205.54061)
		(end 301.363126 -205.54061)
		(width 0.127)
		(layer "B.Cu")
		(net "PHY_SCC_B_TO_DRV_B_23_DP")
	)
	(segment
		(start 280.082752 -206.1464)
		(end 280.082752 -205.7654)
		(width 0.127)
		(layer "B.Cu")
		(net "PHY_SCC_B_TO_DRV_B_23_DP")
	)
	(segment
		(start 367.274602 -180.941472)
		(end 367.485422 -180.986176)
		(width 0.127)
		(layer "B.Cu")
		(net "PHY_SCC_B_TO_DRV_B_23_DP")
	)
	(segment
		(start 366.590834 -181.567328)
		(end 366.910366 -181.35981)
		(width 0.127)
		(layer "B.Cu")
		(net "PHY_SCC_B_TO_DRV_B_23_DP")
	)
	(segment
		(start 366.910366 -181.35981)
		(end 366.95507 -181.14899)
		(width 0.127)
		(layer "B.Cu")
		(net "PHY_SCC_B_TO_DRV_B_23_DP")
	)
	(segment
		(start 366.060482 -181.729888)
		(end 366.380014 -181.52237)
		(width 0.127)
		(layer "B.Cu")
		(net "PHY_SCC_B_TO_DRV_B_23_DP")
	)
	(segment
		(start 368.7445 -179.98694)
		(end 427.786038 -141.645132)
		(width 0.127)
		(layer "B.Cu")
		(net "PHY_SCC_B_TO_DRV_B_23_DP")
	)
	(segment
		(start 366.95507 -181.14899)
		(end 367.274602 -180.941472)
		(width 0.127)
		(layer "B.Cu")
		(net "PHY_SCC_B_TO_DRV_B_23_DP")
	)
	(segment
		(start 475.780862 -131.443476)
		(end 477.212152 -130.51409)
		(width 0.127)
		(layer "B.Cu")
		(net "PHY_SCC_B_TO_DRV_B_23_DP")
	)
	(arc
		(start 280.230834 -206.294482)
		(mid 280.126124 -206.25111)
		(end 280.082752 -206.1464)
		(width 0.127)
		(layer "B.Cu")
		(net "PHY_SCC_B_TO_DRV_B_23_DP")
	)
	(arc
		(start 280.082752 -205.7654)
		(mid 280.148591 -205.606449)
		(end 280.307542 -205.54061)
		(width 0.127)
		(layer "B.Cu")
		(net "PHY_SCC_B_TO_DRV_B_23_DP")
	)
	(arc
		(start 477.682052 -128.774952)
		(mid 477.72535 -128.670422)
		(end 477.82988 -128.627124)
		(width 0.127)
		(layer "B.Cu")
		(net "PHY_SCC_B_TO_DRV_B_23_DP")
	)
	(segment
		(start 478.624392 -130.069844)
		(end 477.867726 -130.069844)
		(width 0.127)
		(layer "F.Cu")
		(net "PHY_SCC_B_TO_DRV_B_23_DN")
	)
	(segment
		(start 478.773998 -130.21945)
		(end 478.624392 -130.069844)
		(width 0.127)
		(layer "F.Cu")
		(net "PHY_SCC_B_TO_DRV_B_23_DN")
	)
	(segment
		(start 477.224852 -128.627124)
		(end 476.964502 -128.627124)
		(width 0.127)
		(layer "F.Cu")
		(net "PHY_SCC_B_TO_DRV_B_23_DN")
	)
	(segment
		(start 477.389952 -129.59207)
		(end 477.389952 -128.792224)
		(width 0.127)
		(layer "F.Cu")
		(net "PHY_SCC_B_TO_DRV_B_23_DN")
	)
	(segment
		(start 477.867726 -130.069844)
		(end 477.389952 -129.59207)
		(width 0.127)
		(layer "F.Cu")
		(net "PHY_SCC_B_TO_DRV_B_23_DN")
	)
	(segment
		(start 479.105214 -130.21945)
		(end 478.773998 -130.21945)
		(width 0.127)
		(layer "F.Cu")
		(net "PHY_SCC_B_TO_DRV_B_23_DN")
	)
	(arc
		(start 477.389952 -128.792224)
		(mid 477.341595 -128.675481)
		(end 477.224852 -128.627124)
		(width 0.127)
		(layer "F.Cu")
		(net "PHY_SCC_B_TO_DRV_B_23_DN")
	)
	(segment
		(start 477.389952 -129.704592)
		(end 477.389952 -128.774952)
		(width 0.127)
		(layer "B.Cu")
		(net "PHY_SCC_B_TO_DRV_B_23_DN")
	)
	(segment
		(start 477.242124 -128.627124)
		(end 476.964502 -128.627124)
		(width 0.127)
		(layer "B.Cu")
		(net "PHY_SCC_B_TO_DRV_B_23_DN")
	)
	(segment
		(start 427.672246 -141.370558)
		(end 475.66707 -131.168902)
		(width 0.127)
		(layer "B.Cu")
		(net "PHY_SCC_B_TO_DRV_B_23_DN")
	)
	(segment
		(start 279.790652 -206.1464)
		(end 279.790652 -205.7654)
		(width 0.127)
		(layer "B.Cu")
		(net "PHY_SCC_B_TO_DRV_B_23_DN")
	)
	(segment
		(start 342.918034 -196.410326)
		(end 427.672246 -141.370558)
		(width 0.127)
		(layer "B.Cu")
		(net "PHY_SCC_B_TO_DRV_B_23_DN")
	)
	(segment
		(start 279.236678 -206.294482)
		(end 279.64257 -206.294482)
		(width 0.127)
		(layer "B.Cu")
		(net "PHY_SCC_B_TO_DRV_B_23_DN")
	)
	(segment
		(start 280.307542 -205.24851)
		(end 301.332392 -205.24851)
		(width 0.127)
		(layer "B.Cu")
		(net "PHY_SCC_B_TO_DRV_B_23_DN")
	)
	(segment
		(start 477.001078 -130.302762)
		(end 477.389952 -129.704592)
		(width 0.127)
		(layer "B.Cu")
		(net "PHY_SCC_B_TO_DRV_B_23_DN")
	)
	(segment
		(start 301.332392 -205.24851)
		(end 342.918034 -196.410326)
		(width 0.127)
		(layer "B.Cu")
		(net "PHY_SCC_B_TO_DRV_B_23_DN")
	)
	(segment
		(start 475.66707 -131.168902)
		(end 477.001078 -130.302762)
		(width 0.127)
		(layer "B.Cu")
		(net "PHY_SCC_B_TO_DRV_B_23_DN")
	)
	(arc
		(start 279.790652 -205.7654)
		(mid 279.942046 -205.399904)
		(end 280.307542 -205.24851)
		(width 0.127)
		(layer "B.Cu")
		(net "PHY_SCC_B_TO_DRV_B_23_DN")
	)
	(arc
		(start 279.64257 -206.294482)
		(mid 279.74728 -206.25111)
		(end 279.790652 -206.1464)
		(width 0.127)
		(layer "B.Cu")
		(net "PHY_SCC_B_TO_DRV_B_23_DN")
	)
	(arc
		(start 477.389952 -128.774952)
		(mid 477.346654 -128.670422)
		(end 477.242124 -128.627124)
		(width 0.127)
		(layer "B.Cu")
		(net "PHY_SCC_B_TO_DRV_B_23_DN")
	)
	(segment
		(start 446.345056 -129.74828)
		(end 446.13195 -129.535174)
		(width 0.127)
		(layer "F.Cu")
		(net "PHY_SCC_B_TO_DRV_B_22_DP")
	)
	(segment
		(start 447.555112 -129.66065)
		(end 447.223896 -129.66065)
		(width 0.127)
		(layer "F.Cu")
		(net "PHY_SCC_B_TO_DRV_B_22_DP")
	)
	(segment
		(start 447.223896 -129.66065)
		(end 447.136266 -129.74828)
		(width 0.127)
		(layer "F.Cu")
		(net "PHY_SCC_B_TO_DRV_B_22_DP")
	)
	(segment
		(start 447.136266 -129.74828)
		(end 446.345056 -129.74828)
		(width 0.127)
		(layer "F.Cu")
		(net "PHY_SCC_B_TO_DRV_B_22_DP")
	)
	(segment
		(start 446.301876 -128.627124)
		(end 446.5574 -128.627124)
		(width 0.127)
		(layer "F.Cu")
		(net "PHY_SCC_B_TO_DRV_B_22_DP")
	)
	(segment
		(start 446.13195 -129.535174)
		(end 446.13195 -128.79705)
		(width 0.127)
		(layer "F.Cu")
		(net "PHY_SCC_B_TO_DRV_B_22_DP")
	)
	(arc
		(start 446.13195 -128.79705)
		(mid 446.18172 -128.676894)
		(end 446.301876 -128.627124)
		(width 0.127)
		(layer "F.Cu")
		(net "PHY_SCC_B_TO_DRV_B_22_DP")
	)
	(segment
		(start 445.520318 -131.414774)
		(end 446.13195 -130.471926)
		(width 0.127)
		(layer "B.Cu")
		(net "PHY_SCC_B_TO_DRV_B_22_DP")
	)
	(segment
		(start 279.307544 -203.740512)
		(end 302.097694 -203.740512)
		(width 0.127)
		(layer "B.Cu")
		(net "PHY_SCC_B_TO_DRV_B_22_DP")
	)
	(segment
		(start 410.199332 -150.969726)
		(end 410.518864 -150.762208)
		(width 0.127)
		(layer "B.Cu")
		(net "PHY_SCC_B_TO_DRV_B_22_DP")
	)
	(segment
		(start 411.413452 -150.18131)
		(end 411.45841 -149.97049)
		(width 0.127)
		(layer "B.Cu")
		(net "PHY_SCC_B_TO_DRV_B_22_DP")
	)
	(segment
		(start 279.082754 -204.346302)
		(end 279.082754 -203.965302)
		(width 0.127)
		(layer "B.Cu")
		(net "PHY_SCC_B_TO_DRV_B_22_DP")
	)
	(segment
		(start 408.409902 -152.131776)
		(end 408.729434 -151.924258)
		(width 0.127)
		(layer "B.Cu")
		(net "PHY_SCC_B_TO_DRV_B_22_DP")
	)
	(segment
		(start 410.563568 -150.551388)
		(end 410.8831 -150.34387)
		(width 0.127)
		(layer "B.Cu")
		(net "PHY_SCC_B_TO_DRV_B_22_DP")
	)
	(segment
		(start 411.45841 -149.97049)
		(end 437.360822 -133.149086)
		(width 0.127)
		(layer "B.Cu")
		(net "PHY_SCC_B_TO_DRV_B_22_DP")
	)
	(segment
		(start 446.13195 -130.471926)
		(end 446.13195 -128.79705)
		(width 0.127)
		(layer "B.Cu")
		(net "PHY_SCC_B_TO_DRV_B_22_DP")
	)
	(segment
		(start 408.729434 -151.924258)
		(end 408.774138 -151.713438)
		(width 0.127)
		(layer "B.Cu")
		(net "PHY_SCC_B_TO_DRV_B_22_DP")
	)
	(segment
		(start 409.988512 -150.925022)
		(end 410.199332 -150.969726)
		(width 0.127)
		(layer "B.Cu")
		(net "PHY_SCC_B_TO_DRV_B_22_DP")
	)
	(segment
		(start 437.360822 -133.149086)
		(end 445.520318 -131.414774)
		(width 0.127)
		(layer "B.Cu")
		(net "PHY_SCC_B_TO_DRV_B_22_DP")
	)
	(segment
		(start 409.66898 -151.132286)
		(end 409.988512 -150.925022)
		(width 0.127)
		(layer "B.Cu")
		(net "PHY_SCC_B_TO_DRV_B_22_DP")
	)
	(segment
		(start 409.09367 -151.50592)
		(end 409.30449 -151.550624)
		(width 0.127)
		(layer "B.Cu")
		(net "PHY_SCC_B_TO_DRV_B_22_DP")
	)
	(segment
		(start 410.518864 -150.762208)
		(end 410.563568 -150.551388)
		(width 0.127)
		(layer "B.Cu")
		(net "PHY_SCC_B_TO_DRV_B_22_DP")
	)
	(segment
		(start 446.301876 -128.627124)
		(end 446.5574 -128.627124)
		(width 0.127)
		(layer "B.Cu")
		(net "PHY_SCC_B_TO_DRV_B_22_DP")
	)
	(segment
		(start 302.097694 -203.740512)
		(end 341.533226 -195.379594)
		(width 0.127)
		(layer "B.Cu")
		(net "PHY_SCC_B_TO_DRV_B_22_DP")
	)
	(segment
		(start 410.8831 -150.34387)
		(end 411.09392 -150.388574)
		(width 0.127)
		(layer "B.Cu")
		(net "PHY_SCC_B_TO_DRV_B_22_DP")
	)
	(segment
		(start 411.09392 -150.388574)
		(end 411.413452 -150.18131)
		(width 0.127)
		(layer "B.Cu")
		(net "PHY_SCC_B_TO_DRV_B_22_DP")
	)
	(segment
		(start 409.30449 -151.550624)
		(end 409.624022 -151.343106)
		(width 0.127)
		(layer "B.Cu")
		(net "PHY_SCC_B_TO_DRV_B_22_DP")
	)
	(segment
		(start 341.533226 -195.379594)
		(end 408.199082 -152.086818)
		(width 0.127)
		(layer "B.Cu")
		(net "PHY_SCC_B_TO_DRV_B_22_DP")
	)
	(segment
		(start 408.199082 -152.086818)
		(end 408.409902 -152.131776)
		(width 0.127)
		(layer "B.Cu")
		(net "PHY_SCC_B_TO_DRV_B_22_DP")
	)
	(segment
		(start 408.774138 -151.713438)
		(end 409.09367 -151.50592)
		(width 0.127)
		(layer "B.Cu")
		(net "PHY_SCC_B_TO_DRV_B_22_DP")
	)
	(segment
		(start 409.624022 -151.343106)
		(end 409.66898 -151.132286)
		(width 0.127)
		(layer "B.Cu")
		(net "PHY_SCC_B_TO_DRV_B_22_DP")
	)
	(segment
		(start 279.636728 -204.494384)
		(end 279.230836 -204.494384)
		(width 0.127)
		(layer "B.Cu")
		(net "PHY_SCC_B_TO_DRV_B_22_DP")
	)
	(arc
		(start 446.13195 -128.79705)
		(mid 446.18172 -128.676894)
		(end 446.301876 -128.627124)
		(width 0.127)
		(layer "B.Cu")
		(net "PHY_SCC_B_TO_DRV_B_22_DP")
	)
	(arc
		(start 279.082754 -203.965302)
		(mid 279.148593 -203.806351)
		(end 279.307544 -203.740512)
		(width 0.127)
		(layer "B.Cu")
		(net "PHY_SCC_B_TO_DRV_B_22_DP")
	)
	(arc
		(start 279.230836 -204.494384)
		(mid 279.126126 -204.451012)
		(end 279.082754 -204.346302)
		(width 0.127)
		(layer "B.Cu")
		(net "PHY_SCC_B_TO_DRV_B_22_DP")
	)
	(segment
		(start 445.669924 -128.627124)
		(end 445.4144 -128.627124)
		(width 0.127)
		(layer "F.Cu")
		(net "PHY_SCC_B_TO_DRV_B_22_DN")
	)
	(segment
		(start 447.555112 -130.21945)
		(end 447.223896 -130.21945)
		(width 0.127)
		(layer "F.Cu")
		(net "PHY_SCC_B_TO_DRV_B_22_DN")
	)
	(segment
		(start 445.83985 -129.656332)
		(end 445.83985 -128.79705)
		(width 0.127)
		(layer "F.Cu")
		(net "PHY_SCC_B_TO_DRV_B_22_DN")
	)
	(segment
		(start 447.223896 -130.21945)
		(end 447.044826 -130.04038)
		(width 0.127)
		(layer "F.Cu")
		(net "PHY_SCC_B_TO_DRV_B_22_DN")
	)
	(segment
		(start 447.044826 -130.04038)
		(end 446.223898 -130.04038)
		(width 0.127)
		(layer "F.Cu")
		(net "PHY_SCC_B_TO_DRV_B_22_DN")
	)
	(segment
		(start 446.223898 -130.04038)
		(end 445.83985 -129.656332)
		(width 0.127)
		(layer "F.Cu")
		(net "PHY_SCC_B_TO_DRV_B_22_DN")
	)
	(arc
		(start 445.83985 -128.79705)
		(mid 445.79008 -128.676894)
		(end 445.669924 -128.627124)
		(width 0.127)
		(layer "F.Cu")
		(net "PHY_SCC_B_TO_DRV_B_22_DN")
	)
	(segment
		(start 445.669924 -128.627124)
		(end 445.4144 -128.627124)
		(width 0.127)
		(layer "B.Cu")
		(net "PHY_SCC_B_TO_DRV_B_22_DN")
	)
	(segment
		(start 445.590422 -130.769868)
		(end 445.83985 -130.385312)
		(width 0.127)
		(layer "B.Cu")
		(net "PHY_SCC_B_TO_DRV_B_22_DN")
	)
	(segment
		(start 341.419688 -195.10502)
		(end 437.24703 -132.874512)
		(width 0.127)
		(layer "B.Cu")
		(net "PHY_SCC_B_TO_DRV_B_22_DN")
	)
	(segment
		(start 302.06696 -203.448412)
		(end 341.419688 -195.10502)
		(width 0.127)
		(layer "B.Cu")
		(net "PHY_SCC_B_TO_DRV_B_22_DN")
	)
	(segment
		(start 445.340994 -131.153916)
		(end 445.590422 -130.769868)
		(width 0.127)
		(layer "B.Cu")
		(net "PHY_SCC_B_TO_DRV_B_22_DN")
	)
	(segment
		(start 445.83985 -130.385312)
		(end 445.83985 -128.79705)
		(width 0.127)
		(layer "B.Cu")
		(net "PHY_SCC_B_TO_DRV_B_22_DN")
	)
	(segment
		(start 278.790654 -204.346302)
		(end 278.790654 -203.965302)
		(width 0.127)
		(layer "B.Cu")
		(net "PHY_SCC_B_TO_DRV_B_22_DN")
	)
	(segment
		(start 437.24703 -132.874512)
		(end 445.340994 -131.153916)
		(width 0.127)
		(layer "B.Cu")
		(net "PHY_SCC_B_TO_DRV_B_22_DN")
	)
	(segment
		(start 278.23668 -204.494384)
		(end 278.642572 -204.494384)
		(width 0.127)
		(layer "B.Cu")
		(net "PHY_SCC_B_TO_DRV_B_22_DN")
	)
	(segment
		(start 279.307544 -203.448412)
		(end 302.06696 -203.448412)
		(width 0.127)
		(layer "B.Cu")
		(net "PHY_SCC_B_TO_DRV_B_22_DN")
	)
	(arc
		(start 278.790654 -203.965302)
		(mid 278.942048 -203.599806)
		(end 279.307544 -203.448412)
		(width 0.127)
		(layer "B.Cu")
		(net "PHY_SCC_B_TO_DRV_B_22_DN")
	)
	(arc
		(start 278.642572 -204.494384)
		(mid 278.747282 -204.451012)
		(end 278.790654 -204.346302)
		(width 0.127)
		(layer "B.Cu")
		(net "PHY_SCC_B_TO_DRV_B_22_DN")
	)
	(arc
		(start 445.83985 -128.79705)
		(mid 445.79008 -128.676894)
		(end 445.669924 -128.627124)
		(width 0.127)
		(layer "B.Cu")
		(net "PHY_SCC_B_TO_DRV_B_22_DN")
	)
	(segment
		(start 415.573718 -129.76098)
		(end 414.807908 -129.76098)
		(width 0.127)
		(layer "F.Cu")
		(net "PHY_SCC_B_TO_DRV_B_21_DP")
	)
	(segment
		(start 416.005264 -129.66065)
		(end 415.674048 -129.66065)
		(width 0.127)
		(layer "F.Cu")
		(net "PHY_SCC_B_TO_DRV_B_21_DP")
	)
	(segment
		(start 414.582102 -129.535174)
		(end 414.582102 -128.768602)
		(width 0.127)
		(layer "F.Cu")
		(net "PHY_SCC_B_TO_DRV_B_21_DP")
	)
	(segment
		(start 414.807908 -129.76098)
		(end 414.582102 -129.535174)
		(width 0.127)
		(layer "F.Cu")
		(net "PHY_SCC_B_TO_DRV_B_21_DP")
	)
	(segment
		(start 415.674048 -129.66065)
		(end 415.573718 -129.76098)
		(width 0.127)
		(layer "F.Cu")
		(net "PHY_SCC_B_TO_DRV_B_21_DP")
	)
	(segment
		(start 414.72358 -128.627124)
		(end 415.007552 -128.627124)
		(width 0.127)
		(layer "F.Cu")
		(net "PHY_SCC_B_TO_DRV_B_21_DP")
	)
	(arc
		(start 414.582102 -128.768602)
		(mid 414.62354 -128.668562)
		(end 414.72358 -128.627124)
		(width 0.127)
		(layer "F.Cu")
		(net "PHY_SCC_B_TO_DRV_B_21_DP")
	)
	(segment
		(start 407.10866 -146.105626)
		(end 407.063702 -145.894806)
		(width 0.127)
		(layer "B.Cu")
		(net "PHY_SCC_B_TO_DRV_B_21_DP")
	)
	(segment
		(start 408.225752 -144.105376)
		(end 414.231328 -134.857998)
		(width 0.127)
		(layer "B.Cu")
		(net "PHY_SCC_B_TO_DRV_B_21_DP")
	)
	(segment
		(start 407.644854 -145.000218)
		(end 407.852372 -144.680686)
		(width 0.127)
		(layer "B.Cu")
		(net "PHY_SCC_B_TO_DRV_B_21_DP")
	)
	(segment
		(start 414.582102 -133.207252)
		(end 414.582102 -128.768602)
		(width 0.127)
		(layer "B.Cu")
		(net "PHY_SCC_B_TO_DRV_B_21_DP")
	)
	(segment
		(start 408.063192 -144.635728)
		(end 408.27071 -144.316196)
		(width 0.127)
		(layer "B.Cu")
		(net "PHY_SCC_B_TO_DRV_B_21_DP")
	)
	(segment
		(start 408.27071 -144.316196)
		(end 408.225752 -144.105376)
		(width 0.127)
		(layer "B.Cu")
		(net "PHY_SCC_B_TO_DRV_B_21_DP")
	)
	(segment
		(start 406.901142 -146.425158)
		(end 407.10866 -146.105626)
		(width 0.127)
		(layer "B.Cu")
		(net "PHY_SCC_B_TO_DRV_B_21_DP")
	)
	(segment
		(start 280.307542 -201.940668)
		(end 303.147476 -201.940668)
		(width 0.127)
		(layer "B.Cu")
		(net "PHY_SCC_B_TO_DRV_B_21_DP")
	)
	(segment
		(start 407.063702 -145.894806)
		(end 407.27122 -145.575274)
		(width 0.127)
		(layer "B.Cu")
		(net "PHY_SCC_B_TO_DRV_B_21_DP")
	)
	(segment
		(start 407.48204 -145.53057)
		(end 407.689558 -145.211038)
		(width 0.127)
		(layer "B.Cu")
		(net "PHY_SCC_B_TO_DRV_B_21_DP")
	)
	(segment
		(start 406.690322 -146.469862)
		(end 406.901142 -146.425158)
		(width 0.127)
		(layer "B.Cu")
		(net "PHY_SCC_B_TO_DRV_B_21_DP")
	)
	(segment
		(start 406.527508 -147.000214)
		(end 406.482804 -146.789394)
		(width 0.127)
		(layer "B.Cu")
		(net "PHY_SCC_B_TO_DRV_B_21_DP")
	)
	(segment
		(start 414.72358 -128.627124)
		(end 415.007552 -128.627124)
		(width 0.127)
		(layer "B.Cu")
		(net "PHY_SCC_B_TO_DRV_B_21_DP")
	)
	(segment
		(start 407.27122 -145.575274)
		(end 407.48204 -145.53057)
		(width 0.127)
		(layer "B.Cu")
		(net "PHY_SCC_B_TO_DRV_B_21_DP")
	)
	(segment
		(start 303.147476 -201.940668)
		(end 334.738218 -195.22567)
		(width 0.127)
		(layer "B.Cu")
		(net "PHY_SCC_B_TO_DRV_B_21_DP")
	)
	(segment
		(start 414.231328 -134.857998)
		(end 414.582102 -133.207252)
		(width 0.127)
		(layer "B.Cu")
		(net "PHY_SCC_B_TO_DRV_B_21_DP")
	)
	(segment
		(start 406.31999 -147.319746)
		(end 406.527508 -147.000214)
		(width 0.127)
		(layer "B.Cu")
		(net "PHY_SCC_B_TO_DRV_B_21_DP")
	)
	(segment
		(start 334.738218 -195.22567)
		(end 404.388066 -150.01494)
		(width 0.127)
		(layer "B.Cu")
		(net "PHY_SCC_B_TO_DRV_B_21_DP")
	)
	(segment
		(start 280.636726 -202.69454)
		(end 280.230834 -202.69454)
		(width 0.127)
		(layer "B.Cu")
		(net "PHY_SCC_B_TO_DRV_B_21_DP")
	)
	(segment
		(start 404.388066 -150.01494)
		(end 406.10917 -147.364704)
		(width 0.127)
		(layer "B.Cu")
		(net "PHY_SCC_B_TO_DRV_B_21_DP")
	)
	(segment
		(start 280.082752 -202.546458)
		(end 280.082752 -202.165458)
		(width 0.127)
		(layer "B.Cu")
		(net "PHY_SCC_B_TO_DRV_B_21_DP")
	)
	(segment
		(start 407.852372 -144.680686)
		(end 408.063192 -144.635728)
		(width 0.127)
		(layer "B.Cu")
		(net "PHY_SCC_B_TO_DRV_B_21_DP")
	)
	(segment
		(start 406.482804 -146.789394)
		(end 406.690322 -146.469862)
		(width 0.127)
		(layer "B.Cu")
		(net "PHY_SCC_B_TO_DRV_B_21_DP")
	)
	(segment
		(start 407.689558 -145.211038)
		(end 407.644854 -145.000218)
		(width 0.127)
		(layer "B.Cu")
		(net "PHY_SCC_B_TO_DRV_B_21_DP")
	)
	(segment
		(start 406.10917 -147.364704)
		(end 406.31999 -147.319746)
		(width 0.127)
		(layer "B.Cu")
		(net "PHY_SCC_B_TO_DRV_B_21_DP")
	)
	(arc
		(start 414.582102 -128.768602)
		(mid 414.62354 -128.668562)
		(end 414.72358 -128.627124)
		(width 0.127)
		(layer "B.Cu")
		(net "PHY_SCC_B_TO_DRV_B_21_DP")
	)
	(arc
		(start 280.230834 -202.69454)
		(mid 280.126124 -202.651168)
		(end 280.082752 -202.546458)
		(width 0.127)
		(layer "B.Cu")
		(net "PHY_SCC_B_TO_DRV_B_21_DP")
	)
	(arc
		(start 280.082752 -202.165458)
		(mid 280.148591 -202.006507)
		(end 280.307542 -201.940668)
		(width 0.127)
		(layer "B.Cu")
		(net "PHY_SCC_B_TO_DRV_B_21_DP")
	)
	(segment
		(start 415.674048 -130.21945)
		(end 415.507678 -130.05308)
		(width 0.127)
		(layer "F.Cu")
		(net "PHY_SCC_B_TO_DRV_B_21_DN")
	)
	(segment
		(start 415.507678 -130.05308)
		(end 414.68675 -130.05308)
		(width 0.127)
		(layer "F.Cu")
		(net "PHY_SCC_B_TO_DRV_B_21_DN")
	)
	(segment
		(start 416.005264 -130.21945)
		(end 415.674048 -130.21945)
		(width 0.127)
		(layer "F.Cu")
		(net "PHY_SCC_B_TO_DRV_B_21_DN")
	)
	(segment
		(start 414.68675 -130.05308)
		(end 414.290002 -129.656332)
		(width 0.127)
		(layer "F.Cu")
		(net "PHY_SCC_B_TO_DRV_B_21_DN")
	)
	(segment
		(start 414.290002 -129.656332)
		(end 414.290002 -128.768602)
		(width 0.127)
		(layer "F.Cu")
		(net "PHY_SCC_B_TO_DRV_B_21_DN")
	)
	(segment
		(start 414.148524 -128.627124)
		(end 413.864552 -128.627124)
		(width 0.127)
		(layer "F.Cu")
		(net "PHY_SCC_B_TO_DRV_B_21_DN")
	)
	(arc
		(start 414.290002 -128.768602)
		(mid 414.248564 -128.668562)
		(end 414.148524 -128.627124)
		(width 0.127)
		(layer "F.Cu")
		(net "PHY_SCC_B_TO_DRV_B_21_DN")
	)
	(segment
		(start 413.956754 -134.744206)
		(end 414.290002 -133.176518)
		(width 0.127)
		(layer "B.Cu")
		(net "PHY_SCC_B_TO_DRV_B_21_DN")
	)
	(segment
		(start 280.307542 -201.648568)
		(end 303.116742 -201.648568)
		(width 0.127)
		(layer "B.Cu")
		(net "PHY_SCC_B_TO_DRV_B_21_DN")
	)
	(segment
		(start 414.290002 -133.176518)
		(end 414.290002 -128.768602)
		(width 0.127)
		(layer "B.Cu")
		(net "PHY_SCC_B_TO_DRV_B_21_DN")
	)
	(segment
		(start 414.148524 -128.627124)
		(end 413.864552 -128.627124)
		(width 0.127)
		(layer "B.Cu")
		(net "PHY_SCC_B_TO_DRV_B_21_DN")
	)
	(segment
		(start 279.236678 -202.69454)
		(end 279.64257 -202.69454)
		(width 0.127)
		(layer "B.Cu")
		(net "PHY_SCC_B_TO_DRV_B_21_DN")
	)
	(segment
		(start 404.176738 -149.803612)
		(end 413.956754 -134.744206)
		(width 0.127)
		(layer "B.Cu")
		(net "PHY_SCC_B_TO_DRV_B_21_DN")
	)
	(segment
		(start 303.116742 -201.648568)
		(end 334.62468 -194.951096)
		(width 0.127)
		(layer "B.Cu")
		(net "PHY_SCC_B_TO_DRV_B_21_DN")
	)
	(segment
		(start 279.790652 -202.546458)
		(end 279.790652 -202.165458)
		(width 0.127)
		(layer "B.Cu")
		(net "PHY_SCC_B_TO_DRV_B_21_DN")
	)
	(segment
		(start 334.62468 -194.951096)
		(end 404.176738 -149.803612)
		(width 0.127)
		(layer "B.Cu")
		(net "PHY_SCC_B_TO_DRV_B_21_DN")
	)
	(arc
		(start 414.290002 -128.768602)
		(mid 414.248564 -128.668562)
		(end 414.148524 -128.627124)
		(width 0.127)
		(layer "B.Cu")
		(net "PHY_SCC_B_TO_DRV_B_21_DN")
	)
	(arc
		(start 279.64257 -202.69454)
		(mid 279.74728 -202.651168)
		(end 279.790652 -202.546458)
		(width 0.127)
		(layer "B.Cu")
		(net "PHY_SCC_B_TO_DRV_B_21_DN")
	)
	(arc
		(start 279.790652 -202.165458)
		(mid 279.942046 -201.799962)
		(end 280.307542 -201.648568)
		(width 0.127)
		(layer "B.Cu")
		(net "PHY_SCC_B_TO_DRV_B_21_DN")
	)
	(segment
		(start 383.195576 -128.627124)
		(end 383.45745 -128.627124)
		(width 0.127)
		(layer "F.Cu")
		(net "PHY_SCC_B_TO_DRV_B_20_DP")
	)
	(segment
		(start 383.032 -129.535174)
		(end 383.032 -128.7907)
		(width 0.127)
		(layer "F.Cu")
		(net "PHY_SCC_B_TO_DRV_B_20_DP")
	)
	(segment
		(start 383.26187 -129.765044)
		(end 383.032 -129.535174)
		(width 0.127)
		(layer "F.Cu")
		(net "PHY_SCC_B_TO_DRV_B_20_DP")
	)
	(segment
		(start 384.019552 -129.765044)
		(end 383.26187 -129.765044)
		(width 0.127)
		(layer "F.Cu")
		(net "PHY_SCC_B_TO_DRV_B_20_DP")
	)
	(segment
		(start 384.455162 -129.66065)
		(end 384.123946 -129.66065)
		(width 0.127)
		(layer "F.Cu")
		(net "PHY_SCC_B_TO_DRV_B_20_DP")
	)
	(segment
		(start 384.123946 -129.66065)
		(end 384.019552 -129.765044)
		(width 0.127)
		(layer "F.Cu")
		(net "PHY_SCC_B_TO_DRV_B_20_DP")
	)
	(arc
		(start 383.032 -128.7907)
		(mid 383.07991 -128.675034)
		(end 383.195576 -128.627124)
		(width 0.127)
		(layer "F.Cu")
		(net "PHY_SCC_B_TO_DRV_B_20_DP")
	)
	(segment
		(start 355.848158 -178.280314)
		(end 377.390152 -145.108422)
		(width 0.127)
		(layer "B.Cu")
		(net "PHY_SCC_B_TO_DRV_B_20_DP")
	)
	(segment
		(start 334.50403 -192.141348)
		(end 355.848158 -178.280314)
		(width 0.127)
		(layer "B.Cu")
		(net "PHY_SCC_B_TO_DRV_B_20_DP")
	)
	(segment
		(start 377.390152 -145.108422)
		(end 377.600972 -145.063718)
		(width 0.127)
		(layer "B.Cu")
		(net "PHY_SCC_B_TO_DRV_B_20_DP")
	)
	(segment
		(start 378.344684 -143.638524)
		(end 378.552202 -143.318992)
		(width 0.127)
		(layer "B.Cu")
		(net "PHY_SCC_B_TO_DRV_B_20_DP")
	)
	(segment
		(start 382.50495 -137.23239)
		(end 383.032 -134.752334)
		(width 0.127)
		(layer "B.Cu")
		(net "PHY_SCC_B_TO_DRV_B_20_DP")
	)
	(segment
		(start 377.600972 -145.063718)
		(end 377.80849 -144.744186)
		(width 0.127)
		(layer "B.Cu")
		(net "PHY_SCC_B_TO_DRV_B_20_DP")
	)
	(segment
		(start 379.506734 -141.849348)
		(end 382.50495 -137.23239)
		(width 0.127)
		(layer "B.Cu")
		(net "PHY_SCC_B_TO_DRV_B_20_DP")
	)
	(segment
		(start 296.870628 -200.14057)
		(end 334.50403 -192.141348)
		(width 0.127)
		(layer "B.Cu")
		(net "PHY_SCC_B_TO_DRV_B_20_DP")
	)
	(segment
		(start 378.925582 -142.743936)
		(end 379.1331 -142.424404)
		(width 0.127)
		(layer "B.Cu")
		(net "PHY_SCC_B_TO_DRV_B_20_DP")
	)
	(segment
		(start 383.032 -134.752334)
		(end 383.032 -128.7907)
		(width 0.127)
		(layer "B.Cu")
		(net "PHY_SCC_B_TO_DRV_B_20_DP")
	)
	(segment
		(start 378.763022 -143.274288)
		(end 378.97054 -142.954756)
		(width 0.127)
		(layer "B.Cu")
		(net "PHY_SCC_B_TO_DRV_B_20_DP")
	)
	(segment
		(start 379.551438 -142.060168)
		(end 379.506734 -141.849348)
		(width 0.127)
		(layer "B.Cu")
		(net "PHY_SCC_B_TO_DRV_B_20_DP")
	)
	(segment
		(start 383.195576 -128.627124)
		(end 383.45745 -128.627124)
		(width 0.127)
		(layer "B.Cu")
		(net "PHY_SCC_B_TO_DRV_B_20_DP")
	)
	(segment
		(start 378.97054 -142.954756)
		(end 378.925582 -142.743936)
		(width 0.127)
		(layer "B.Cu")
		(net "PHY_SCC_B_TO_DRV_B_20_DP")
	)
	(segment
		(start 377.97105 -144.213834)
		(end 378.18187 -144.168876)
		(width 0.127)
		(layer "B.Cu")
		(net "PHY_SCC_B_TO_DRV_B_20_DP")
	)
	(segment
		(start 279.307544 -200.14057)
		(end 296.870628 -200.14057)
		(width 0.127)
		(layer "B.Cu")
		(net "PHY_SCC_B_TO_DRV_B_20_DP")
	)
	(segment
		(start 279.636728 -200.894442)
		(end 279.230836 -200.894442)
		(width 0.127)
		(layer "B.Cu")
		(net "PHY_SCC_B_TO_DRV_B_20_DP")
	)
	(segment
		(start 377.763532 -144.533366)
		(end 377.97105 -144.213834)
		(width 0.127)
		(layer "B.Cu")
		(net "PHY_SCC_B_TO_DRV_B_20_DP")
	)
	(segment
		(start 379.34392 -142.3797)
		(end 379.551438 -142.060168)
		(width 0.127)
		(layer "B.Cu")
		(net "PHY_SCC_B_TO_DRV_B_20_DP")
	)
	(segment
		(start 378.552202 -143.318992)
		(end 378.763022 -143.274288)
		(width 0.127)
		(layer "B.Cu")
		(net "PHY_SCC_B_TO_DRV_B_20_DP")
	)
	(segment
		(start 279.082754 -200.74636)
		(end 279.082754 -200.36536)
		(width 0.127)
		(layer "B.Cu")
		(net "PHY_SCC_B_TO_DRV_B_20_DP")
	)
	(segment
		(start 377.80849 -144.744186)
		(end 377.763532 -144.533366)
		(width 0.127)
		(layer "B.Cu")
		(net "PHY_SCC_B_TO_DRV_B_20_DP")
	)
	(segment
		(start 378.18187 -144.168876)
		(end 378.389388 -143.849344)
		(width 0.127)
		(layer "B.Cu")
		(net "PHY_SCC_B_TO_DRV_B_20_DP")
	)
	(segment
		(start 379.1331 -142.424404)
		(end 379.34392 -142.3797)
		(width 0.127)
		(layer "B.Cu")
		(net "PHY_SCC_B_TO_DRV_B_20_DP")
	)
	(segment
		(start 378.389388 -143.849344)
		(end 378.344684 -143.638524)
		(width 0.127)
		(layer "B.Cu")
		(net "PHY_SCC_B_TO_DRV_B_20_DP")
	)
	(arc
		(start 279.230836 -200.894442)
		(mid 279.126126 -200.85107)
		(end 279.082754 -200.74636)
		(width 0.127)
		(layer "B.Cu")
		(net "PHY_SCC_B_TO_DRV_B_20_DP")
	)
	(arc
		(start 383.032 -128.7907)
		(mid 383.07991 -128.675034)
		(end 383.195576 -128.627124)
		(width 0.127)
		(layer "B.Cu")
		(net "PHY_SCC_B_TO_DRV_B_20_DP")
	)
	(arc
		(start 279.082754 -200.36536)
		(mid 279.148593 -200.206409)
		(end 279.307544 -200.14057)
		(width 0.127)
		(layer "B.Cu")
		(net "PHY_SCC_B_TO_DRV_B_20_DP")
	)
	(segment
		(start 384.455162 -130.21945)
		(end 384.123946 -130.21945)
		(width 0.127)
		(layer "F.Cu")
		(net "PHY_SCC_B_TO_DRV_B_20_DN")
	)
	(segment
		(start 382.576324 -128.627124)
		(end 382.31445 -128.627124)
		(width 0.127)
		(layer "F.Cu")
		(net "PHY_SCC_B_TO_DRV_B_20_DN")
	)
	(segment
		(start 384.123946 -130.21945)
		(end 383.96164 -130.057144)
		(width 0.127)
		(layer "F.Cu")
		(net "PHY_SCC_B_TO_DRV_B_20_DN")
	)
	(segment
		(start 383.140712 -130.057144)
		(end 382.7399 -129.656332)
		(width 0.127)
		(layer "F.Cu")
		(net "PHY_SCC_B_TO_DRV_B_20_DN")
	)
	(segment
		(start 383.96164 -130.057144)
		(end 383.140712 -130.057144)
		(width 0.127)
		(layer "F.Cu")
		(net "PHY_SCC_B_TO_DRV_B_20_DN")
	)
	(segment
		(start 382.7399 -129.656332)
		(end 382.7399 -128.7907)
		(width 0.127)
		(layer "F.Cu")
		(net "PHY_SCC_B_TO_DRV_B_20_DN")
	)
	(arc
		(start 382.7399 -128.7907)
		(mid 382.69199 -128.675034)
		(end 382.576324 -128.627124)
		(width 0.127)
		(layer "F.Cu")
		(net "PHY_SCC_B_TO_DRV_B_20_DN")
	)
	(segment
		(start 382.576324 -128.627124)
		(end 382.31445 -128.627124)
		(width 0.127)
		(layer "B.Cu")
		(net "PHY_SCC_B_TO_DRV_B_20_DN")
	)
	(segment
		(start 355.63683 -178.068986)
		(end 382.230376 -137.118598)
		(width 0.127)
		(layer "B.Cu")
		(net "PHY_SCC_B_TO_DRV_B_20_DN")
	)
	(segment
		(start 382.7399 -134.7216)
		(end 382.7399 -128.7907)
		(width 0.127)
		(layer "B.Cu")
		(net "PHY_SCC_B_TO_DRV_B_20_DN")
	)
	(segment
		(start 278.23668 -200.894442)
		(end 278.642572 -200.894442)
		(width 0.127)
		(layer "B.Cu")
		(net "PHY_SCC_B_TO_DRV_B_20_DN")
	)
	(segment
		(start 334.390238 -191.866774)
		(end 355.63683 -178.068986)
		(width 0.127)
		(layer "B.Cu")
		(net "PHY_SCC_B_TO_DRV_B_20_DN")
	)
	(segment
		(start 382.230376 -137.118598)
		(end 382.7399 -134.7216)
		(width 0.127)
		(layer "B.Cu")
		(net "PHY_SCC_B_TO_DRV_B_20_DN")
	)
	(segment
		(start 278.790654 -200.74636)
		(end 278.790654 -200.36536)
		(width 0.127)
		(layer "B.Cu")
		(net "PHY_SCC_B_TO_DRV_B_20_DN")
	)
	(segment
		(start 296.839894 -199.84847)
		(end 334.390238 -191.866774)
		(width 0.127)
		(layer "B.Cu")
		(net "PHY_SCC_B_TO_DRV_B_20_DN")
	)
	(segment
		(start 279.307544 -199.84847)
		(end 296.839894 -199.84847)
		(width 0.127)
		(layer "B.Cu")
		(net "PHY_SCC_B_TO_DRV_B_20_DN")
	)
	(arc
		(start 278.642572 -200.894442)
		(mid 278.747282 -200.85107)
		(end 278.790654 -200.74636)
		(width 0.127)
		(layer "B.Cu")
		(net "PHY_SCC_B_TO_DRV_B_20_DN")
	)
	(arc
		(start 278.790654 -200.36536)
		(mid 278.942048 -199.999864)
		(end 279.307544 -199.84847)
		(width 0.127)
		(layer "B.Cu")
		(net "PHY_SCC_B_TO_DRV_B_20_DN")
	)
	(arc
		(start 382.7399 -128.7907)
		(mid 382.69199 -128.675034)
		(end 382.576324 -128.627124)
		(width 0.127)
		(layer "B.Cu")
		(net "PHY_SCC_B_TO_DRV_B_20_DN")
	)
	(segment
		(start 97.385632 -244.68582)
		(end 97.385632 -244.419374)
		(width 0.127)
		(layer "F.Cu")
		(net "PHY_SCC_B_TO_DRV_B_2_DP")
	)
	(segment
		(start 96.238822 -244.660674)
		(end 96.422972 -244.844824)
		(width 0.127)
		(layer "F.Cu")
		(net "PHY_SCC_B_TO_DRV_B_2_DP")
	)
	(segment
		(start 96.422972 -244.844824)
		(end 97.226628 -244.844824)
		(width 0.127)
		(layer "F.Cu")
		(net "PHY_SCC_B_TO_DRV_B_2_DP")
	)
	(segment
		(start 95.842836 -244.660674)
		(end 96.238822 -244.660674)
		(width 0.127)
		(layer "F.Cu")
		(net "PHY_SCC_B_TO_DRV_B_2_DP")
	)
	(arc
		(start 97.226628 -244.844824)
		(mid 97.339061 -244.798253)
		(end 97.385632 -244.68582)
		(width 0.127)
		(layer "F.Cu")
		(net "PHY_SCC_B_TO_DRV_B_2_DP")
	)
	(segment
		(start 97.385632 -244.710204)
		(end 97.385632 -244.419374)
		(width 0.127)
		(layer "B.Cu")
		(net "PHY_SCC_B_TO_DRV_B_2_DP")
	)
	(segment
		(start 269.956788 -232.248456)
		(end 258.678426 -234.6452)
		(width 0.127)
		(layer "B.Cu")
		(net "PHY_SCC_B_TO_DRV_B_2_DP")
	)
	(segment
		(start 98.180906 -244.844824)
		(end 97.520252 -244.844824)
		(width 0.127)
		(layer "B.Cu")
		(net "PHY_SCC_B_TO_DRV_B_2_DP")
	)
	(segment
		(start 279.082754 -233.08056)
		(end 279.082754 -232.90276)
		(width 0.127)
		(layer "B.Cu")
		(net "PHY_SCC_B_TO_DRV_B_2_DP")
	)
	(segment
		(start 207.39227 -223.744282)
		(end 122.115326 -241.151156)
		(width 0.127)
		(layer "B.Cu")
		(net "PHY_SCC_B_TO_DRV_B_2_DP")
	)
	(segment
		(start 278.42845 -232.248456)
		(end 269.956788 -232.248456)
		(width 0.127)
		(layer "B.Cu")
		(net "PHY_SCC_B_TO_DRV_B_2_DP")
	)
	(segment
		(start 258.678426 -234.6452)
		(end 207.39227 -223.744282)
		(width 0.127)
		(layer "B.Cu")
		(net "PHY_SCC_B_TO_DRV_B_2_DP")
	)
	(segment
		(start 122.115326 -241.151156)
		(end 98.180906 -244.844824)
		(width 0.127)
		(layer "B.Cu")
		(net "PHY_SCC_B_TO_DRV_B_2_DP")
	)
	(segment
		(start 279.636728 -233.294428)
		(end 279.296622 -233.294428)
		(width 0.127)
		(layer "B.Cu")
		(net "PHY_SCC_B_TO_DRV_B_2_DP")
	)
	(arc
		(start 279.082754 -232.90276)
		(mid 278.891113 -232.440097)
		(end 278.42845 -232.248456)
		(width 0.127)
		(layer "B.Cu")
		(net "PHY_SCC_B_TO_DRV_B_2_DP")
	)
	(arc
		(start 97.520252 -244.844824)
		(mid 97.425061 -244.805395)
		(end 97.385632 -244.710204)
		(width 0.127)
		(layer "B.Cu")
		(net "PHY_SCC_B_TO_DRV_B_2_DP")
	)
	(arc
		(start 279.296622 -233.294428)
		(mid 279.145394 -233.231788)
		(end 279.082754 -233.08056)
		(width 0.127)
		(layer "B.Cu")
		(net "PHY_SCC_B_TO_DRV_B_2_DP")
	)
	(segment
		(start 96.305624 -245.136924)
		(end 97.226628 -245.136924)
		(width 0.127)
		(layer "F.Cu")
		(net "PHY_SCC_B_TO_DRV_B_2_DN")
	)
	(segment
		(start 95.842836 -245.219474)
		(end 96.223074 -245.219474)
		(width 0.127)
		(layer "F.Cu")
		(net "PHY_SCC_B_TO_DRV_B_2_DN")
	)
	(segment
		(start 96.223074 -245.219474)
		(end 96.305624 -245.136924)
		(width 0.127)
		(layer "F.Cu")
		(net "PHY_SCC_B_TO_DRV_B_2_DN")
	)
	(segment
		(start 97.385632 -245.295928)
		(end 97.385632 -245.562374)
		(width 0.127)
		(layer "F.Cu")
		(net "PHY_SCC_B_TO_DRV_B_2_DN")
	)
	(arc
		(start 97.226628 -245.136924)
		(mid 97.339061 -245.183495)
		(end 97.385632 -245.295928)
		(width 0.127)
		(layer "F.Cu")
		(net "PHY_SCC_B_TO_DRV_B_2_DN")
	)
	(segment
		(start 97.385632 -245.281196)
		(end 97.385632 -245.562374)
		(width 0.127)
		(layer "B.Cu")
		(net "PHY_SCC_B_TO_DRV_B_2_DN")
	)
	(segment
		(start 278.790654 -233.08056)
		(end 278.790654 -232.90276)
		(width 0.127)
		(layer "B.Cu")
		(net "PHY_SCC_B_TO_DRV_B_2_DN")
	)
	(segment
		(start 136.461754 -238.676434)
		(end 136.088374 -238.752634)
		(width 0.127)
		(layer "B.Cu")
		(net "PHY_SCC_B_TO_DRV_B_2_DN")
	)
	(segment
		(start 134.371334 -239.103154)
		(end 133.997954 -239.179354)
		(width 0.127)
		(layer "B.Cu")
		(net "PHY_SCC_B_TO_DRV_B_2_DN")
	)
	(segment
		(start 269.987522 -232.540556)
		(end 258.678426 -234.943904)
		(width 0.127)
		(layer "B.Cu")
		(net "PHY_SCC_B_TO_DRV_B_2_DN")
	)
	(segment
		(start 135.535416 -238.710216)
		(end 135.416544 -238.889794)
		(width 0.127)
		(layer "B.Cu")
		(net "PHY_SCC_B_TO_DRV_B_2_DN")
	)
	(segment
		(start 132.772912 -239.274096)
		(end 122.166888 -241.438938)
		(width 0.127)
		(layer "B.Cu")
		(net "PHY_SCC_B_TO_DRV_B_2_DN")
	)
	(segment
		(start 136.580626 -238.496856)
		(end 136.461754 -238.676434)
		(width 0.127)
		(layer "B.Cu")
		(net "PHY_SCC_B_TO_DRV_B_2_DN")
	)
	(segment
		(start 278.42845 -232.540556)
		(end 269.987522 -232.540556)
		(width 0.127)
		(layer "B.Cu")
		(net "PHY_SCC_B_TO_DRV_B_2_DN")
	)
	(segment
		(start 135.043164 -238.965994)
		(end 134.863332 -238.847376)
		(width 0.127)
		(layer "B.Cu")
		(net "PHY_SCC_B_TO_DRV_B_2_DN")
	)
	(segment
		(start 207.391 -224.042732)
		(end 136.580626 -238.496856)
		(width 0.127)
		(layer "B.Cu")
		(net "PHY_SCC_B_TO_DRV_B_2_DN")
	)
	(segment
		(start 133.326124 -239.316514)
		(end 132.952744 -239.392714)
		(width 0.127)
		(layer "B.Cu")
		(net "PHY_SCC_B_TO_DRV_B_2_DN")
	)
	(segment
		(start 134.863332 -238.847376)
		(end 134.490206 -238.923576)
		(width 0.127)
		(layer "B.Cu")
		(net "PHY_SCC_B_TO_DRV_B_2_DN")
	)
	(segment
		(start 136.088374 -238.752634)
		(end 135.908542 -238.634016)
		(width 0.127)
		(layer "B.Cu")
		(net "PHY_SCC_B_TO_DRV_B_2_DN")
	)
	(segment
		(start 134.490206 -238.923576)
		(end 134.371334 -239.103154)
		(width 0.127)
		(layer "B.Cu")
		(net "PHY_SCC_B_TO_DRV_B_2_DN")
	)
	(segment
		(start 133.444742 -239.136936)
		(end 133.326124 -239.316514)
		(width 0.127)
		(layer "B.Cu")
		(net "PHY_SCC_B_TO_DRV_B_2_DN")
	)
	(segment
		(start 258.678426 -234.943904)
		(end 207.391 -224.042732)
		(width 0.127)
		(layer "B.Cu")
		(net "PHY_SCC_B_TO_DRV_B_2_DN")
	)
	(segment
		(start 122.166888 -241.438938)
		(end 98.203512 -245.136924)
		(width 0.127)
		(layer "B.Cu")
		(net "PHY_SCC_B_TO_DRV_B_2_DN")
	)
	(segment
		(start 133.818122 -239.060736)
		(end 133.444742 -239.136936)
		(width 0.127)
		(layer "B.Cu")
		(net "PHY_SCC_B_TO_DRV_B_2_DN")
	)
	(segment
		(start 133.997954 -239.179354)
		(end 133.818122 -239.060736)
		(width 0.127)
		(layer "B.Cu")
		(net "PHY_SCC_B_TO_DRV_B_2_DN")
	)
	(segment
		(start 98.203512 -245.136924)
		(end 97.529904 -245.136924)
		(width 0.127)
		(layer "B.Cu")
		(net "PHY_SCC_B_TO_DRV_B_2_DN")
	)
	(segment
		(start 278.23668 -233.294428)
		(end 278.576786 -233.294428)
		(width 0.127)
		(layer "B.Cu")
		(net "PHY_SCC_B_TO_DRV_B_2_DN")
	)
	(segment
		(start 135.416544 -238.889794)
		(end 135.043164 -238.965994)
		(width 0.127)
		(layer "B.Cu")
		(net "PHY_SCC_B_TO_DRV_B_2_DN")
	)
	(segment
		(start 132.952744 -239.392714)
		(end 132.772912 -239.274096)
		(width 0.127)
		(layer "B.Cu")
		(net "PHY_SCC_B_TO_DRV_B_2_DN")
	)
	(segment
		(start 135.908542 -238.634016)
		(end 135.535416 -238.710216)
		(width 0.127)
		(layer "B.Cu")
		(net "PHY_SCC_B_TO_DRV_B_2_DN")
	)
	(arc
		(start 97.529904 -245.136924)
		(mid 97.427888 -245.17918)
		(end 97.385632 -245.281196)
		(width 0.127)
		(layer "B.Cu")
		(net "PHY_SCC_B_TO_DRV_B_2_DN")
	)
	(arc
		(start 278.790654 -232.90276)
		(mid 278.684567 -232.646643)
		(end 278.42845 -232.540556)
		(width 0.127)
		(layer "B.Cu")
		(net "PHY_SCC_B_TO_DRV_B_2_DN")
	)
	(arc
		(start 278.576786 -233.294428)
		(mid 278.728014 -233.231788)
		(end 278.790654 -233.08056)
		(width 0.127)
		(layer "B.Cu")
		(net "PHY_SCC_B_TO_DRV_B_2_DN")
	)
	(segment
		(start 351.707958 -129.76098)
		(end 351.482152 -129.535174)
		(width 0.127)
		(layer "F.Cu")
		(net "PHY_SCC_B_TO_DRV_B_19_DP")
	)
	(segment
		(start 352.574098 -129.66065)
		(end 352.473768 -129.76098)
		(width 0.127)
		(layer "F.Cu")
		(net "PHY_SCC_B_TO_DRV_B_19_DP")
	)
	(segment
		(start 351.64268 -128.627124)
		(end 351.907602 -128.627124)
		(width 0.127)
		(layer "F.Cu")
		(net "PHY_SCC_B_TO_DRV_B_19_DP")
	)
	(segment
		(start 351.482152 -129.535174)
		(end 351.482152 -128.787652)
		(width 0.127)
		(layer "F.Cu")
		(net "PHY_SCC_B_TO_DRV_B_19_DP")
	)
	(segment
		(start 352.905314 -129.66065)
		(end 352.574098 -129.66065)
		(width 0.127)
		(layer "F.Cu")
		(net "PHY_SCC_B_TO_DRV_B_19_DP")
	)
	(segment
		(start 352.473768 -129.76098)
		(end 351.707958 -129.76098)
		(width 0.127)
		(layer "F.Cu")
		(net "PHY_SCC_B_TO_DRV_B_19_DP")
	)
	(arc
		(start 351.482152 -128.787652)
		(mid 351.52917 -128.674142)
		(end 351.64268 -128.627124)
		(width 0.127)
		(layer "F.Cu")
		(net "PHY_SCC_B_TO_DRV_B_19_DP")
	)
	(segment
		(start 280.082752 -198.946262)
		(end 280.082752 -198.565262)
		(width 0.127)
		(layer "B.Cu")
		(net "PHY_SCC_B_TO_DRV_B_19_DP")
	)
	(segment
		(start 323.31406 -173.626526)
		(end 323.52488 -173.581822)
		(width 0.127)
		(layer "B.Cu")
		(net "PHY_SCC_B_TO_DRV_B_19_DP")
	)
	(segment
		(start 280.636726 -199.094344)
		(end 280.230834 -199.094344)
		(width 0.127)
		(layer "B.Cu")
		(net "PHY_SCC_B_TO_DRV_B_19_DP")
	)
	(segment
		(start 280.307542 -198.340472)
		(end 291.40531 -198.340472)
		(width 0.127)
		(layer "B.Cu")
		(net "PHY_SCC_B_TO_DRV_B_19_DP")
	)
	(segment
		(start 322.362576 -175.371252)
		(end 322.570094 -175.05172)
		(width 0.127)
		(layer "B.Cu")
		(net "PHY_SCC_B_TO_DRV_B_19_DP")
	)
	(segment
		(start 323.68744 -173.05147)
		(end 351.482152 -130.25247)
		(width 0.127)
		(layer "B.Cu")
		(net "PHY_SCC_B_TO_DRV_B_19_DP")
	)
	(segment
		(start 306.812188 -195.066158)
		(end 311.270904 -192.170558)
		(width 0.127)
		(layer "B.Cu")
		(net "PHY_SCC_B_TO_DRV_B_19_DP")
	)
	(segment
		(start 323.106542 -173.946058)
		(end 323.31406 -173.626526)
		(width 0.127)
		(layer "B.Cu")
		(net "PHY_SCC_B_TO_DRV_B_19_DP")
	)
	(segment
		(start 322.151756 -175.415956)
		(end 322.362576 -175.371252)
		(width 0.127)
		(layer "B.Cu")
		(net "PHY_SCC_B_TO_DRV_B_19_DP")
	)
	(segment
		(start 291.40531 -198.340472)
		(end 306.812188 -195.066158)
		(width 0.127)
		(layer "B.Cu")
		(net "PHY_SCC_B_TO_DRV_B_19_DP")
	)
	(segment
		(start 321.989196 -175.946308)
		(end 321.944492 -175.735488)
		(width 0.127)
		(layer "B.Cu")
		(net "PHY_SCC_B_TO_DRV_B_19_DP")
	)
	(segment
		(start 322.570094 -175.05172)
		(end 322.52539 -174.8409)
		(width 0.127)
		(layer "B.Cu")
		(net "PHY_SCC_B_TO_DRV_B_19_DP")
	)
	(segment
		(start 323.732398 -173.26229)
		(end 323.68744 -173.05147)
		(width 0.127)
		(layer "B.Cu")
		(net "PHY_SCC_B_TO_DRV_B_19_DP")
	)
	(segment
		(start 311.270904 -192.170558)
		(end 321.570858 -176.310544)
		(width 0.127)
		(layer "B.Cu")
		(net "PHY_SCC_B_TO_DRV_B_19_DP")
	)
	(segment
		(start 351.64268 -128.627124)
		(end 351.907602 -128.627124)
		(width 0.127)
		(layer "B.Cu")
		(net "PHY_SCC_B_TO_DRV_B_19_DP")
	)
	(segment
		(start 321.570858 -176.310544)
		(end 321.781678 -176.26584)
		(width 0.127)
		(layer "B.Cu")
		(net "PHY_SCC_B_TO_DRV_B_19_DP")
	)
	(segment
		(start 322.943728 -174.47641)
		(end 323.151246 -174.156878)
		(width 0.127)
		(layer "B.Cu")
		(net "PHY_SCC_B_TO_DRV_B_19_DP")
	)
	(segment
		(start 323.52488 -173.581822)
		(end 323.732398 -173.26229)
		(width 0.127)
		(layer "B.Cu")
		(net "PHY_SCC_B_TO_DRV_B_19_DP")
	)
	(segment
		(start 321.781678 -176.26584)
		(end 321.989196 -175.946308)
		(width 0.127)
		(layer "B.Cu")
		(net "PHY_SCC_B_TO_DRV_B_19_DP")
	)
	(segment
		(start 351.482152 -130.25247)
		(end 351.482152 -128.787652)
		(width 0.127)
		(layer "B.Cu")
		(net "PHY_SCC_B_TO_DRV_B_19_DP")
	)
	(segment
		(start 321.944492 -175.735488)
		(end 322.151756 -175.415956)
		(width 0.127)
		(layer "B.Cu")
		(net "PHY_SCC_B_TO_DRV_B_19_DP")
	)
	(segment
		(start 322.732908 -174.521368)
		(end 322.943728 -174.47641)
		(width 0.127)
		(layer "B.Cu")
		(net "PHY_SCC_B_TO_DRV_B_19_DP")
	)
	(segment
		(start 323.151246 -174.156878)
		(end 323.106542 -173.946058)
		(width 0.127)
		(layer "B.Cu")
		(net "PHY_SCC_B_TO_DRV_B_19_DP")
	)
	(segment
		(start 322.52539 -174.8409)
		(end 322.732908 -174.521368)
		(width 0.127)
		(layer "B.Cu")
		(net "PHY_SCC_B_TO_DRV_B_19_DP")
	)
	(arc
		(start 280.230834 -199.094344)
		(mid 280.126124 -199.050972)
		(end 280.082752 -198.946262)
		(width 0.127)
		(layer "B.Cu")
		(net "PHY_SCC_B_TO_DRV_B_19_DP")
	)
	(arc
		(start 280.082752 -198.565262)
		(mid 280.148591 -198.406311)
		(end 280.307542 -198.340472)
		(width 0.127)
		(layer "B.Cu")
		(net "PHY_SCC_B_TO_DRV_B_19_DP")
	)
	(arc
		(start 351.482152 -128.787652)
		(mid 351.52917 -128.674142)
		(end 351.64268 -128.627124)
		(width 0.127)
		(layer "B.Cu")
		(net "PHY_SCC_B_TO_DRV_B_19_DP")
	)
	(segment
		(start 352.407728 -130.05308)
		(end 351.5868 -130.05308)
		(width 0.127)
		(layer "F.Cu")
		(net "PHY_SCC_B_TO_DRV_B_19_DN")
	)
	(segment
		(start 351.190052 -129.656332)
		(end 351.190052 -128.787652)
		(width 0.127)
		(layer "F.Cu")
		(net "PHY_SCC_B_TO_DRV_B_19_DN")
	)
	(segment
		(start 352.574098 -130.21945)
		(end 352.407728 -130.05308)
		(width 0.127)
		(layer "F.Cu")
		(net "PHY_SCC_B_TO_DRV_B_19_DN")
	)
	(segment
		(start 352.905314 -130.21945)
		(end 352.574098 -130.21945)
		(width 0.127)
		(layer "F.Cu")
		(net "PHY_SCC_B_TO_DRV_B_19_DN")
	)
	(segment
		(start 351.029524 -128.627124)
		(end 350.764602 -128.627124)
		(width 0.127)
		(layer "F.Cu")
		(net "PHY_SCC_B_TO_DRV_B_19_DN")
	)
	(segment
		(start 351.5868 -130.05308)
		(end 351.190052 -129.656332)
		(width 0.127)
		(layer "F.Cu")
		(net "PHY_SCC_B_TO_DRV_B_19_DN")
	)
	(arc
		(start 351.190052 -128.787652)
		(mid 351.143034 -128.674142)
		(end 351.029524 -128.627124)
		(width 0.127)
		(layer "F.Cu")
		(net "PHY_SCC_B_TO_DRV_B_19_DN")
	)
	(segment
		(start 311.059576 -191.95923)
		(end 351.190052 -130.165856)
		(width 0.127)
		(layer "B.Cu")
		(net "PHY_SCC_B_TO_DRV_B_19_DN")
	)
	(segment
		(start 306.698396 -194.791584)
		(end 311.059576 -191.95923)
		(width 0.127)
		(layer "B.Cu")
		(net "PHY_SCC_B_TO_DRV_B_19_DN")
	)
	(segment
		(start 351.029524 -128.627124)
		(end 350.764602 -128.627124)
		(width 0.127)
		(layer "B.Cu")
		(net "PHY_SCC_B_TO_DRV_B_19_DN")
	)
	(segment
		(start 279.236678 -199.094344)
		(end 279.64257 -199.094344)
		(width 0.127)
		(layer "B.Cu")
		(net "PHY_SCC_B_TO_DRV_B_19_DN")
	)
	(segment
		(start 280.307542 -198.048372)
		(end 291.374576 -198.048372)
		(width 0.127)
		(layer "B.Cu")
		(net "PHY_SCC_B_TO_DRV_B_19_DN")
	)
	(segment
		(start 291.374576 -198.048372)
		(end 306.698396 -194.791584)
		(width 0.127)
		(layer "B.Cu")
		(net "PHY_SCC_B_TO_DRV_B_19_DN")
	)
	(segment
		(start 279.790652 -198.946262)
		(end 279.790652 -198.565262)
		(width 0.127)
		(layer "B.Cu")
		(net "PHY_SCC_B_TO_DRV_B_19_DN")
	)
	(segment
		(start 351.190052 -130.165856)
		(end 351.190052 -128.787652)
		(width 0.127)
		(layer "B.Cu")
		(net "PHY_SCC_B_TO_DRV_B_19_DN")
	)
	(arc
		(start 279.64257 -199.094344)
		(mid 279.74728 -199.050972)
		(end 279.790652 -198.946262)
		(width 0.127)
		(layer "B.Cu")
		(net "PHY_SCC_B_TO_DRV_B_19_DN")
	)
	(arc
		(start 279.790652 -198.565262)
		(mid 279.942046 -198.199766)
		(end 280.307542 -198.048372)
		(width 0.127)
		(layer "B.Cu")
		(net "PHY_SCC_B_TO_DRV_B_19_DN")
	)
	(arc
		(start 351.190052 -128.787652)
		(mid 351.143034 -128.674142)
		(end 351.029524 -128.627124)
		(width 0.127)
		(layer "B.Cu")
		(net "PHY_SCC_B_TO_DRV_B_19_DN")
	)
	(segment
		(start 320.156586 -129.75971)
		(end 319.93205 -129.535174)
		(width 0.127)
		(layer "F.Cu")
		(net "PHY_SCC_B_TO_DRV_B_18_DP")
	)
	(segment
		(start 319.93205 -129.535174)
		(end 319.93205 -128.78435)
		(width 0.127)
		(layer "F.Cu")
		(net "PHY_SCC_B_TO_DRV_B_18_DP")
	)
	(segment
		(start 320.089276 -128.627124)
		(end 320.3575 -128.627124)
		(width 0.127)
		(layer "F.Cu")
		(net "PHY_SCC_B_TO_DRV_B_18_DP")
	)
	(segment
		(start 321.355212 -129.66065)
		(end 321.023996 -129.66065)
		(width 0.127)
		(layer "F.Cu")
		(net "PHY_SCC_B_TO_DRV_B_18_DP")
	)
	(segment
		(start 321.023996 -129.66065)
		(end 320.924936 -129.75971)
		(width 0.127)
		(layer "F.Cu")
		(net "PHY_SCC_B_TO_DRV_B_18_DP")
	)
	(segment
		(start 320.924936 -129.75971)
		(end 320.156586 -129.75971)
		(width 0.127)
		(layer "F.Cu")
		(net "PHY_SCC_B_TO_DRV_B_18_DP")
	)
	(arc
		(start 319.93205 -128.78435)
		(mid 319.9781 -128.673174)
		(end 320.089276 -128.627124)
		(width 0.127)
		(layer "F.Cu")
		(net "PHY_SCC_B_TO_DRV_B_18_DP")
	)
	(segment
		(start 321.03822 -151.424386)
		(end 321.117468 -151.051768)
		(width 0.127)
		(layer "B.Cu")
		(net "PHY_SCC_B_TO_DRV_B_18_DP")
	)
	(segment
		(start 321.00012 -150.87092)
		(end 321.079368 -150.498302)
		(width 0.127)
		(layer "B.Cu")
		(net "PHY_SCC_B_TO_DRV_B_18_DP")
	)
	(segment
		(start 320.895726 -152.0952)
		(end 320.778378 -151.914352)
		(width 0.127)
		(layer "B.Cu")
		(net "PHY_SCC_B_TO_DRV_B_18_DP")
	)
	(segment
		(start 279.307544 -196.540628)
		(end 290.061396 -196.540628)
		(width 0.127)
		(layer "B.Cu")
		(net "PHY_SCC_B_TO_DRV_B_18_DP")
	)
	(segment
		(start 321.444112 -148.784056)
		(end 322.581016 -143.437102)
		(width 0.127)
		(layer "B.Cu")
		(net "PHY_SCC_B_TO_DRV_B_18_DP")
	)
	(segment
		(start 279.636728 -197.2945)
		(end 279.230836 -197.2945)
		(width 0.127)
		(layer "B.Cu")
		(net "PHY_SCC_B_TO_DRV_B_18_DP")
	)
	(segment
		(start 321.222116 -149.827488)
		(end 321.301364 -149.45487)
		(width 0.127)
		(layer "B.Cu")
		(net "PHY_SCC_B_TO_DRV_B_18_DP")
	)
	(segment
		(start 321.260216 -150.380954)
		(end 321.339464 -150.008336)
		(width 0.127)
		(layer "B.Cu")
		(net "PHY_SCC_B_TO_DRV_B_18_DP")
	)
	(segment
		(start 290.061396 -196.540628)
		(end 306.931568 -192.955418)
		(width 0.127)
		(layer "B.Cu")
		(net "PHY_SCC_B_TO_DRV_B_18_DP")
	)
	(segment
		(start 320.63563 -152.585166)
		(end 320.816478 -152.467818)
		(width 0.127)
		(layer "B.Cu")
		(net "PHY_SCC_B_TO_DRV_B_18_DP")
	)
	(segment
		(start 320.816478 -152.467818)
		(end 320.895726 -152.0952)
		(width 0.127)
		(layer "B.Cu")
		(net "PHY_SCC_B_TO_DRV_B_18_DP")
	)
	(segment
		(start 313.823604 -184.618122)
		(end 320.63563 -152.585166)
		(width 0.127)
		(layer "B.Cu")
		(net "PHY_SCC_B_TO_DRV_B_18_DP")
	)
	(segment
		(start 321.56146 -148.964904)
		(end 321.444112 -148.784056)
		(width 0.127)
		(layer "B.Cu")
		(net "PHY_SCC_B_TO_DRV_B_18_DP")
	)
	(segment
		(start 322.581016 -143.437102)
		(end 319.93205 -130.834892)
		(width 0.127)
		(layer "B.Cu")
		(net "PHY_SCC_B_TO_DRV_B_18_DP")
	)
	(segment
		(start 309.48884 -191.294512)
		(end 313.823604 -184.618122)
		(width 0.127)
		(layer "B.Cu")
		(net "PHY_SCC_B_TO_DRV_B_18_DP")
	)
	(segment
		(start 320.089276 -128.627124)
		(end 320.3575 -128.627124)
		(width 0.127)
		(layer "B.Cu")
		(net "PHY_SCC_B_TO_DRV_B_18_DP")
	)
	(segment
		(start 279.082754 -197.146418)
		(end 279.082754 -196.765418)
		(width 0.127)
		(layer "B.Cu")
		(net "PHY_SCC_B_TO_DRV_B_18_DP")
	)
	(segment
		(start 320.778378 -151.914352)
		(end 320.857626 -151.541734)
		(width 0.127)
		(layer "B.Cu")
		(net "PHY_SCC_B_TO_DRV_B_18_DP")
	)
	(segment
		(start 319.93205 -130.834892)
		(end 319.93205 -128.78435)
		(width 0.127)
		(layer "B.Cu")
		(net "PHY_SCC_B_TO_DRV_B_18_DP")
	)
	(segment
		(start 321.482212 -149.337522)
		(end 321.56146 -148.964904)
		(width 0.127)
		(layer "B.Cu")
		(net "PHY_SCC_B_TO_DRV_B_18_DP")
	)
	(segment
		(start 321.079368 -150.498302)
		(end 321.260216 -150.380954)
		(width 0.127)
		(layer "B.Cu")
		(net "PHY_SCC_B_TO_DRV_B_18_DP")
	)
	(segment
		(start 321.301364 -149.45487)
		(end 321.482212 -149.337522)
		(width 0.127)
		(layer "B.Cu")
		(net "PHY_SCC_B_TO_DRV_B_18_DP")
	)
	(segment
		(start 306.931568 -192.955418)
		(end 309.48884 -191.294512)
		(width 0.127)
		(layer "B.Cu")
		(net "PHY_SCC_B_TO_DRV_B_18_DP")
	)
	(segment
		(start 321.117468 -151.051768)
		(end 321.00012 -150.87092)
		(width 0.127)
		(layer "B.Cu")
		(net "PHY_SCC_B_TO_DRV_B_18_DP")
	)
	(segment
		(start 320.857626 -151.541734)
		(end 321.03822 -151.424386)
		(width 0.127)
		(layer "B.Cu")
		(net "PHY_SCC_B_TO_DRV_B_18_DP")
	)
	(segment
		(start 321.339464 -150.008336)
		(end 321.222116 -149.827488)
		(width 0.127)
		(layer "B.Cu")
		(net "PHY_SCC_B_TO_DRV_B_18_DP")
	)
	(arc
		(start 279.230836 -197.2945)
		(mid 279.126126 -197.251128)
		(end 279.082754 -197.146418)
		(width 0.127)
		(layer "B.Cu")
		(net "PHY_SCC_B_TO_DRV_B_18_DP")
	)
	(arc
		(start 319.93205 -128.78435)
		(mid 319.9781 -128.673174)
		(end 320.089276 -128.627124)
		(width 0.127)
		(layer "B.Cu")
		(net "PHY_SCC_B_TO_DRV_B_18_DP")
	)
	(arc
		(start 279.082754 -196.765418)
		(mid 279.148593 -196.606467)
		(end 279.307544 -196.540628)
		(width 0.127)
		(layer "B.Cu")
		(net "PHY_SCC_B_TO_DRV_B_18_DP")
	)
	(segment
		(start 321.355212 -130.21945)
		(end 321.023996 -130.21945)
		(width 0.127)
		(layer "F.Cu")
		(net "PHY_SCC_B_TO_DRV_B_18_DN")
	)
	(segment
		(start 319.63995 -129.656332)
		(end 319.63995 -128.78435)
		(width 0.127)
		(layer "F.Cu")
		(net "PHY_SCC_B_TO_DRV_B_18_DN")
	)
	(segment
		(start 320.856356 -130.05181)
		(end 320.035428 -130.05181)
		(width 0.127)
		(layer "F.Cu")
		(net "PHY_SCC_B_TO_DRV_B_18_DN")
	)
	(segment
		(start 321.023996 -130.21945)
		(end 320.856356 -130.05181)
		(width 0.127)
		(layer "F.Cu")
		(net "PHY_SCC_B_TO_DRV_B_18_DN")
	)
	(segment
		(start 320.035428 -130.05181)
		(end 319.63995 -129.656332)
		(width 0.127)
		(layer "F.Cu")
		(net "PHY_SCC_B_TO_DRV_B_18_DN")
	)
	(segment
		(start 319.482724 -128.627124)
		(end 319.2145 -128.627124)
		(width 0.127)
		(layer "F.Cu")
		(net "PHY_SCC_B_TO_DRV_B_18_DN")
	)
	(arc
		(start 319.63995 -128.78435)
		(mid 319.5939 -128.673174)
		(end 319.482724 -128.627124)
		(width 0.127)
		(layer "F.Cu")
		(net "PHY_SCC_B_TO_DRV_B_18_DN")
	)
	(segment
		(start 313.54903 -184.50433)
		(end 322.282312 -143.436848)
		(width 0.127)
		(layer "B.Cu")
		(net "PHY_SCC_B_TO_DRV_B_18_DN")
	)
	(segment
		(start 322.282312 -143.436848)
		(end 322.282312 -143.436594)
		(width 0.127)
		(layer "B.Cu")
		(net "PHY_SCC_B_TO_DRV_B_18_DN")
	)
	(segment
		(start 290.030662 -196.248528)
		(end 306.817776 -192.680844)
		(width 0.127)
		(layer "B.Cu")
		(net "PHY_SCC_B_TO_DRV_B_18_DN")
	)
	(segment
		(start 319.63995 -130.865626)
		(end 319.63995 -128.78435)
		(width 0.127)
		(layer "B.Cu")
		(net "PHY_SCC_B_TO_DRV_B_18_DN")
	)
	(segment
		(start 278.790654 -197.146418)
		(end 278.790654 -196.765418)
		(width 0.127)
		(layer "B.Cu")
		(net "PHY_SCC_B_TO_DRV_B_18_DN")
	)
	(segment
		(start 306.817776 -192.680844)
		(end 309.277512 -191.083184)
		(width 0.127)
		(layer "B.Cu")
		(net "PHY_SCC_B_TO_DRV_B_18_DN")
	)
	(segment
		(start 319.482724 -128.627124)
		(end 319.2145 -128.627124)
		(width 0.127)
		(layer "B.Cu")
		(net "PHY_SCC_B_TO_DRV_B_18_DN")
	)
	(segment
		(start 309.277512 -191.083184)
		(end 313.54903 -184.50433)
		(width 0.127)
		(layer "B.Cu")
		(net "PHY_SCC_B_TO_DRV_B_18_DN")
	)
	(segment
		(start 279.307544 -196.248528)
		(end 290.030662 -196.248528)
		(width 0.127)
		(layer "B.Cu")
		(net "PHY_SCC_B_TO_DRV_B_18_DN")
	)
	(segment
		(start 278.23668 -197.2945)
		(end 278.642572 -197.2945)
		(width 0.127)
		(layer "B.Cu")
		(net "PHY_SCC_B_TO_DRV_B_18_DN")
	)
	(segment
		(start 322.282312 -143.436594)
		(end 319.63995 -130.865626)
		(width 0.127)
		(layer "B.Cu")
		(net "PHY_SCC_B_TO_DRV_B_18_DN")
	)
	(arc
		(start 278.642572 -197.2945)
		(mid 278.747282 -197.251128)
		(end 278.790654 -197.146418)
		(width 0.127)
		(layer "B.Cu")
		(net "PHY_SCC_B_TO_DRV_B_18_DN")
	)
	(arc
		(start 319.63995 -128.78435)
		(mid 319.5939 -128.673174)
		(end 319.482724 -128.627124)
		(width 0.127)
		(layer "B.Cu")
		(net "PHY_SCC_B_TO_DRV_B_18_DN")
	)
	(arc
		(start 278.790654 -196.765418)
		(mid 278.942048 -196.399922)
		(end 279.307544 -196.248528)
		(width 0.127)
		(layer "B.Cu")
		(net "PHY_SCC_B_TO_DRV_B_18_DN")
	)
	(segment
		(start 191.073024 -129.8448)
		(end 191.87668 -129.8448)
		(width 0.127)
		(layer "F.Cu")
		(net "PHY_SCC_B_TO_DRV_B_17_DP")
	)
	(segment
		(start 192.035684 -129.685796)
		(end 192.035684 -129.41935)
		(width 0.127)
		(layer "F.Cu")
		(net "PHY_SCC_B_TO_DRV_B_17_DP")
	)
	(segment
		(start 190.888874 -129.66065)
		(end 191.073024 -129.8448)
		(width 0.127)
		(layer "F.Cu")
		(net "PHY_SCC_B_TO_DRV_B_17_DP")
	)
	(segment
		(start 190.492888 -129.66065)
		(end 190.888874 -129.66065)
		(width 0.127)
		(layer "F.Cu")
		(net "PHY_SCC_B_TO_DRV_B_17_DP")
	)
	(arc
		(start 191.87668 -129.8448)
		(mid 191.989113 -129.798229)
		(end 192.035684 -129.685796)
		(width 0.127)
		(layer "F.Cu")
		(net "PHY_SCC_B_TO_DRV_B_17_DP")
	)
	(segment
		(start 262.09117 -204.289406)
		(end 229.038404 -182.824628)
		(width 0.127)
		(layer "B.Cu")
		(net "PHY_SCC_B_TO_DRV_B_17_DP")
	)
	(segment
		(start 193.099436 -129.897124)
		(end 192.852802 -129.8448)
		(width 0.127)
		(layer "B.Cu")
		(net "PHY_SCC_B_TO_DRV_B_17_DP")
	)
	(segment
		(start 192.035684 -129.71018)
		(end 192.035684 -129.41935)
		(width 0.127)
		(layer "B.Cu")
		(net "PHY_SCC_B_TO_DRV_B_17_DP")
	)
	(segment
		(start 278.42845 -207.048608)
		(end 275.072856 -207.048608)
		(width 0.127)
		(layer "B.Cu")
		(net "PHY_SCC_B_TO_DRV_B_17_DP")
	)
	(segment
		(start 229.038404 -182.824628)
		(end 210.665822 -164.452046)
		(width 0.127)
		(layer "B.Cu")
		(net "PHY_SCC_B_TO_DRV_B_17_DP")
	)
	(segment
		(start 196.299328 -142.329662)
		(end 193.84645 -130.734308)
		(width 0.127)
		(layer "B.Cu")
		(net "PHY_SCC_B_TO_DRV_B_17_DP")
	)
	(segment
		(start 279.636728 -208.09458)
		(end 279.296622 -208.09458)
		(width 0.127)
		(layer "B.Cu")
		(net "PHY_SCC_B_TO_DRV_B_17_DP")
	)
	(segment
		(start 210.665822 -164.452046)
		(end 196.299328 -142.329662)
		(width 0.127)
		(layer "B.Cu")
		(net "PHY_SCC_B_TO_DRV_B_17_DP")
	)
	(segment
		(start 279.082754 -207.880712)
		(end 279.082754 -207.702912)
		(width 0.127)
		(layer "B.Cu")
		(net "PHY_SCC_B_TO_DRV_B_17_DP")
	)
	(segment
		(start 192.852802 -129.8448)
		(end 192.170304 -129.8448)
		(width 0.127)
		(layer "B.Cu")
		(net "PHY_SCC_B_TO_DRV_B_17_DP")
	)
	(segment
		(start 275.072856 -207.048608)
		(end 262.09117 -204.289406)
		(width 0.127)
		(layer "B.Cu")
		(net "PHY_SCC_B_TO_DRV_B_17_DP")
	)
	(segment
		(start 193.451734 -130.126232)
		(end 193.099436 -129.897124)
		(width 0.127)
		(layer "B.Cu")
		(net "PHY_SCC_B_TO_DRV_B_17_DP")
	)
	(segment
		(start 193.84645 -130.734308)
		(end 193.451734 -130.126232)
		(width 0.127)
		(layer "B.Cu")
		(net "PHY_SCC_B_TO_DRV_B_17_DP")
	)
	(arc
		(start 279.082754 -207.702912)
		(mid 278.891113 -207.240249)
		(end 278.42845 -207.048608)
		(width 0.127)
		(layer "B.Cu")
		(net "PHY_SCC_B_TO_DRV_B_17_DP")
	)
	(arc
		(start 192.170304 -129.8448)
		(mid 192.075113 -129.805371)
		(end 192.035684 -129.71018)
		(width 0.127)
		(layer "B.Cu")
		(net "PHY_SCC_B_TO_DRV_B_17_DP")
	)
	(arc
		(start 279.296622 -208.09458)
		(mid 279.145394 -208.03194)
		(end 279.082754 -207.880712)
		(width 0.127)
		(layer "B.Cu")
		(net "PHY_SCC_B_TO_DRV_B_17_DP")
	)
	(segment
		(start 190.492888 -130.21945)
		(end 190.873126 -130.21945)
		(width 0.127)
		(layer "F.Cu")
		(net "PHY_SCC_B_TO_DRV_B_17_DN")
	)
	(segment
		(start 192.035684 -130.295904)
		(end 192.035684 -130.56235)
		(width 0.127)
		(layer "F.Cu")
		(net "PHY_SCC_B_TO_DRV_B_17_DN")
	)
	(segment
		(start 190.955676 -130.1369)
		(end 191.87668 -130.1369)
		(width 0.127)
		(layer "F.Cu")
		(net "PHY_SCC_B_TO_DRV_B_17_DN")
	)
	(segment
		(start 190.873126 -130.21945)
		(end 190.955676 -130.1369)
		(width 0.127)
		(layer "F.Cu")
		(net "PHY_SCC_B_TO_DRV_B_17_DN")
	)
	(arc
		(start 191.87668 -130.1369)
		(mid 191.989113 -130.183471)
		(end 192.035684 -130.295904)
		(width 0.127)
		(layer "F.Cu")
		(net "PHY_SCC_B_TO_DRV_B_17_DN")
	)
	(segment
		(start 208.539334 -162.012376)
		(end 208.587086 -161.787586)
		(width 0.127)
		(layer "B.Cu")
		(net "PHY_SCC_B_TO_DRV_B_17_DN")
	)
	(segment
		(start 209.131408 -162.924236)
		(end 209.17916 -162.699446)
		(width 0.127)
		(layer "B.Cu")
		(net "PHY_SCC_B_TO_DRV_B_17_DN")
	)
	(segment
		(start 192.985644 -130.171698)
		(end 192.821814 -130.1369)
		(width 0.127)
		(layer "B.Cu")
		(net "PHY_SCC_B_TO_DRV_B_17_DN")
	)
	(segment
		(start 208.168748 -161.423096)
		(end 207.96123 -161.103564)
		(width 0.127)
		(layer "B.Cu")
		(net "PHY_SCC_B_TO_DRV_B_17_DN")
	)
	(segment
		(start 261.977378 -204.56398)
		(end 228.853492 -183.052974)
		(width 0.127)
		(layer "B.Cu")
		(net "PHY_SCC_B_TO_DRV_B_17_DN")
	)
	(segment
		(start 228.853492 -183.052974)
		(end 210.437476 -164.636958)
		(width 0.127)
		(layer "B.Cu")
		(net "PHY_SCC_B_TO_DRV_B_17_DN")
	)
	(segment
		(start 208.379568 -161.468054)
		(end 208.168748 -161.423096)
		(width 0.127)
		(layer "B.Cu")
		(net "PHY_SCC_B_TO_DRV_B_17_DN")
	)
	(segment
		(start 207.425036 -159.998156)
		(end 196.024754 -142.4432)
		(width 0.127)
		(layer "B.Cu")
		(net "PHY_SCC_B_TO_DRV_B_17_DN")
	)
	(segment
		(start 208.971642 -162.379914)
		(end 208.746852 -162.331908)
		(width 0.127)
		(layer "B.Cu")
		(net "PHY_SCC_B_TO_DRV_B_17_DN")
	)
	(segment
		(start 210.437476 -164.636958)
		(end 209.563716 -163.29152)
		(width 0.127)
		(layer "B.Cu")
		(net "PHY_SCC_B_TO_DRV_B_17_DN")
	)
	(segment
		(start 209.17916 -162.699446)
		(end 208.971642 -162.379914)
		(width 0.127)
		(layer "B.Cu")
		(net "PHY_SCC_B_TO_DRV_B_17_DN")
	)
	(segment
		(start 207.587596 -160.528508)
		(end 207.380078 -160.208976)
		(width 0.127)
		(layer "B.Cu")
		(net "PHY_SCC_B_TO_DRV_B_17_DN")
	)
	(segment
		(start 193.240406 -130.337306)
		(end 192.985644 -130.171698)
		(width 0.127)
		(layer "B.Cu")
		(net "PHY_SCC_B_TO_DRV_B_17_DN")
	)
	(segment
		(start 192.821814 -130.1369)
		(end 192.179956 -130.1369)
		(width 0.127)
		(layer "B.Cu")
		(net "PHY_SCC_B_TO_DRV_B_17_DN")
	)
	(segment
		(start 209.338926 -163.243768)
		(end 209.131408 -162.924236)
		(width 0.127)
		(layer "B.Cu")
		(net "PHY_SCC_B_TO_DRV_B_17_DN")
	)
	(segment
		(start 196.024754 -142.4432)
		(end 193.571876 -130.847846)
		(width 0.127)
		(layer "B.Cu")
		(net "PHY_SCC_B_TO_DRV_B_17_DN")
	)
	(segment
		(start 208.005934 -160.892744)
		(end 207.798416 -160.573212)
		(width 0.127)
		(layer "B.Cu")
		(net "PHY_SCC_B_TO_DRV_B_17_DN")
	)
	(segment
		(start 275.042122 -207.340708)
		(end 261.977378 -204.56398)
		(width 0.127)
		(layer "B.Cu")
		(net "PHY_SCC_B_TO_DRV_B_17_DN")
	)
	(segment
		(start 278.23668 -208.09458)
		(end 278.576786 -208.09458)
		(width 0.127)
		(layer "B.Cu")
		(net "PHY_SCC_B_TO_DRV_B_17_DN")
	)
	(segment
		(start 208.746852 -162.331908)
		(end 208.539334 -162.012376)
		(width 0.127)
		(layer "B.Cu")
		(net "PHY_SCC_B_TO_DRV_B_17_DN")
	)
	(segment
		(start 193.571876 -130.847846)
		(end 193.240406 -130.337306)
		(width 0.127)
		(layer "B.Cu")
		(net "PHY_SCC_B_TO_DRV_B_17_DN")
	)
	(segment
		(start 208.587086 -161.787586)
		(end 208.379568 -161.468054)
		(width 0.127)
		(layer "B.Cu")
		(net "PHY_SCC_B_TO_DRV_B_17_DN")
	)
	(segment
		(start 278.42845 -207.340708)
		(end 275.042122 -207.340708)
		(width 0.127)
		(layer "B.Cu")
		(net "PHY_SCC_B_TO_DRV_B_17_DN")
	)
	(segment
		(start 207.96123 -161.103564)
		(end 208.005934 -160.892744)
		(width 0.127)
		(layer "B.Cu")
		(net "PHY_SCC_B_TO_DRV_B_17_DN")
	)
	(segment
		(start 278.790654 -207.880712)
		(end 278.790654 -207.702912)
		(width 0.127)
		(layer "B.Cu")
		(net "PHY_SCC_B_TO_DRV_B_17_DN")
	)
	(segment
		(start 209.563716 -163.29152)
		(end 209.338926 -163.243768)
		(width 0.127)
		(layer "B.Cu")
		(net "PHY_SCC_B_TO_DRV_B_17_DN")
	)
	(segment
		(start 207.798416 -160.573212)
		(end 207.587596 -160.528508)
		(width 0.127)
		(layer "B.Cu")
		(net "PHY_SCC_B_TO_DRV_B_17_DN")
	)
	(segment
		(start 192.035684 -130.281172)
		(end 192.035684 -130.56235)
		(width 0.127)
		(layer "B.Cu")
		(net "PHY_SCC_B_TO_DRV_B_17_DN")
	)
	(segment
		(start 207.380078 -160.208976)
		(end 207.425036 -159.998156)
		(width 0.127)
		(layer "B.Cu")
		(net "PHY_SCC_B_TO_DRV_B_17_DN")
	)
	(arc
		(start 192.179956 -130.1369)
		(mid 192.07794 -130.179156)
		(end 192.035684 -130.281172)
		(width 0.127)
		(layer "B.Cu")
		(net "PHY_SCC_B_TO_DRV_B_17_DN")
	)
	(arc
		(start 278.576786 -208.09458)
		(mid 278.728014 -208.03194)
		(end 278.790654 -207.880712)
		(width 0.127)
		(layer "B.Cu")
		(net "PHY_SCC_B_TO_DRV_B_17_DN")
	)
	(arc
		(start 278.790654 -207.702912)
		(mid 278.684567 -207.446795)
		(end 278.42845 -207.340708)
		(width 0.127)
		(layer "B.Cu")
		(net "PHY_SCC_B_TO_DRV_B_17_DN")
	)
	(segment
		(start 159.338772 -129.66065)
		(end 159.522922 -129.8448)
		(width 0.127)
		(layer "F.Cu")
		(net "PHY_SCC_B_TO_DRV_B_16_DP")
	)
	(segment
		(start 160.485582 -129.685796)
		(end 160.485582 -129.41935)
		(width 0.127)
		(layer "F.Cu")
		(net "PHY_SCC_B_TO_DRV_B_16_DP")
	)
	(segment
		(start 158.942786 -129.66065)
		(end 159.338772 -129.66065)
		(width 0.127)
		(layer "F.Cu")
		(net "PHY_SCC_B_TO_DRV_B_16_DP")
	)
	(segment
		(start 159.522922 -129.8448)
		(end 160.326578 -129.8448)
		(width 0.127)
		(layer "F.Cu")
		(net "PHY_SCC_B_TO_DRV_B_16_DP")
	)
	(arc
		(start 160.326578 -129.8448)
		(mid 160.439011 -129.798229)
		(end 160.485582 -129.685796)
		(width 0.127)
		(layer "F.Cu")
		(net "PHY_SCC_B_TO_DRV_B_16_DP")
	)
	(segment
		(start 242.298728 -202.842114)
		(end 184.023254 -164.997384)
		(width 0.127)
		(layer "B.Cu")
		(net "PHY_SCC_B_TO_DRV_B_16_DP")
	)
	(segment
		(start 270.556736 -208.848452)
		(end 242.298728 -202.842114)
		(width 0.127)
		(layer "B.Cu")
		(net "PHY_SCC_B_TO_DRV_B_16_DP")
	)
	(segment
		(start 280.636726 -209.894424)
		(end 280.29662 -209.894424)
		(width 0.127)
		(layer "B.Cu")
		(net "PHY_SCC_B_TO_DRV_B_16_DP")
	)
	(segment
		(start 184.023254 -164.997384)
		(end 161.315654 -130.030728)
		(width 0.127)
		(layer "B.Cu")
		(net "PHY_SCC_B_TO_DRV_B_16_DP")
	)
	(segment
		(start 279.428448 -208.848452)
		(end 270.556736 -208.848452)
		(width 0.127)
		(layer "B.Cu")
		(net "PHY_SCC_B_TO_DRV_B_16_DP")
	)
	(segment
		(start 161.029142 -129.8448)
		(end 160.620202 -129.8448)
		(width 0.127)
		(layer "B.Cu")
		(net "PHY_SCC_B_TO_DRV_B_16_DP")
	)
	(segment
		(start 280.082752 -209.680556)
		(end 280.082752 -209.502756)
		(width 0.127)
		(layer "B.Cu")
		(net "PHY_SCC_B_TO_DRV_B_16_DP")
	)
	(segment
		(start 161.315654 -130.030728)
		(end 161.029142 -129.8448)
		(width 0.127)
		(layer "B.Cu")
		(net "PHY_SCC_B_TO_DRV_B_16_DP")
	)
	(segment
		(start 160.485582 -129.71018)
		(end 160.485582 -129.41935)
		(width 0.127)
		(layer "B.Cu")
		(net "PHY_SCC_B_TO_DRV_B_16_DP")
	)
	(arc
		(start 280.29662 -209.894424)
		(mid 280.145392 -209.831784)
		(end 280.082752 -209.680556)
		(width 0.127)
		(layer "B.Cu")
		(net "PHY_SCC_B_TO_DRV_B_16_DP")
	)
	(arc
		(start 280.082752 -209.502756)
		(mid 279.891111 -209.040093)
		(end 279.428448 -208.848452)
		(width 0.127)
		(layer "B.Cu")
		(net "PHY_SCC_B_TO_DRV_B_16_DP")
	)
	(arc
		(start 160.620202 -129.8448)
		(mid 160.525011 -129.805371)
		(end 160.485582 -129.71018)
		(width 0.127)
		(layer "B.Cu")
		(net "PHY_SCC_B_TO_DRV_B_16_DP")
	)
	(segment
		(start 158.942786 -130.21945)
		(end 159.323024 -130.21945)
		(width 0.127)
		(layer "F.Cu")
		(net "PHY_SCC_B_TO_DRV_B_16_DN")
	)
	(segment
		(start 159.405574 -130.1369)
		(end 160.326578 -130.1369)
		(width 0.127)
		(layer "F.Cu")
		(net "PHY_SCC_B_TO_DRV_B_16_DN")
	)
	(segment
		(start 160.485582 -130.295904)
		(end 160.485582 -130.56235)
		(width 0.127)
		(layer "F.Cu")
		(net "PHY_SCC_B_TO_DRV_B_16_DN")
	)
	(segment
		(start 159.323024 -130.21945)
		(end 159.405574 -130.1369)
		(width 0.127)
		(layer "F.Cu")
		(net "PHY_SCC_B_TO_DRV_B_16_DN")
	)
	(arc
		(start 160.326578 -130.1369)
		(mid 160.439011 -130.183471)
		(end 160.485582 -130.295904)
		(width 0.127)
		(layer "F.Cu")
		(net "PHY_SCC_B_TO_DRV_B_16_DN")
	)
	(segment
		(start 168.438576 -141.815566)
		(end 168.231058 -141.496034)
		(width 0.127)
		(layer "B.Cu")
		(net "PHY_SCC_B_TO_DRV_B_16_DN")
	)
	(segment
		(start 167.113712 -139.495784)
		(end 161.104326 -130.242056)
		(width 0.127)
		(layer "B.Cu")
		(net "PHY_SCC_B_TO_DRV_B_16_DN")
	)
	(segment
		(start 167.857424 -140.920724)
		(end 167.649906 -140.601192)
		(width 0.127)
		(layer "B.Cu")
		(net "PHY_SCC_B_TO_DRV_B_16_DN")
	)
	(segment
		(start 242.184936 -203.116688)
		(end 183.811926 -165.208712)
		(width 0.127)
		(layer "B.Cu")
		(net "PHY_SCC_B_TO_DRV_B_16_DN")
	)
	(segment
		(start 183.811926 -165.208712)
		(end 169.230548 -142.755112)
		(width 0.127)
		(layer "B.Cu")
		(net "PHY_SCC_B_TO_DRV_B_16_DN")
	)
	(segment
		(start 168.068244 -140.965682)
		(end 167.857424 -140.920724)
		(width 0.127)
		(layer "B.Cu")
		(net "PHY_SCC_B_TO_DRV_B_16_DN")
	)
	(segment
		(start 270.526002 -209.140552)
		(end 242.184936 -203.116688)
		(width 0.127)
		(layer "B.Cu")
		(net "PHY_SCC_B_TO_DRV_B_16_DN")
	)
	(segment
		(start 279.790652 -209.680556)
		(end 279.790652 -209.502756)
		(width 0.127)
		(layer "B.Cu")
		(net "PHY_SCC_B_TO_DRV_B_16_DN")
	)
	(segment
		(start 160.485582 -130.281172)
		(end 160.485582 -130.56235)
		(width 0.127)
		(layer "B.Cu")
		(net "PHY_SCC_B_TO_DRV_B_16_DN")
	)
	(segment
		(start 279.236678 -209.894424)
		(end 279.576784 -209.894424)
		(width 0.127)
		(layer "B.Cu")
		(net "PHY_SCC_B_TO_DRV_B_16_DN")
	)
	(segment
		(start 168.856914 -142.179802)
		(end 168.649396 -141.86027)
		(width 0.127)
		(layer "B.Cu")
		(net "PHY_SCC_B_TO_DRV_B_16_DN")
	)
	(segment
		(start 167.276526 -140.026136)
		(end 167.069008 -139.706604)
		(width 0.127)
		(layer "B.Cu")
		(net "PHY_SCC_B_TO_DRV_B_16_DN")
	)
	(segment
		(start 169.230294 -142.755112)
		(end 169.019474 -142.710154)
		(width 0.127)
		(layer "B.Cu")
		(net "PHY_SCC_B_TO_DRV_B_16_DN")
	)
	(segment
		(start 168.275762 -141.285214)
		(end 168.068244 -140.965682)
		(width 0.127)
		(layer "B.Cu")
		(net "PHY_SCC_B_TO_DRV_B_16_DN")
	)
	(segment
		(start 168.811956 -142.390622)
		(end 168.856914 -142.179802)
		(width 0.127)
		(layer "B.Cu")
		(net "PHY_SCC_B_TO_DRV_B_16_DN")
	)
	(segment
		(start 168.231058 -141.496034)
		(end 168.275762 -141.285214)
		(width 0.127)
		(layer "B.Cu")
		(net "PHY_SCC_B_TO_DRV_B_16_DN")
	)
	(segment
		(start 279.428448 -209.140552)
		(end 270.526002 -209.140552)
		(width 0.127)
		(layer "B.Cu")
		(net "PHY_SCC_B_TO_DRV_B_16_DN")
	)
	(segment
		(start 161.104326 -130.242056)
		(end 160.942528 -130.1369)
		(width 0.127)
		(layer "B.Cu")
		(net "PHY_SCC_B_TO_DRV_B_16_DN")
	)
	(segment
		(start 169.230548 -142.755112)
		(end 169.230294 -142.755112)
		(width 0.127)
		(layer "B.Cu")
		(net "PHY_SCC_B_TO_DRV_B_16_DN")
	)
	(segment
		(start 167.069008 -139.706604)
		(end 167.113712 -139.495784)
		(width 0.127)
		(layer "B.Cu")
		(net "PHY_SCC_B_TO_DRV_B_16_DN")
	)
	(segment
		(start 167.649906 -140.601192)
		(end 167.694864 -140.390372)
		(width 0.127)
		(layer "B.Cu")
		(net "PHY_SCC_B_TO_DRV_B_16_DN")
	)
	(segment
		(start 167.694864 -140.390372)
		(end 167.487346 -140.07084)
		(width 0.127)
		(layer "B.Cu")
		(net "PHY_SCC_B_TO_DRV_B_16_DN")
	)
	(segment
		(start 160.942528 -130.1369)
		(end 160.629854 -130.1369)
		(width 0.127)
		(layer "B.Cu")
		(net "PHY_SCC_B_TO_DRV_B_16_DN")
	)
	(segment
		(start 168.649396 -141.86027)
		(end 168.438576 -141.815566)
		(width 0.127)
		(layer "B.Cu")
		(net "PHY_SCC_B_TO_DRV_B_16_DN")
	)
	(segment
		(start 167.487346 -140.07084)
		(end 167.276526 -140.026136)
		(width 0.127)
		(layer "B.Cu")
		(net "PHY_SCC_B_TO_DRV_B_16_DN")
	)
	(segment
		(start 169.019474 -142.710154)
		(end 168.811956 -142.390622)
		(width 0.127)
		(layer "B.Cu")
		(net "PHY_SCC_B_TO_DRV_B_16_DN")
	)
	(arc
		(start 160.629854 -130.1369)
		(mid 160.527838 -130.179156)
		(end 160.485582 -130.281172)
		(width 0.127)
		(layer "B.Cu")
		(net "PHY_SCC_B_TO_DRV_B_16_DN")
	)
	(arc
		(start 279.790652 -209.502756)
		(mid 279.684565 -209.246639)
		(end 279.428448 -209.140552)
		(width 0.127)
		(layer "B.Cu")
		(net "PHY_SCC_B_TO_DRV_B_16_DN")
	)
	(arc
		(start 279.576784 -209.894424)
		(mid 279.728012 -209.831784)
		(end 279.790652 -209.680556)
		(width 0.127)
		(layer "B.Cu")
		(net "PHY_SCC_B_TO_DRV_B_16_DN")
	)
	(segment
		(start 127.392684 -129.66065)
		(end 127.78867 -129.66065)
		(width 0.127)
		(layer "F.Cu")
		(net "PHY_SCC_B_TO_DRV_B_15_DP")
	)
	(segment
		(start 128.93548 -129.685796)
		(end 128.93548 -129.41935)
		(width 0.127)
		(layer "F.Cu")
		(net "PHY_SCC_B_TO_DRV_B_15_DP")
	)
	(segment
		(start 127.78867 -129.66065)
		(end 127.97282 -129.8448)
		(width 0.127)
		(layer "F.Cu")
		(net "PHY_SCC_B_TO_DRV_B_15_DP")
	)
	(segment
		(start 127.97282 -129.8448)
		(end 128.776476 -129.8448)
		(width 0.127)
		(layer "F.Cu")
		(net "PHY_SCC_B_TO_DRV_B_15_DP")
	)
	(arc
		(start 128.776476 -129.8448)
		(mid 128.888909 -129.798229)
		(end 128.93548 -129.685796)
		(width 0.127)
		(layer "F.Cu")
		(net "PHY_SCC_B_TO_DRV_B_15_DP")
	)
	(segment
		(start 129.916174 -129.8448)
		(end 129.0701 -129.8448)
		(width 0.127)
		(layer "B.Cu")
		(net "PHY_SCC_B_TO_DRV_B_15_DP")
	)
	(segment
		(start 277.32863 -210.64855)
		(end 272.234914 -211.731098)
		(width 0.127)
		(layer "B.Cu")
		(net "PHY_SCC_B_TO_DRV_B_15_DP")
	)
	(segment
		(start 279.082754 -211.480654)
		(end 279.082754 -211.302854)
		(width 0.127)
		(layer "B.Cu")
		(net "PHY_SCC_B_TO_DRV_B_15_DP")
	)
	(segment
		(start 278.42845 -210.64855)
		(end 277.32863 -210.64855)
		(width 0.127)
		(layer "B.Cu")
		(net "PHY_SCC_B_TO_DRV_B_15_DP")
	)
	(segment
		(start 128.93548 -129.71018)
		(end 128.93548 -129.41935)
		(width 0.127)
		(layer "B.Cu")
		(net "PHY_SCC_B_TO_DRV_B_15_DP")
	)
	(segment
		(start 272.234914 -211.731098)
		(end 240.775744 -205.045564)
		(width 0.127)
		(layer "B.Cu")
		(net "PHY_SCC_B_TO_DRV_B_15_DP")
	)
	(segment
		(start 240.775744 -205.045564)
		(end 143.472662 -141.856714)
		(width 0.127)
		(layer "B.Cu")
		(net "PHY_SCC_B_TO_DRV_B_15_DP")
	)
	(segment
		(start 279.636728 -211.694522)
		(end 279.296622 -211.694522)
		(width 0.127)
		(layer "B.Cu")
		(net "PHY_SCC_B_TO_DRV_B_15_DP")
	)
	(segment
		(start 143.472662 -141.856714)
		(end 129.916174 -129.8448)
		(width 0.127)
		(layer "B.Cu")
		(net "PHY_SCC_B_TO_DRV_B_15_DP")
	)
	(arc
		(start 129.0701 -129.8448)
		(mid 128.974909 -129.805371)
		(end 128.93548 -129.71018)
		(width 0.127)
		(layer "B.Cu")
		(net "PHY_SCC_B_TO_DRV_B_15_DP")
	)
	(arc
		(start 279.296622 -211.694522)
		(mid 279.145394 -211.631882)
		(end 279.082754 -211.480654)
		(width 0.127)
		(layer "B.Cu")
		(net "PHY_SCC_B_TO_DRV_B_15_DP")
	)
	(arc
		(start 279.082754 -211.302854)
		(mid 278.891113 -210.840191)
		(end 278.42845 -210.64855)
		(width 0.127)
		(layer "B.Cu")
		(net "PHY_SCC_B_TO_DRV_B_15_DP")
	)
	(segment
		(start 127.855472 -130.1369)
		(end 128.776476 -130.1369)
		(width 0.127)
		(layer "F.Cu")
		(net "PHY_SCC_B_TO_DRV_B_15_DN")
	)
	(segment
		(start 128.93548 -130.295904)
		(end 128.93548 -130.56235)
		(width 0.127)
		(layer "F.Cu")
		(net "PHY_SCC_B_TO_DRV_B_15_DN")
	)
	(segment
		(start 127.772922 -130.21945)
		(end 127.855472 -130.1369)
		(width 0.127)
		(layer "F.Cu")
		(net "PHY_SCC_B_TO_DRV_B_15_DN")
	)
	(segment
		(start 127.392684 -130.21945)
		(end 127.772922 -130.21945)
		(width 0.127)
		(layer "F.Cu")
		(net "PHY_SCC_B_TO_DRV_B_15_DN")
	)
	(arc
		(start 128.776476 -130.1369)
		(mid 128.888909 -130.183471)
		(end 128.93548 -130.295904)
		(width 0.127)
		(layer "F.Cu")
		(net "PHY_SCC_B_TO_DRV_B_15_DN")
	)
	(segment
		(start 178.429666 -165.100508)
		(end 178.381914 -164.875464)
		(width 0.127)
		(layer "B.Cu")
		(net "PHY_SCC_B_TO_DRV_B_15_DN")
	)
	(segment
		(start 278.23668 -211.694522)
		(end 278.576786 -211.694522)
		(width 0.127)
		(layer "B.Cu")
		(net "PHY_SCC_B_TO_DRV_B_15_DN")
	)
	(segment
		(start 129.805176 -130.1369)
		(end 129.079752 -130.1369)
		(width 0.127)
		(layer "B.Cu")
		(net "PHY_SCC_B_TO_DRV_B_15_DN")
	)
	(segment
		(start 178.974242 -165.26002)
		(end 178.749198 -165.308026)
		(width 0.127)
		(layer "B.Cu")
		(net "PHY_SCC_B_TO_DRV_B_15_DN")
	)
	(segment
		(start 159.587946 -152.85212)
		(end 159.542988 -152.6413)
		(width 0.127)
		(layer "B.Cu")
		(net "PHY_SCC_B_TO_DRV_B_15_DN")
	)
	(segment
		(start 159.542988 -152.6413)
		(end 143.295116 -142.089886)
		(width 0.127)
		(layer "B.Cu")
		(net "PHY_SCC_B_TO_DRV_B_15_DN")
	)
	(segment
		(start 179.885848 -165.852094)
		(end 179.661058 -165.9001)
		(width 0.127)
		(layer "B.Cu")
		(net "PHY_SCC_B_TO_DRV_B_15_DN")
	)
	(segment
		(start 160.118298 -153.014934)
		(end 159.907478 -153.059638)
		(width 0.127)
		(layer "B.Cu")
		(net "PHY_SCC_B_TO_DRV_B_15_DN")
	)
	(segment
		(start 178.381914 -164.875464)
		(end 161.012886 -153.596086)
		(width 0.127)
		(layer "B.Cu")
		(net "PHY_SCC_B_TO_DRV_B_15_DN")
	)
	(segment
		(start 272.234914 -212.029802)
		(end 240.661952 -205.320138)
		(width 0.127)
		(layer "B.Cu")
		(net "PHY_SCC_B_TO_DRV_B_15_DN")
	)
	(segment
		(start 128.93548 -130.281172)
		(end 128.93548 -130.56235)
		(width 0.127)
		(layer "B.Cu")
		(net "PHY_SCC_B_TO_DRV_B_15_DN")
	)
	(segment
		(start 179.293774 -165.467538)
		(end 178.974242 -165.26002)
		(width 0.127)
		(layer "B.Cu")
		(net "PHY_SCC_B_TO_DRV_B_15_DN")
	)
	(segment
		(start 240.661952 -205.320138)
		(end 179.885848 -165.852094)
		(width 0.127)
		(layer "B.Cu")
		(net "PHY_SCC_B_TO_DRV_B_15_DN")
	)
	(segment
		(start 160.482534 -153.433272)
		(end 160.43783 -153.222452)
		(width 0.127)
		(layer "B.Cu")
		(net "PHY_SCC_B_TO_DRV_B_15_DN")
	)
	(segment
		(start 160.802066 -153.64079)
		(end 160.482534 -153.433272)
		(width 0.127)
		(layer "B.Cu")
		(net "PHY_SCC_B_TO_DRV_B_15_DN")
	)
	(segment
		(start 160.43783 -153.222452)
		(end 160.118298 -153.014934)
		(width 0.127)
		(layer "B.Cu")
		(net "PHY_SCC_B_TO_DRV_B_15_DN")
	)
	(segment
		(start 179.661058 -165.9001)
		(end 179.341526 -165.692582)
		(width 0.127)
		(layer "B.Cu")
		(net "PHY_SCC_B_TO_DRV_B_15_DN")
	)
	(segment
		(start 143.295116 -142.089886)
		(end 129.805176 -130.1369)
		(width 0.127)
		(layer "B.Cu")
		(net "PHY_SCC_B_TO_DRV_B_15_DN")
	)
	(segment
		(start 178.749198 -165.308026)
		(end 178.429666 -165.100508)
		(width 0.127)
		(layer "B.Cu")
		(net "PHY_SCC_B_TO_DRV_B_15_DN")
	)
	(segment
		(start 179.341526 -165.692582)
		(end 179.293774 -165.467538)
		(width 0.127)
		(layer "B.Cu")
		(net "PHY_SCC_B_TO_DRV_B_15_DN")
	)
	(segment
		(start 278.42845 -210.94065)
		(end 277.359364 -210.94065)
		(width 0.127)
		(layer "B.Cu")
		(net "PHY_SCC_B_TO_DRV_B_15_DN")
	)
	(segment
		(start 278.790654 -211.480654)
		(end 278.790654 -211.302854)
		(width 0.127)
		(layer "B.Cu")
		(net "PHY_SCC_B_TO_DRV_B_15_DN")
	)
	(segment
		(start 161.012886 -153.596086)
		(end 160.802066 -153.64079)
		(width 0.127)
		(layer "B.Cu")
		(net "PHY_SCC_B_TO_DRV_B_15_DN")
	)
	(segment
		(start 277.359364 -210.94065)
		(end 272.234914 -212.029802)
		(width 0.127)
		(layer "B.Cu")
		(net "PHY_SCC_B_TO_DRV_B_15_DN")
	)
	(segment
		(start 159.907478 -153.059638)
		(end 159.587946 -152.85212)
		(width 0.127)
		(layer "B.Cu")
		(net "PHY_SCC_B_TO_DRV_B_15_DN")
	)
	(arc
		(start 278.790654 -211.302854)
		(mid 278.684567 -211.046737)
		(end 278.42845 -210.94065)
		(width 0.127)
		(layer "B.Cu")
		(net "PHY_SCC_B_TO_DRV_B_15_DN")
	)
	(arc
		(start 278.576786 -211.694522)
		(mid 278.728014 -211.631882)
		(end 278.790654 -211.480654)
		(width 0.127)
		(layer "B.Cu")
		(net "PHY_SCC_B_TO_DRV_B_15_DN")
	)
	(arc
		(start 129.079752 -130.1369)
		(mid 128.977736 -130.179156)
		(end 128.93548 -130.281172)
		(width 0.127)
		(layer "B.Cu")
		(net "PHY_SCC_B_TO_DRV_B_15_DN")
	)
	(segment
		(start 96.238822 -129.66065)
		(end 96.422972 -129.8448)
		(width 0.127)
		(layer "F.Cu")
		(net "PHY_SCC_B_TO_DRV_B_14_DP")
	)
	(segment
		(start 97.385632 -129.685796)
		(end 97.385632 -129.41935)
		(width 0.127)
		(layer "F.Cu")
		(net "PHY_SCC_B_TO_DRV_B_14_DP")
	)
	(segment
		(start 95.842836 -129.66065)
		(end 96.238822 -129.66065)
		(width 0.127)
		(layer "F.Cu")
		(net "PHY_SCC_B_TO_DRV_B_14_DP")
	)
	(segment
		(start 96.422972 -129.8448)
		(end 97.226628 -129.8448)
		(width 0.127)
		(layer "F.Cu")
		(net "PHY_SCC_B_TO_DRV_B_14_DP")
	)
	(arc
		(start 97.226628 -129.8448)
		(mid 97.339061 -129.798229)
		(end 97.385632 -129.685796)
		(width 0.127)
		(layer "F.Cu")
		(net "PHY_SCC_B_TO_DRV_B_14_DP")
	)
	(segment
		(start 280.636726 -213.494366)
		(end 280.29662 -213.494366)
		(width 0.127)
		(layer "B.Cu")
		(net "PHY_SCC_B_TO_DRV_B_14_DP")
	)
	(segment
		(start 279.428448 -212.448394)
		(end 276.377146 -212.448394)
		(width 0.127)
		(layer "B.Cu")
		(net "PHY_SCC_B_TO_DRV_B_14_DP")
	)
	(segment
		(start 131.541774 -136.91616)
		(end 98.234754 -129.8448)
		(width 0.127)
		(layer "B.Cu")
		(net "PHY_SCC_B_TO_DRV_B_14_DP")
	)
	(segment
		(start 270.273018 -213.744302)
		(end 239.909096 -207.291178)
		(width 0.127)
		(layer "B.Cu")
		(net "PHY_SCC_B_TO_DRV_B_14_DP")
	)
	(segment
		(start 280.082752 -213.280498)
		(end 280.082752 -213.102698)
		(width 0.127)
		(layer "B.Cu")
		(net "PHY_SCC_B_TO_DRV_B_14_DP")
	)
	(segment
		(start 276.377146 -212.448394)
		(end 270.273018 -213.744302)
		(width 0.127)
		(layer "B.Cu")
		(net "PHY_SCC_B_TO_DRV_B_14_DP")
	)
	(segment
		(start 98.234754 -129.8448)
		(end 97.520252 -129.8448)
		(width 0.127)
		(layer "B.Cu")
		(net "PHY_SCC_B_TO_DRV_B_14_DP")
	)
	(segment
		(start 97.385632 -129.71018)
		(end 97.385632 -129.41935)
		(width 0.127)
		(layer "B.Cu")
		(net "PHY_SCC_B_TO_DRV_B_14_DP")
	)
	(segment
		(start 239.909096 -207.291178)
		(end 131.541774 -136.91616)
		(width 0.127)
		(layer "B.Cu")
		(net "PHY_SCC_B_TO_DRV_B_14_DP")
	)
	(arc
		(start 280.082752 -213.102698)
		(mid 279.891111 -212.640035)
		(end 279.428448 -212.448394)
		(width 0.127)
		(layer "B.Cu")
		(net "PHY_SCC_B_TO_DRV_B_14_DP")
	)
	(arc
		(start 97.520252 -129.8448)
		(mid 97.425061 -129.805371)
		(end 97.385632 -129.71018)
		(width 0.127)
		(layer "B.Cu")
		(net "PHY_SCC_B_TO_DRV_B_14_DP")
	)
	(arc
		(start 280.29662 -213.494366)
		(mid 280.145392 -213.431726)
		(end 280.082752 -213.280498)
		(width 0.127)
		(layer "B.Cu")
		(net "PHY_SCC_B_TO_DRV_B_14_DP")
	)
	(segment
		(start 95.842836 -130.21945)
		(end 96.223074 -130.21945)
		(width 0.127)
		(layer "F.Cu")
		(net "PHY_SCC_B_TO_DRV_B_14_DN")
	)
	(segment
		(start 96.305624 -130.1369)
		(end 97.226628 -130.1369)
		(width 0.127)
		(layer "F.Cu")
		(net "PHY_SCC_B_TO_DRV_B_14_DN")
	)
	(segment
		(start 97.385632 -130.295904)
		(end 97.385632 -130.56235)
		(width 0.127)
		(layer "F.Cu")
		(net "PHY_SCC_B_TO_DRV_B_14_DN")
	)
	(segment
		(start 96.223074 -130.21945)
		(end 96.305624 -130.1369)
		(width 0.127)
		(layer "F.Cu")
		(net "PHY_SCC_B_TO_DRV_B_14_DN")
	)
	(arc
		(start 97.226628 -130.1369)
		(mid 97.339061 -130.183471)
		(end 97.385632 -130.295904)
		(width 0.127)
		(layer "F.Cu")
		(net "PHY_SCC_B_TO_DRV_B_14_DN")
	)
	(segment
		(start 239.795304 -207.565752)
		(end 186.383676 -172.879512)
		(width 0.127)
		(layer "B.Cu")
		(net "PHY_SCC_B_TO_DRV_B_14_DN")
	)
	(segment
		(start 184.594246 -171.717716)
		(end 184.383426 -171.76242)
		(width 0.127)
		(layer "B.Cu")
		(net "PHY_SCC_B_TO_DRV_B_14_DN")
	)
	(segment
		(start 97.385632 -130.281172)
		(end 97.385632 -130.56235)
		(width 0.127)
		(layer "B.Cu")
		(net "PHY_SCC_B_TO_DRV_B_14_DN")
	)
	(segment
		(start 184.958482 -172.1358)
		(end 184.913778 -171.92498)
		(width 0.127)
		(layer "B.Cu")
		(net "PHY_SCC_B_TO_DRV_B_14_DN")
	)
	(segment
		(start 98.20402 -130.1369)
		(end 97.529904 -130.1369)
		(width 0.127)
		(layer "B.Cu")
		(net "PHY_SCC_B_TO_DRV_B_14_DN")
	)
	(segment
		(start 270.273018 -214.043006)
		(end 239.795304 -207.565752)
		(width 0.127)
		(layer "B.Cu")
		(net "PHY_SCC_B_TO_DRV_B_14_DN")
	)
	(segment
		(start 184.913778 -171.92498)
		(end 184.594246 -171.717716)
		(width 0.127)
		(layer "B.Cu")
		(net "PHY_SCC_B_TO_DRV_B_14_DN")
	)
	(segment
		(start 186.383676 -172.879512)
		(end 186.172856 -172.92447)
		(width 0.127)
		(layer "B.Cu")
		(net "PHY_SCC_B_TO_DRV_B_14_DN")
	)
	(segment
		(start 184.063894 -171.554902)
		(end 184.01919 -171.344082)
		(width 0.127)
		(layer "B.Cu")
		(net "PHY_SCC_B_TO_DRV_B_14_DN")
	)
	(segment
		(start 185.488834 -172.298614)
		(end 185.278014 -172.343318)
		(width 0.127)
		(layer "B.Cu")
		(net "PHY_SCC_B_TO_DRV_B_14_DN")
	)
	(segment
		(start 276.40788 -212.740494)
		(end 270.273018 -214.043006)
		(width 0.127)
		(layer "B.Cu")
		(net "PHY_SCC_B_TO_DRV_B_14_DN")
	)
	(segment
		(start 184.01919 -171.344082)
		(end 183.699658 -171.136564)
		(width 0.127)
		(layer "B.Cu")
		(net "PHY_SCC_B_TO_DRV_B_14_DN")
	)
	(segment
		(start 185.853324 -172.716952)
		(end 185.808366 -172.506132)
		(width 0.127)
		(layer "B.Cu")
		(net "PHY_SCC_B_TO_DRV_B_14_DN")
	)
	(segment
		(start 183.699658 -171.136564)
		(end 183.488838 -171.181268)
		(width 0.127)
		(layer "B.Cu")
		(net "PHY_SCC_B_TO_DRV_B_14_DN")
	)
	(segment
		(start 279.236678 -213.494366)
		(end 279.576784 -213.494366)
		(width 0.127)
		(layer "B.Cu")
		(net "PHY_SCC_B_TO_DRV_B_14_DN")
	)
	(segment
		(start 185.808366 -172.506132)
		(end 185.488834 -172.298614)
		(width 0.127)
		(layer "B.Cu")
		(net "PHY_SCC_B_TO_DRV_B_14_DN")
	)
	(segment
		(start 186.172856 -172.92447)
		(end 185.853324 -172.716952)
		(width 0.127)
		(layer "B.Cu")
		(net "PHY_SCC_B_TO_DRV_B_14_DN")
	)
	(segment
		(start 131.428236 -137.190734)
		(end 98.20402 -130.1369)
		(width 0.127)
		(layer "B.Cu")
		(net "PHY_SCC_B_TO_DRV_B_14_DN")
	)
	(segment
		(start 183.488838 -171.181268)
		(end 183.169306 -170.974004)
		(width 0.127)
		(layer "B.Cu")
		(net "PHY_SCC_B_TO_DRV_B_14_DN")
	)
	(segment
		(start 184.383426 -171.76242)
		(end 184.063894 -171.554902)
		(width 0.127)
		(layer "B.Cu")
		(net "PHY_SCC_B_TO_DRV_B_14_DN")
	)
	(segment
		(start 183.124348 -170.763184)
		(end 131.428236 -137.190734)
		(width 0.127)
		(layer "B.Cu")
		(net "PHY_SCC_B_TO_DRV_B_14_DN")
	)
	(segment
		(start 279.428448 -212.740494)
		(end 276.40788 -212.740494)
		(width 0.127)
		(layer "B.Cu")
		(net "PHY_SCC_B_TO_DRV_B_14_DN")
	)
	(segment
		(start 183.169306 -170.974004)
		(end 183.124348 -170.763184)
		(width 0.127)
		(layer "B.Cu")
		(net "PHY_SCC_B_TO_DRV_B_14_DN")
	)
	(segment
		(start 279.790652 -213.280498)
		(end 279.790652 -213.102698)
		(width 0.127)
		(layer "B.Cu")
		(net "PHY_SCC_B_TO_DRV_B_14_DN")
	)
	(segment
		(start 185.278014 -172.343318)
		(end 184.958482 -172.1358)
		(width 0.127)
		(layer "B.Cu")
		(net "PHY_SCC_B_TO_DRV_B_14_DN")
	)
	(arc
		(start 97.529904 -130.1369)
		(mid 97.427888 -130.179156)
		(end 97.385632 -130.281172)
		(width 0.127)
		(layer "B.Cu")
		(net "PHY_SCC_B_TO_DRV_B_14_DN")
	)
	(arc
		(start 279.790652 -213.102698)
		(mid 279.684565 -212.846581)
		(end 279.428448 -212.740494)
		(width 0.127)
		(layer "B.Cu")
		(net "PHY_SCC_B_TO_DRV_B_14_DN")
	)
	(arc
		(start 279.576784 -213.494366)
		(mid 279.728012 -213.431726)
		(end 279.790652 -213.280498)
		(width 0.127)
		(layer "B.Cu")
		(net "PHY_SCC_B_TO_DRV_B_14_DN")
	)
	(segment
		(start 64.292734 -129.66065)
		(end 64.68872 -129.66065)
		(width 0.127)
		(layer "F.Cu")
		(net "PHY_SCC_B_TO_DRV_B_13_DP")
	)
	(segment
		(start 64.68872 -129.66065)
		(end 64.87287 -129.8448)
		(width 0.127)
		(layer "F.Cu")
		(net "PHY_SCC_B_TO_DRV_B_13_DP")
	)
	(segment
		(start 64.87287 -129.8448)
		(end 65.676526 -129.8448)
		(width 0.127)
		(layer "F.Cu")
		(net "PHY_SCC_B_TO_DRV_B_13_DP")
	)
	(segment
		(start 65.83553 -129.685796)
		(end 65.83553 -129.41935)
		(width 0.127)
		(layer "F.Cu")
		(net "PHY_SCC_B_TO_DRV_B_13_DP")
	)
	(arc
		(start 65.676526 -129.8448)
		(mid 65.788959 -129.798229)
		(end 65.83553 -129.685796)
		(width 0.127)
		(layer "F.Cu")
		(net "PHY_SCC_B_TO_DRV_B_13_DP")
	)
	(segment
		(start 66.722244 -129.8448)
		(end 65.97015 -129.8448)
		(width 0.127)
		(layer "B.Cu")
		(net "PHY_SCC_B_TO_DRV_B_13_DP")
	)
	(segment
		(start 153.14676 -155.45181)
		(end 83.288886 -140.603478)
		(width 0.127)
		(layer "B.Cu")
		(net "PHY_SCC_B_TO_DRV_B_13_DP")
	)
	(segment
		(start 236.26699 -209.43189)
		(end 153.14676 -155.45181)
		(width 0.127)
		(layer "B.Cu")
		(net "PHY_SCC_B_TO_DRV_B_13_DP")
	)
	(segment
		(start 83.288886 -140.603478)
		(end 66.722244 -129.8448)
		(width 0.127)
		(layer "B.Cu")
		(net "PHY_SCC_B_TO_DRV_B_13_DP")
	)
	(segment
		(start 279.636728 -215.294464)
		(end 279.296622 -215.294464)
		(width 0.127)
		(layer "B.Cu")
		(net "PHY_SCC_B_TO_DRV_B_13_DP")
	)
	(segment
		(start 65.83553 -129.71018)
		(end 65.83553 -129.41935)
		(width 0.127)
		(layer "B.Cu")
		(net "PHY_SCC_B_TO_DRV_B_13_DP")
	)
	(segment
		(start 278.42845 -214.248492)
		(end 275.54809 -214.248492)
		(width 0.127)
		(layer "B.Cu")
		(net "PHY_SCC_B_TO_DRV_B_13_DP")
	)
	(segment
		(start 275.54809 -214.248492)
		(end 267.237972 -216.015062)
		(width 0.127)
		(layer "B.Cu")
		(net "PHY_SCC_B_TO_DRV_B_13_DP")
	)
	(segment
		(start 267.237972 -216.015062)
		(end 236.26699 -209.43189)
		(width 0.127)
		(layer "B.Cu")
		(net "PHY_SCC_B_TO_DRV_B_13_DP")
	)
	(segment
		(start 279.082754 -215.080596)
		(end 279.082754 -214.902796)
		(width 0.127)
		(layer "B.Cu")
		(net "PHY_SCC_B_TO_DRV_B_13_DP")
	)
	(arc
		(start 65.97015 -129.8448)
		(mid 65.874959 -129.805371)
		(end 65.83553 -129.71018)
		(width 0.127)
		(layer "B.Cu")
		(net "PHY_SCC_B_TO_DRV_B_13_DP")
	)
	(arc
		(start 279.296622 -215.294464)
		(mid 279.145394 -215.231824)
		(end 279.082754 -215.080596)
		(width 0.127)
		(layer "B.Cu")
		(net "PHY_SCC_B_TO_DRV_B_13_DP")
	)
	(arc
		(start 279.082754 -214.902796)
		(mid 278.891113 -214.440133)
		(end 278.42845 -214.248492)
		(width 0.127)
		(layer "B.Cu")
		(net "PHY_SCC_B_TO_DRV_B_13_DP")
	)
	(segment
		(start 64.292734 -130.21945)
		(end 64.672972 -130.21945)
		(width 0.127)
		(layer "F.Cu")
		(net "PHY_SCC_B_TO_DRV_B_13_DN")
	)
	(segment
		(start 64.672972 -130.21945)
		(end 64.755522 -130.1369)
		(width 0.127)
		(layer "F.Cu")
		(net "PHY_SCC_B_TO_DRV_B_13_DN")
	)
	(segment
		(start 64.755522 -130.1369)
		(end 65.676526 -130.1369)
		(width 0.127)
		(layer "F.Cu")
		(net "PHY_SCC_B_TO_DRV_B_13_DN")
	)
	(segment
		(start 65.83553 -130.295904)
		(end 65.83553 -130.56235)
		(width 0.127)
		(layer "F.Cu")
		(net "PHY_SCC_B_TO_DRV_B_13_DN")
	)
	(arc
		(start 65.676526 -130.1369)
		(mid 65.788959 -130.183471)
		(end 65.83553 -130.295904)
		(width 0.127)
		(layer "F.Cu")
		(net "PHY_SCC_B_TO_DRV_B_13_DN")
	)
	(segment
		(start 155.83789 -157.729682)
		(end 155.518358 -157.522164)
		(width 0.127)
		(layer "B.Cu")
		(net "PHY_SCC_B_TO_DRV_B_13_DN")
	)
	(segment
		(start 156.4132 -158.103316)
		(end 156.368242 -157.892496)
		(width 0.127)
		(layer "B.Cu")
		(net "PHY_SCC_B_TO_DRV_B_13_DN")
	)
	(segment
		(start 155.518358 -157.522164)
		(end 155.473654 -157.311344)
		(width 0.127)
		(layer "B.Cu")
		(net "PHY_SCC_B_TO_DRV_B_13_DN")
	)
	(segment
		(start 157.307788 -158.684214)
		(end 157.263084 -158.473394)
		(width 0.127)
		(layer "B.Cu")
		(net "PHY_SCC_B_TO_DRV_B_13_DN")
	)
	(segment
		(start 156.732732 -158.310834)
		(end 156.4132 -158.103316)
		(width 0.127)
		(layer "B.Cu")
		(net "PHY_SCC_B_TO_DRV_B_13_DN")
	)
	(segment
		(start 278.23668 -215.294464)
		(end 278.576786 -215.294464)
		(width 0.127)
		(layer "B.Cu")
		(net "PHY_SCC_B_TO_DRV_B_13_DN")
	)
	(segment
		(start 66.635376 -130.1369)
		(end 65.979802 -130.1369)
		(width 0.127)
		(layer "B.Cu")
		(net "PHY_SCC_B_TO_DRV_B_13_DN")
	)
	(segment
		(start 278.790654 -215.080596)
		(end 278.790654 -214.902796)
		(width 0.127)
		(layer "B.Cu")
		(net "PHY_SCC_B_TO_DRV_B_13_DN")
	)
	(segment
		(start 156.943552 -158.265876)
		(end 156.732732 -158.310834)
		(width 0.127)
		(layer "B.Cu")
		(net "PHY_SCC_B_TO_DRV_B_13_DN")
	)
	(segment
		(start 157.263084 -158.473394)
		(end 156.943552 -158.265876)
		(width 0.127)
		(layer "B.Cu")
		(net "PHY_SCC_B_TO_DRV_B_13_DN")
	)
	(segment
		(start 155.473654 -157.311344)
		(end 153.032968 -155.726384)
		(width 0.127)
		(layer "B.Cu")
		(net "PHY_SCC_B_TO_DRV_B_13_DN")
	)
	(segment
		(start 158.732728 -159.427926)
		(end 158.521908 -159.472884)
		(width 0.127)
		(layer "B.Cu")
		(net "PHY_SCC_B_TO_DRV_B_13_DN")
	)
	(segment
		(start 156.04871 -157.684978)
		(end 155.83789 -157.729682)
		(width 0.127)
		(layer "B.Cu")
		(net "PHY_SCC_B_TO_DRV_B_13_DN")
	)
	(segment
		(start 158.521908 -159.472884)
		(end 158.202376 -159.265366)
		(width 0.127)
		(layer "B.Cu")
		(net "PHY_SCC_B_TO_DRV_B_13_DN")
	)
	(segment
		(start 158.157672 -159.054546)
		(end 157.83814 -158.847028)
		(width 0.127)
		(layer "B.Cu")
		(net "PHY_SCC_B_TO_DRV_B_13_DN")
	)
	(segment
		(start 278.42845 -214.540592)
		(end 275.578824 -214.540592)
		(width 0.127)
		(layer "B.Cu")
		(net "PHY_SCC_B_TO_DRV_B_13_DN")
	)
	(segment
		(start 153.032968 -155.726384)
		(end 83.175094 -140.878052)
		(width 0.127)
		(layer "B.Cu")
		(net "PHY_SCC_B_TO_DRV_B_13_DN")
	)
	(segment
		(start 156.368242 -157.892496)
		(end 156.04871 -157.684978)
		(width 0.127)
		(layer "B.Cu")
		(net "PHY_SCC_B_TO_DRV_B_13_DN")
	)
	(segment
		(start 267.237972 -216.313766)
		(end 236.153198 -209.706464)
		(width 0.127)
		(layer "B.Cu")
		(net "PHY_SCC_B_TO_DRV_B_13_DN")
	)
	(segment
		(start 236.153198 -209.706464)
		(end 158.732728 -159.427926)
		(width 0.127)
		(layer "B.Cu")
		(net "PHY_SCC_B_TO_DRV_B_13_DN")
	)
	(segment
		(start 275.578824 -214.540592)
		(end 267.237972 -216.313766)
		(width 0.127)
		(layer "B.Cu")
		(net "PHY_SCC_B_TO_DRV_B_13_DN")
	)
	(segment
		(start 65.83553 -130.281172)
		(end 65.83553 -130.56235)
		(width 0.127)
		(layer "B.Cu")
		(net "PHY_SCC_B_TO_DRV_B_13_DN")
	)
	(segment
		(start 157.83814 -158.847028)
		(end 157.62732 -158.891732)
		(width 0.127)
		(layer "B.Cu")
		(net "PHY_SCC_B_TO_DRV_B_13_DN")
	)
	(segment
		(start 157.62732 -158.891732)
		(end 157.307788 -158.684214)
		(width 0.127)
		(layer "B.Cu")
		(net "PHY_SCC_B_TO_DRV_B_13_DN")
	)
	(segment
		(start 158.202376 -159.265366)
		(end 158.157672 -159.054546)
		(width 0.127)
		(layer "B.Cu")
		(net "PHY_SCC_B_TO_DRV_B_13_DN")
	)
	(segment
		(start 83.175094 -140.878052)
		(end 66.635376 -130.1369)
		(width 0.127)
		(layer "B.Cu")
		(net "PHY_SCC_B_TO_DRV_B_13_DN")
	)
	(arc
		(start 65.979802 -130.1369)
		(mid 65.877786 -130.179156)
		(end 65.83553 -130.281172)
		(width 0.127)
		(layer "B.Cu")
		(net "PHY_SCC_B_TO_DRV_B_13_DN")
	)
	(arc
		(start 278.576786 -215.294464)
		(mid 278.728014 -215.231824)
		(end 278.790654 -215.080596)
		(width 0.127)
		(layer "B.Cu")
		(net "PHY_SCC_B_TO_DRV_B_13_DN")
	)
	(arc
		(start 278.790654 -214.902796)
		(mid 278.684567 -214.646679)
		(end 278.42845 -214.540592)
		(width 0.127)
		(layer "B.Cu")
		(net "PHY_SCC_B_TO_DRV_B_13_DN")
	)
	(segment
		(start 34.285682 -129.685796)
		(end 34.285682 -129.41935)
		(width 0.127)
		(layer "F.Cu")
		(net "PHY_SCC_B_TO_DRV_B_12_DP")
	)
	(segment
		(start 33.323022 -129.8448)
		(end 34.126678 -129.8448)
		(width 0.127)
		(layer "F.Cu")
		(net "PHY_SCC_B_TO_DRV_B_12_DP")
	)
	(segment
		(start 32.742886 -129.66065)
		(end 33.138872 -129.66065)
		(width 0.127)
		(layer "F.Cu")
		(net "PHY_SCC_B_TO_DRV_B_12_DP")
	)
	(segment
		(start 33.138872 -129.66065)
		(end 33.323022 -129.8448)
		(width 0.127)
		(layer "F.Cu")
		(net "PHY_SCC_B_TO_DRV_B_12_DP")
	)
	(arc
		(start 34.126678 -129.8448)
		(mid 34.239111 -129.798229)
		(end 34.285682 -129.685796)
		(width 0.127)
		(layer "F.Cu")
		(net "PHY_SCC_B_TO_DRV_B_12_DP")
	)
	(segment
		(start 51.755802 -132.326634)
		(end 35.52698 -129.8448)
		(width 0.127)
		(layer "B.Cu")
		(net "PHY_SCC_B_TO_DRV_B_12_DP")
	)
	(segment
		(start 64.727328 -140.753338)
		(end 51.755802 -132.326634)
		(width 0.127)
		(layer "B.Cu")
		(net "PHY_SCC_B_TO_DRV_B_12_DP")
	)
	(segment
		(start 267.300964 -217.641424)
		(end 231.62133 -210.056984)
		(width 0.127)
		(layer "B.Cu")
		(net "PHY_SCC_B_TO_DRV_B_12_DP")
	)
	(segment
		(start 280.082752 -216.880694)
		(end 280.082752 -216.702894)
		(width 0.127)
		(layer "B.Cu")
		(net "PHY_SCC_B_TO_DRV_B_12_DP")
	)
	(segment
		(start 35.52698 -129.8448)
		(end 34.420302 -129.8448)
		(width 0.127)
		(layer "B.Cu")
		(net "PHY_SCC_B_TO_DRV_B_12_DP")
	)
	(segment
		(start 280.636726 -217.094562)
		(end 280.29662 -217.094562)
		(width 0.127)
		(layer "B.Cu")
		(net "PHY_SCC_B_TO_DRV_B_12_DP")
	)
	(segment
		(start 154.13736 -159.757872)
		(end 64.727328 -140.753338)
		(width 0.127)
		(layer "B.Cu")
		(net "PHY_SCC_B_TO_DRV_B_12_DP")
	)
	(segment
		(start 279.428448 -216.04859)
		(end 274.79498 -216.04859)
		(width 0.127)
		(layer "B.Cu")
		(net "PHY_SCC_B_TO_DRV_B_12_DP")
	)
	(segment
		(start 274.79498 -216.04859)
		(end 267.300964 -217.641424)
		(width 0.127)
		(layer "B.Cu")
		(net "PHY_SCC_B_TO_DRV_B_12_DP")
	)
	(segment
		(start 231.62133 -210.056984)
		(end 154.13736 -159.757872)
		(width 0.127)
		(layer "B.Cu")
		(net "PHY_SCC_B_TO_DRV_B_12_DP")
	)
	(segment
		(start 34.285682 -129.71018)
		(end 34.285682 -129.41935)
		(width 0.127)
		(layer "B.Cu")
		(net "PHY_SCC_B_TO_DRV_B_12_DP")
	)
	(arc
		(start 280.29662 -217.094562)
		(mid 280.145392 -217.031922)
		(end 280.082752 -216.880694)
		(width 0.127)
		(layer "B.Cu")
		(net "PHY_SCC_B_TO_DRV_B_12_DP")
	)
	(arc
		(start 280.082752 -216.702894)
		(mid 279.891111 -216.240231)
		(end 279.428448 -216.04859)
		(width 0.127)
		(layer "B.Cu")
		(net "PHY_SCC_B_TO_DRV_B_12_DP")
	)
	(arc
		(start 34.420302 -129.8448)
		(mid 34.325111 -129.805371)
		(end 34.285682 -129.71018)
		(width 0.127)
		(layer "B.Cu")
		(net "PHY_SCC_B_TO_DRV_B_12_DP")
	)
	(segment
		(start 33.123124 -130.21945)
		(end 33.205674 -130.1369)
		(width 0.127)
		(layer "F.Cu")
		(net "PHY_SCC_B_TO_DRV_B_12_DN")
	)
	(segment
		(start 33.205674 -130.1369)
		(end 34.126678 -130.1369)
		(width 0.127)
		(layer "F.Cu")
		(net "PHY_SCC_B_TO_DRV_B_12_DN")
	)
	(segment
		(start 34.285682 -130.295904)
		(end 34.285682 -130.56235)
		(width 0.127)
		(layer "F.Cu")
		(net "PHY_SCC_B_TO_DRV_B_12_DN")
	)
	(segment
		(start 32.742886 -130.21945)
		(end 33.123124 -130.21945)
		(width 0.127)
		(layer "F.Cu")
		(net "PHY_SCC_B_TO_DRV_B_12_DN")
	)
	(arc
		(start 34.126678 -130.1369)
		(mid 34.239111 -130.183471)
		(end 34.285682 -130.295904)
		(width 0.127)
		(layer "F.Cu")
		(net "PHY_SCC_B_TO_DRV_B_12_DN")
	)
	(segment
		(start 64.613536 -141.027912)
		(end 51.649376 -132.606034)
		(width 0.127)
		(layer "B.Cu")
		(net "PHY_SCC_B_TO_DRV_B_12_DN")
	)
	(segment
		(start 193.959988 -185.957464)
		(end 193.749168 -186.002422)
		(width 0.127)
		(layer "B.Cu")
		(net "PHY_SCC_B_TO_DRV_B_12_DN")
	)
	(segment
		(start 191.959738 -184.840626)
		(end 191.640206 -184.633108)
		(width 0.127)
		(layer "B.Cu")
		(net "PHY_SCC_B_TO_DRV_B_12_DN")
	)
	(segment
		(start 35.504628 -130.1369)
		(end 34.429954 -130.1369)
		(width 0.127)
		(layer "B.Cu")
		(net "PHY_SCC_B_TO_DRV_B_12_DN")
	)
	(segment
		(start 192.49009 -185.003186)
		(end 192.170558 -184.795668)
		(width 0.127)
		(layer "B.Cu")
		(net "PHY_SCC_B_TO_DRV_B_12_DN")
	)
	(segment
		(start 34.285682 -130.281172)
		(end 34.285682 -130.56235)
		(width 0.127)
		(layer "B.Cu")
		(net "PHY_SCC_B_TO_DRV_B_12_DN")
	)
	(segment
		(start 154.023822 -160.032446)
		(end 64.613536 -141.027912)
		(width 0.127)
		(layer "B.Cu")
		(net "PHY_SCC_B_TO_DRV_B_12_DN")
	)
	(segment
		(start 192.170558 -184.795668)
		(end 191.959738 -184.840626)
		(width 0.127)
		(layer "B.Cu")
		(net "PHY_SCC_B_TO_DRV_B_12_DN")
	)
	(segment
		(start 192.535048 -185.214006)
		(end 192.49009 -185.003186)
		(width 0.127)
		(layer "B.Cu")
		(net "PHY_SCC_B_TO_DRV_B_12_DN")
	)
	(segment
		(start 194.85483 -186.538362)
		(end 194.64401 -186.583066)
		(width 0.127)
		(layer "B.Cu")
		(net "PHY_SCC_B_TO_DRV_B_12_DN")
	)
	(segment
		(start 267.300964 -217.940128)
		(end 231.507792 -210.331558)
		(width 0.127)
		(layer "B.Cu")
		(net "PHY_SCC_B_TO_DRV_B_12_DN")
	)
	(segment
		(start 51.649376 -132.606034)
		(end 35.504628 -130.1369)
		(width 0.127)
		(layer "B.Cu")
		(net "PHY_SCC_B_TO_DRV_B_12_DN")
	)
	(segment
		(start 274.825714 -216.34069)
		(end 267.300964 -217.940128)
		(width 0.127)
		(layer "B.Cu")
		(net "PHY_SCC_B_TO_DRV_B_12_DN")
	)
	(segment
		(start 279.236678 -217.094562)
		(end 279.576784 -217.094562)
		(width 0.127)
		(layer "B.Cu")
		(net "PHY_SCC_B_TO_DRV_B_12_DN")
	)
	(segment
		(start 193.749168 -186.002422)
		(end 193.429636 -185.794904)
		(width 0.127)
		(layer "B.Cu")
		(net "PHY_SCC_B_TO_DRV_B_12_DN")
	)
	(segment
		(start 191.640206 -184.633108)
		(end 191.595248 -184.422288)
		(width 0.127)
		(layer "B.Cu")
		(net "PHY_SCC_B_TO_DRV_B_12_DN")
	)
	(segment
		(start 194.64401 -186.583066)
		(end 194.324478 -186.375802)
		(width 0.127)
		(layer "B.Cu")
		(net "PHY_SCC_B_TO_DRV_B_12_DN")
	)
	(segment
		(start 231.507792 -210.331558)
		(end 194.85483 -186.538362)
		(width 0.127)
		(layer "B.Cu")
		(net "PHY_SCC_B_TO_DRV_B_12_DN")
	)
	(segment
		(start 192.85458 -185.421524)
		(end 192.535048 -185.214006)
		(width 0.127)
		(layer "B.Cu")
		(net "PHY_SCC_B_TO_DRV_B_12_DN")
	)
	(segment
		(start 191.595248 -184.422288)
		(end 154.023822 -160.032446)
		(width 0.127)
		(layer "B.Cu")
		(net "PHY_SCC_B_TO_DRV_B_12_DN")
	)
	(segment
		(start 193.429636 -185.794904)
		(end 193.384932 -185.584084)
		(width 0.127)
		(layer "B.Cu")
		(net "PHY_SCC_B_TO_DRV_B_12_DN")
	)
	(segment
		(start 194.324478 -186.375802)
		(end 194.279774 -186.164982)
		(width 0.127)
		(layer "B.Cu")
		(net "PHY_SCC_B_TO_DRV_B_12_DN")
	)
	(segment
		(start 193.0654 -185.376566)
		(end 192.85458 -185.421524)
		(width 0.127)
		(layer "B.Cu")
		(net "PHY_SCC_B_TO_DRV_B_12_DN")
	)
	(segment
		(start 193.384932 -185.584084)
		(end 193.0654 -185.376566)
		(width 0.127)
		(layer "B.Cu")
		(net "PHY_SCC_B_TO_DRV_B_12_DN")
	)
	(segment
		(start 279.428448 -216.34069)
		(end 274.825714 -216.34069)
		(width 0.127)
		(layer "B.Cu")
		(net "PHY_SCC_B_TO_DRV_B_12_DN")
	)
	(segment
		(start 279.790652 -216.880694)
		(end 279.790652 -216.702894)
		(width 0.127)
		(layer "B.Cu")
		(net "PHY_SCC_B_TO_DRV_B_12_DN")
	)
	(segment
		(start 194.279774 -186.164982)
		(end 193.959988 -185.957464)
		(width 0.127)
		(layer "B.Cu")
		(net "PHY_SCC_B_TO_DRV_B_12_DN")
	)
	(arc
		(start 279.790652 -216.702894)
		(mid 279.684565 -216.446777)
		(end 279.428448 -216.34069)
		(width 0.127)
		(layer "B.Cu")
		(net "PHY_SCC_B_TO_DRV_B_12_DN")
	)
	(arc
		(start 279.576784 -217.094562)
		(mid 279.728012 -217.031922)
		(end 279.790652 -216.880694)
		(width 0.127)
		(layer "B.Cu")
		(net "PHY_SCC_B_TO_DRV_B_12_DN")
	)
	(arc
		(start 34.429954 -130.1369)
		(mid 34.327938 -130.179156)
		(end 34.285682 -130.281172)
		(width 0.127)
		(layer "B.Cu")
		(net "PHY_SCC_B_TO_DRV_B_12_DN")
	)
	(segment
		(start 477.152462 -244.55247)
		(end 477.152462 -244.312694)
		(width 0.127)
		(layer "F.Cu")
		(net "PHY_SCC_B_TO_DRV_B_11_DP")
	)
	(segment
		(start 478.773998 -244.660674)
		(end 478.696528 -244.738144)
		(width 0.127)
		(layer "F.Cu")
		(net "PHY_SCC_B_TO_DRV_B_11_DP")
	)
	(segment
		(start 478.696528 -244.738144)
		(end 477.338136 -244.738144)
		(width 0.127)
		(layer "F.Cu")
		(net "PHY_SCC_B_TO_DRV_B_11_DP")
	)
	(segment
		(start 479.105214 -244.660674)
		(end 478.773998 -244.660674)
		(width 0.127)
		(layer "F.Cu")
		(net "PHY_SCC_B_TO_DRV_B_11_DP")
	)
	(arc
		(start 477.338136 -244.738144)
		(mid 477.206845 -244.683761)
		(end 477.152462 -244.55247)
		(width 0.127)
		(layer "F.Cu")
		(net "PHY_SCC_B_TO_DRV_B_11_DP")
	)
	(segment
		(start 434.996336 -235.761022)
		(end 435.374542 -235.80725)
		(width 0.127)
		(layer "B.Cu")
		(net "PHY_SCC_B_TO_DRV_B_11_DP")
	)
	(segment
		(start 435.50713 -235.977176)
		(end 435.885336 -236.023658)
		(width 0.127)
		(layer "B.Cu")
		(net "PHY_SCC_B_TO_DRV_B_11_DP")
	)
	(segment
		(start 437.492394 -236.067092)
		(end 437.624982 -236.236764)
		(width 0.127)
		(layer "B.Cu")
		(net "PHY_SCC_B_TO_DRV_B_11_DP")
	)
	(segment
		(start 436.566056 -236.10697)
		(end 436.944262 -236.153452)
		(width 0.127)
		(layer "B.Cu")
		(net "PHY_SCC_B_TO_DRV_B_11_DP")
	)
	(segment
		(start 279.082754 -219.1004)
		(end 279.082754 -219.329)
		(width 0.127)
		(layer "B.Cu")
		(net "PHY_SCC_B_TO_DRV_B_11_DP")
	)
	(segment
		(start 279.636728 -218.894406)
		(end 279.288748 -218.894406)
		(width 0.127)
		(layer "B.Cu")
		(net "PHY_SCC_B_TO_DRV_B_11_DP")
	)
	(segment
		(start 437.624982 -236.236764)
		(end 438.003188 -236.283246)
		(width 0.127)
		(layer "B.Cu")
		(net "PHY_SCC_B_TO_DRV_B_11_DP")
	)
	(segment
		(start 436.055262 -235.890816)
		(end 436.433468 -235.937298)
		(width 0.127)
		(layer "B.Cu")
		(net "PHY_SCC_B_TO_DRV_B_11_DP")
	)
	(segment
		(start 471.967306 -244.738144)
		(end 476.985584 -244.738144)
		(width 0.127)
		(layer "B.Cu")
		(net "PHY_SCC_B_TO_DRV_B_11_DP")
	)
	(segment
		(start 436.944262 -236.153452)
		(end 437.114188 -236.02061)
		(width 0.127)
		(layer "B.Cu")
		(net "PHY_SCC_B_TO_DRV_B_11_DP")
	)
	(segment
		(start 279.389586 -219.635832)
		(end 290.014914 -219.635832)
		(width 0.127)
		(layer "B.Cu")
		(net "PHY_SCC_B_TO_DRV_B_11_DP")
	)
	(segment
		(start 438.683908 -236.366558)
		(end 449.331334 -237.672118)
		(width 0.127)
		(layer "B.Cu")
		(net "PHY_SCC_B_TO_DRV_B_11_DP")
	)
	(segment
		(start 435.374542 -235.80725)
		(end 435.50713 -235.977176)
		(width 0.127)
		(layer "B.Cu")
		(net "PHY_SCC_B_TO_DRV_B_11_DP")
	)
	(segment
		(start 438.003188 -236.283246)
		(end 438.17286 -236.150404)
		(width 0.127)
		(layer "B.Cu")
		(net "PHY_SCC_B_TO_DRV_B_11_DP")
	)
	(segment
		(start 290.014914 -219.635832)
		(end 340.966806 -224.386648)
		(width 0.127)
		(layer "B.Cu")
		(net "PHY_SCC_B_TO_DRV_B_11_DP")
	)
	(segment
		(start 436.433468 -235.937298)
		(end 436.566056 -236.10697)
		(width 0.127)
		(layer "B.Cu")
		(net "PHY_SCC_B_TO_DRV_B_11_DP")
	)
	(segment
		(start 340.966806 -224.386648)
		(end 434.826664 -235.89361)
		(width 0.127)
		(layer "B.Cu")
		(net "PHY_SCC_B_TO_DRV_B_11_DP")
	)
	(segment
		(start 449.331334 -237.672118)
		(end 471.967306 -244.738144)
		(width 0.127)
		(layer "B.Cu")
		(net "PHY_SCC_B_TO_DRV_B_11_DP")
	)
	(segment
		(start 437.114188 -236.02061)
		(end 437.492394 -236.067092)
		(width 0.127)
		(layer "B.Cu")
		(net "PHY_SCC_B_TO_DRV_B_11_DP")
	)
	(segment
		(start 438.17286 -236.150404)
		(end 438.551066 -236.196886)
		(width 0.127)
		(layer "B.Cu")
		(net "PHY_SCC_B_TO_DRV_B_11_DP")
	)
	(segment
		(start 477.152462 -244.571266)
		(end 477.152462 -244.312694)
		(width 0.127)
		(layer "B.Cu")
		(net "PHY_SCC_B_TO_DRV_B_11_DP")
	)
	(segment
		(start 435.885336 -236.023658)
		(end 436.055262 -235.890816)
		(width 0.127)
		(layer "B.Cu")
		(net "PHY_SCC_B_TO_DRV_B_11_DP")
	)
	(segment
		(start 438.551066 -236.196886)
		(end 438.683908 -236.366558)
		(width 0.127)
		(layer "B.Cu")
		(net "PHY_SCC_B_TO_DRV_B_11_DP")
	)
	(segment
		(start 434.826664 -235.89361)
		(end 434.996336 -235.761022)
		(width 0.127)
		(layer "B.Cu")
		(net "PHY_SCC_B_TO_DRV_B_11_DP")
	)
	(arc
		(start 279.288748 -218.894406)
		(mid 279.143088 -218.95474)
		(end 279.082754 -219.1004)
		(width 0.127)
		(layer "B.Cu")
		(net "PHY_SCC_B_TO_DRV_B_11_DP")
	)
	(arc
		(start 279.082754 -219.329)
		(mid 279.172623 -219.545963)
		(end 279.389586 -219.635832)
		(width 0.127)
		(layer "B.Cu")
		(net "PHY_SCC_B_TO_DRV_B_11_DP")
	)
	(arc
		(start 476.985584 -244.738144)
		(mid 477.103585 -244.689267)
		(end 477.152462 -244.571266)
		(width 0.127)
		(layer "B.Cu")
		(net "PHY_SCC_B_TO_DRV_B_11_DP")
	)
	(segment
		(start 477.152462 -245.215918)
		(end 477.152462 -245.455694)
		(width 0.127)
		(layer "F.Cu")
		(net "PHY_SCC_B_TO_DRV_B_11_DN")
	)
	(segment
		(start 478.773998 -245.219474)
		(end 478.584768 -245.030244)
		(width 0.127)
		(layer "F.Cu")
		(net "PHY_SCC_B_TO_DRV_B_11_DN")
	)
	(segment
		(start 478.584768 -245.030244)
		(end 477.338136 -245.030244)
		(width 0.127)
		(layer "F.Cu")
		(net "PHY_SCC_B_TO_DRV_B_11_DN")
	)
	(segment
		(start 479.105214 -245.219474)
		(end 478.773998 -245.219474)
		(width 0.127)
		(layer "F.Cu")
		(net "PHY_SCC_B_TO_DRV_B_11_DN")
	)
	(arc
		(start 477.338136 -245.030244)
		(mid 477.206845 -245.084627)
		(end 477.152462 -245.215918)
		(width 0.127)
		(layer "F.Cu")
		(net "PHY_SCC_B_TO_DRV_B_11_DN")
	)
	(segment
		(start 449.268596 -237.958884)
		(end 471.922602 -245.030244)
		(width 0.127)
		(layer "B.Cu")
		(net "PHY_SCC_B_TO_DRV_B_11_DN")
	)
	(segment
		(start 278.23668 -218.894406)
		(end 278.58466 -218.894406)
		(width 0.127)
		(layer "B.Cu")
		(net "PHY_SCC_B_TO_DRV_B_11_DN")
	)
	(segment
		(start 278.790654 -219.1004)
		(end 278.790654 -219.329)
		(width 0.127)
		(layer "B.Cu")
		(net "PHY_SCC_B_TO_DRV_B_11_DN")
	)
	(segment
		(start 340.935564 -224.677224)
		(end 449.268596 -237.958884)
		(width 0.127)
		(layer "B.Cu")
		(net "PHY_SCC_B_TO_DRV_B_11_DN")
	)
	(segment
		(start 279.389586 -219.927932)
		(end 290.001198 -219.927932)
		(width 0.127)
		(layer "B.Cu")
		(net "PHY_SCC_B_TO_DRV_B_11_DN")
	)
	(segment
		(start 471.922602 -245.030244)
		(end 476.985584 -245.030244)
		(width 0.127)
		(layer "B.Cu")
		(net "PHY_SCC_B_TO_DRV_B_11_DN")
	)
	(segment
		(start 477.152462 -245.197122)
		(end 477.152462 -245.455694)
		(width 0.127)
		(layer "B.Cu")
		(net "PHY_SCC_B_TO_DRV_B_11_DN")
	)
	(segment
		(start 290.001198 -219.927932)
		(end 340.935564 -224.677224)
		(width 0.127)
		(layer "B.Cu")
		(net "PHY_SCC_B_TO_DRV_B_11_DN")
	)
	(arc
		(start 476.985584 -245.030244)
		(mid 477.103585 -245.079121)
		(end 477.152462 -245.197122)
		(width 0.127)
		(layer "B.Cu")
		(net "PHY_SCC_B_TO_DRV_B_11_DN")
	)
	(arc
		(start 278.790654 -219.329)
		(mid 278.966077 -219.752509)
		(end 279.389586 -219.927932)
		(width 0.127)
		(layer "B.Cu")
		(net "PHY_SCC_B_TO_DRV_B_11_DN")
	)
	(arc
		(start 278.58466 -218.894406)
		(mid 278.73032 -218.95474)
		(end 278.790654 -219.1004)
		(width 0.127)
		(layer "B.Cu")
		(net "PHY_SCC_B_TO_DRV_B_11_DN")
	)
	(segment
		(start 445.60236 -244.547644)
		(end 445.60236 -244.312694)
		(width 0.127)
		(layer "F.Cu")
		(net "PHY_SCC_B_TO_DRV_B_10_DP")
	)
	(segment
		(start 447.1162 -244.738144)
		(end 445.79286 -244.738144)
		(width 0.127)
		(layer "F.Cu")
		(net "PHY_SCC_B_TO_DRV_B_10_DP")
	)
	(segment
		(start 447.555112 -244.660674)
		(end 447.19367 -244.660674)
		(width 0.127)
		(layer "F.Cu")
		(net "PHY_SCC_B_TO_DRV_B_10_DP")
	)
	(segment
		(start 447.19367 -244.660674)
		(end 447.1162 -244.738144)
		(width 0.127)
		(layer "F.Cu")
		(net "PHY_SCC_B_TO_DRV_B_10_DP")
	)
	(arc
		(start 445.79286 -244.738144)
		(mid 445.658156 -244.682348)
		(end 445.60236 -244.547644)
		(width 0.127)
		(layer "F.Cu")
		(net "PHY_SCC_B_TO_DRV_B_10_DP")
	)
	(segment
		(start 405.823166 -236.131354)
		(end 406.200356 -236.184694)
		(width 0.127)
		(layer "B.Cu")
		(net "PHY_SCC_B_TO_DRV_B_10_DP")
	)
	(segment
		(start 404.26005 -235.755942)
		(end 404.63724 -235.809282)
		(width 0.127)
		(layer "B.Cu")
		(net "PHY_SCC_B_TO_DRV_B_10_DP")
	)
	(segment
		(start 430.775872 -239.667542)
		(end 444.924434 -244.739922)
		(width 0.127)
		(layer "B.Cu")
		(net "PHY_SCC_B_TO_DRV_B_10_DP")
	)
	(segment
		(start 445.60236 -244.60962)
		(end 445.60236 -244.312694)
		(width 0.127)
		(layer "B.Cu")
		(net "PHY_SCC_B_TO_DRV_B_10_DP")
	)
	(segment
		(start 444.924434 -244.739922)
		(end 445.472058 -244.739922)
		(width 0.127)
		(layer "B.Cu")
		(net "PHY_SCC_B_TO_DRV_B_10_DP")
	)
	(segment
		(start 280.636726 -220.694504)
		(end 280.266648 -220.694504)
		(width 0.127)
		(layer "B.Cu")
		(net "PHY_SCC_B_TO_DRV_B_10_DP")
	)
	(segment
		(start 407.806144 -236.258354)
		(end 407.935684 -236.43082)
		(width 0.127)
		(layer "B.Cu")
		(net "PHY_SCC_B_TO_DRV_B_10_DP")
	)
	(segment
		(start 404.087838 -235.885482)
		(end 404.26005 -235.755942)
		(width 0.127)
		(layer "B.Cu")
		(net "PHY_SCC_B_TO_DRV_B_10_DP")
	)
	(segment
		(start 406.879298 -236.28096)
		(end 407.256488 -236.334554)
		(width 0.127)
		(layer "B.Cu")
		(net "PHY_SCC_B_TO_DRV_B_10_DP")
	)
	(segment
		(start 406.749758 -236.108748)
		(end 406.879298 -236.28096)
		(width 0.127)
		(layer "B.Cu")
		(net "PHY_SCC_B_TO_DRV_B_10_DP")
	)
	(segment
		(start 407.256488 -236.334554)
		(end 407.428954 -236.205014)
		(width 0.127)
		(layer "B.Cu")
		(net "PHY_SCC_B_TO_DRV_B_10_DP")
	)
	(segment
		(start 404.76678 -235.981748)
		(end 405.14397 -236.035088)
		(width 0.127)
		(layer "B.Cu")
		(net "PHY_SCC_B_TO_DRV_B_10_DP")
	)
	(segment
		(start 406.200356 -236.184694)
		(end 406.372568 -236.055408)
		(width 0.127)
		(layer "B.Cu")
		(net "PHY_SCC_B_TO_DRV_B_10_DP")
	)
	(segment
		(start 290.580572 -221.43593)
		(end 338.204556 -226.549204)
		(width 0.127)
		(layer "B.Cu")
		(net "PHY_SCC_B_TO_DRV_B_10_DP")
	)
	(segment
		(start 405.316436 -235.905548)
		(end 405.693626 -235.959142)
		(width 0.127)
		(layer "B.Cu")
		(net "PHY_SCC_B_TO_DRV_B_10_DP")
	)
	(segment
		(start 407.935684 -236.43082)
		(end 430.775872 -239.667542)
		(width 0.127)
		(layer "B.Cu")
		(net "PHY_SCC_B_TO_DRV_B_10_DP")
	)
	(segment
		(start 338.214716 -226.550474)
		(end 404.087838 -235.885482)
		(width 0.127)
		(layer "B.Cu")
		(net "PHY_SCC_B_TO_DRV_B_10_DP")
	)
	(segment
		(start 338.204556 -226.549204)
		(end 338.214716 -226.550474)
		(width 0.127)
		(layer "B.Cu")
		(net "PHY_SCC_B_TO_DRV_B_10_DP")
	)
	(segment
		(start 407.428954 -236.205014)
		(end 407.806144 -236.258354)
		(width 0.127)
		(layer "B.Cu")
		(net "PHY_SCC_B_TO_DRV_B_10_DP")
	)
	(segment
		(start 404.63724 -235.809282)
		(end 404.76678 -235.981748)
		(width 0.127)
		(layer "B.Cu")
		(net "PHY_SCC_B_TO_DRV_B_10_DP")
	)
	(segment
		(start 280.386282 -221.43593)
		(end 290.580572 -221.43593)
		(width 0.127)
		(layer "B.Cu")
		(net "PHY_SCC_B_TO_DRV_B_10_DP")
	)
	(segment
		(start 405.693626 -235.959142)
		(end 405.823166 -236.131354)
		(width 0.127)
		(layer "B.Cu")
		(net "PHY_SCC_B_TO_DRV_B_10_DP")
	)
	(segment
		(start 405.14397 -236.035088)
		(end 405.316436 -235.905548)
		(width 0.127)
		(layer "B.Cu")
		(net "PHY_SCC_B_TO_DRV_B_10_DP")
	)
	(segment
		(start 406.372568 -236.055408)
		(end 406.749758 -236.108748)
		(width 0.127)
		(layer "B.Cu")
		(net "PHY_SCC_B_TO_DRV_B_10_DP")
	)
	(segment
		(start 280.082752 -220.8784)
		(end 280.082752 -221.1324)
		(width 0.127)
		(layer "B.Cu")
		(net "PHY_SCC_B_TO_DRV_B_10_DP")
	)
	(arc
		(start 445.472058 -244.739922)
		(mid 445.564195 -244.701757)
		(end 445.60236 -244.60962)
		(width 0.127)
		(layer "B.Cu")
		(net "PHY_SCC_B_TO_DRV_B_10_DP")
	)
	(arc
		(start 280.082752 -221.1324)
		(mid 280.171654 -221.347028)
		(end 280.386282 -221.43593)
		(width 0.127)
		(layer "B.Cu")
		(net "PHY_SCC_B_TO_DRV_B_10_DP")
	)
	(arc
		(start 280.266648 -220.694504)
		(mid 280.136614 -220.748366)
		(end 280.082752 -220.8784)
		(width 0.127)
		(layer "B.Cu")
		(net "PHY_SCC_B_TO_DRV_B_10_DP")
	)
	(segment
		(start 447.189098 -245.219474)
		(end 446.999868 -245.030244)
		(width 0.127)
		(layer "F.Cu")
		(net "PHY_SCC_B_TO_DRV_B_10_DN")
	)
	(segment
		(start 446.999868 -245.030244)
		(end 445.79286 -245.030244)
		(width 0.127)
		(layer "F.Cu")
		(net "PHY_SCC_B_TO_DRV_B_10_DN")
	)
	(segment
		(start 445.60236 -245.220744)
		(end 445.60236 -245.455694)
		(width 0.127)
		(layer "F.Cu")
		(net "PHY_SCC_B_TO_DRV_B_10_DN")
	)
	(segment
		(start 447.555112 -245.219474)
		(end 447.189098 -245.219474)
		(width 0.127)
		(layer "F.Cu")
		(net "PHY_SCC_B_TO_DRV_B_10_DN")
	)
	(arc
		(start 445.79286 -245.030244)
		(mid 445.658156 -245.08604)
		(end 445.60236 -245.220744)
		(width 0.127)
		(layer "F.Cu")
		(net "PHY_SCC_B_TO_DRV_B_10_DN")
	)
	(segment
		(start 279.236678 -220.694504)
		(end 279.606756 -220.694504)
		(width 0.127)
		(layer "B.Cu")
		(net "PHY_SCC_B_TO_DRV_B_10_DN")
	)
	(segment
		(start 430.704752 -239.95253)
		(end 444.873634 -245.032022)
		(width 0.127)
		(layer "B.Cu")
		(net "PHY_SCC_B_TO_DRV_B_10_DN")
	)
	(segment
		(start 280.386282 -221.72803)
		(end 290.564824 -221.72803)
		(width 0.127)
		(layer "B.Cu")
		(net "PHY_SCC_B_TO_DRV_B_10_DN")
	)
	(segment
		(start 290.564824 -221.72803)
		(end 338.173568 -226.83978)
		(width 0.127)
		(layer "B.Cu")
		(net "PHY_SCC_B_TO_DRV_B_10_DN")
	)
	(segment
		(start 279.790652 -220.8784)
		(end 279.790652 -221.1324)
		(width 0.127)
		(layer "B.Cu")
		(net "PHY_SCC_B_TO_DRV_B_10_DN")
	)
	(segment
		(start 338.173568 -226.83978)
		(end 430.704752 -239.95253)
		(width 0.127)
		(layer "B.Cu")
		(net "PHY_SCC_B_TO_DRV_B_10_DN")
	)
	(segment
		(start 445.60236 -245.16842)
		(end 445.60236 -245.455694)
		(width 0.127)
		(layer "B.Cu")
		(net "PHY_SCC_B_TO_DRV_B_10_DN")
	)
	(segment
		(start 444.873634 -245.032022)
		(end 445.465962 -245.032022)
		(width 0.127)
		(layer "B.Cu")
		(net "PHY_SCC_B_TO_DRV_B_10_DN")
	)
	(arc
		(start 445.465962 -245.032022)
		(mid 445.56241 -245.071972)
		(end 445.60236 -245.16842)
		(width 0.127)
		(layer "B.Cu")
		(net "PHY_SCC_B_TO_DRV_B_10_DN")
	)
	(arc
		(start 279.606756 -220.694504)
		(mid 279.73679 -220.748366)
		(end 279.790652 -220.8784)
		(width 0.127)
		(layer "B.Cu")
		(net "PHY_SCC_B_TO_DRV_B_10_DN")
	)
	(arc
		(start 279.790652 -221.1324)
		(mid 279.965108 -221.553574)
		(end 280.386282 -221.72803)
		(width 0.127)
		(layer "B.Cu")
		(net "PHY_SCC_B_TO_DRV_B_10_DN")
	)
	(segment
		(start 64.68872 -244.660674)
		(end 64.87287 -244.844824)
		(width 0.127)
		(layer "F.Cu")
		(net "PHY_SCC_B_TO_DRV_B_1_DP")
	)
	(segment
		(start 64.87287 -244.844824)
		(end 65.676526 -244.844824)
		(width 0.127)
		(layer "F.Cu")
		(net "PHY_SCC_B_TO_DRV_B_1_DP")
	)
	(segment
		(start 64.292734 -244.660674)
		(end 64.68872 -244.660674)
		(width 0.127)
		(layer "F.Cu")
		(net "PHY_SCC_B_TO_DRV_B_1_DP")
	)
	(segment
		(start 65.83553 -244.68582)
		(end 65.83553 -244.419374)
		(width 0.127)
		(layer "F.Cu")
		(net "PHY_SCC_B_TO_DRV_B_1_DP")
	)
	(arc
		(start 65.676526 -244.844824)
		(mid 65.788959 -244.798253)
		(end 65.83553 -244.68582)
		(width 0.127)
		(layer "F.Cu")
		(net "PHY_SCC_B_TO_DRV_B_1_DP")
	)
	(segment
		(start 270.693896 -230.448612)
		(end 258.855972 -232.963974)
		(width 0.127)
		(layer "B.Cu")
		(net "PHY_SCC_B_TO_DRV_B_1_DP")
	)
	(segment
		(start 67.583304 -244.844824)
		(end 65.97015 -244.844824)
		(width 0.127)
		(layer "B.Cu")
		(net "PHY_SCC_B_TO_DRV_B_1_DP")
	)
	(segment
		(start 258.855972 -232.963974)
		(end 201.683874 -220.811852)
		(width 0.127)
		(layer "B.Cu")
		(net "PHY_SCC_B_TO_DRV_B_1_DP")
	)
	(segment
		(start 280.636726 -231.494584)
		(end 280.29662 -231.494584)
		(width 0.127)
		(layer "B.Cu")
		(net "PHY_SCC_B_TO_DRV_B_1_DP")
	)
	(segment
		(start 280.082752 -231.280716)
		(end 280.082752 -231.102916)
		(width 0.127)
		(layer "B.Cu")
		(net "PHY_SCC_B_TO_DRV_B_1_DP")
	)
	(segment
		(start 279.428448 -230.448612)
		(end 270.693896 -230.448612)
		(width 0.127)
		(layer "B.Cu")
		(net "PHY_SCC_B_TO_DRV_B_1_DP")
	)
	(segment
		(start 128.135888 -235.61802)
		(end 67.583304 -244.844824)
		(width 0.127)
		(layer "B.Cu")
		(net "PHY_SCC_B_TO_DRV_B_1_DP")
	)
	(segment
		(start 65.83553 -244.710204)
		(end 65.83553 -244.419374)
		(width 0.127)
		(layer "B.Cu")
		(net "PHY_SCC_B_TO_DRV_B_1_DP")
	)
	(segment
		(start 201.683874 -220.811852)
		(end 128.135888 -235.61802)
		(width 0.127)
		(layer "B.Cu")
		(net "PHY_SCC_B_TO_DRV_B_1_DP")
	)
	(arc
		(start 280.29662 -231.494584)
		(mid 280.145392 -231.431944)
		(end 280.082752 -231.280716)
		(width 0.127)
		(layer "B.Cu")
		(net "PHY_SCC_B_TO_DRV_B_1_DP")
	)
	(arc
		(start 280.082752 -231.102916)
		(mid 279.891111 -230.640253)
		(end 279.428448 -230.448612)
		(width 0.127)
		(layer "B.Cu")
		(net "PHY_SCC_B_TO_DRV_B_1_DP")
	)
	(arc
		(start 65.97015 -244.844824)
		(mid 65.874959 -244.805395)
		(end 65.83553 -244.710204)
		(width 0.127)
		(layer "B.Cu")
		(net "PHY_SCC_B_TO_DRV_B_1_DP")
	)
	(segment
		(start 64.672972 -245.219474)
		(end 64.755522 -245.136924)
		(width 0.127)
		(layer "F.Cu")
		(net "PHY_SCC_B_TO_DRV_B_1_DN")
	)
	(segment
		(start 65.83553 -245.295928)
		(end 65.83553 -245.562374)
		(width 0.127)
		(layer "F.Cu")
		(net "PHY_SCC_B_TO_DRV_B_1_DN")
	)
	(segment
		(start 64.755522 -245.136924)
		(end 65.676526 -245.136924)
		(width 0.127)
		(layer "F.Cu")
		(net "PHY_SCC_B_TO_DRV_B_1_DN")
	)
	(segment
		(start 64.292734 -245.219474)
		(end 64.672972 -245.219474)
		(width 0.127)
		(layer "F.Cu")
		(net "PHY_SCC_B_TO_DRV_B_1_DN")
	)
	(arc
		(start 65.676526 -245.136924)
		(mid 65.788959 -245.183495)
		(end 65.83553 -245.295928)
		(width 0.127)
		(layer "F.Cu")
		(net "PHY_SCC_B_TO_DRV_B_1_DN")
	)
	(segment
		(start 205.552548 -222.08871)
		(end 205.4352 -221.907862)
		(width 0.127)
		(layer "B.Cu")
		(net "PHY_SCC_B_TO_DRV_B_1_DN")
	)
	(segment
		(start 67.605656 -245.136924)
		(end 65.979802 -245.136924)
		(width 0.127)
		(layer "B.Cu")
		(net "PHY_SCC_B_TO_DRV_B_1_DN")
	)
	(segment
		(start 204.509116 -221.866968)
		(end 204.391768 -221.68612)
		(width 0.127)
		(layer "B.Cu")
		(net "PHY_SCC_B_TO_DRV_B_1_DN")
	)
	(segment
		(start 65.83553 -245.281196)
		(end 65.83553 -245.562374)
		(width 0.127)
		(layer "B.Cu")
		(net "PHY_SCC_B_TO_DRV_B_1_DN")
	)
	(segment
		(start 206.106014 -222.05061)
		(end 205.925166 -222.167958)
		(width 0.127)
		(layer "B.Cu")
		(net "PHY_SCC_B_TO_DRV_B_1_DN")
	)
	(segment
		(start 203.465684 -221.645226)
		(end 203.348082 -221.464378)
		(width 0.127)
		(layer "B.Cu")
		(net "PHY_SCC_B_TO_DRV_B_1_DN")
	)
	(segment
		(start 279.236678 -231.494584)
		(end 279.576784 -231.494584)
		(width 0.127)
		(layer "B.Cu")
		(net "PHY_SCC_B_TO_DRV_B_1_DN")
	)
	(segment
		(start 203.348082 -221.464378)
		(end 202.975464 -221.38513)
		(width 0.127)
		(layer "B.Cu")
		(net "PHY_SCC_B_TO_DRV_B_1_DN")
	)
	(segment
		(start 204.391768 -221.68612)
		(end 204.018896 -221.606872)
		(width 0.127)
		(layer "B.Cu")
		(net "PHY_SCC_B_TO_DRV_B_1_DN")
	)
	(segment
		(start 204.881734 -221.946216)
		(end 204.509116 -221.866968)
		(width 0.127)
		(layer "B.Cu")
		(net "PHY_SCC_B_TO_DRV_B_1_DN")
	)
	(segment
		(start 270.72463 -230.740712)
		(end 258.855972 -233.262678)
		(width 0.127)
		(layer "B.Cu")
		(net "PHY_SCC_B_TO_DRV_B_1_DN")
	)
	(segment
		(start 202.79487 -221.502478)
		(end 202.421998 -221.42323)
		(width 0.127)
		(layer "B.Cu")
		(net "PHY_SCC_B_TO_DRV_B_1_DN")
	)
	(segment
		(start 204.018896 -221.606872)
		(end 203.838302 -221.724474)
		(width 0.127)
		(layer "B.Cu")
		(net "PHY_SCC_B_TO_DRV_B_1_DN")
	)
	(segment
		(start 202.421998 -221.42323)
		(end 202.30465 -221.242636)
		(width 0.127)
		(layer "B.Cu")
		(net "PHY_SCC_B_TO_DRV_B_1_DN")
	)
	(segment
		(start 202.30465 -221.242636)
		(end 201.68235 -221.110302)
		(width 0.127)
		(layer "B.Cu")
		(net "PHY_SCC_B_TO_DRV_B_1_DN")
	)
	(segment
		(start 203.838302 -221.724474)
		(end 203.465684 -221.645226)
		(width 0.127)
		(layer "B.Cu")
		(net "PHY_SCC_B_TO_DRV_B_1_DN")
	)
	(segment
		(start 202.975464 -221.38513)
		(end 202.79487 -221.502478)
		(width 0.127)
		(layer "B.Cu")
		(net "PHY_SCC_B_TO_DRV_B_1_DN")
	)
	(segment
		(start 128.186688 -235.905802)
		(end 67.605656 -245.136924)
		(width 0.127)
		(layer "B.Cu")
		(net "PHY_SCC_B_TO_DRV_B_1_DN")
	)
	(segment
		(start 258.855972 -233.262678)
		(end 206.106014 -222.05061)
		(width 0.127)
		(layer "B.Cu")
		(net "PHY_SCC_B_TO_DRV_B_1_DN")
	)
	(segment
		(start 205.4352 -221.907862)
		(end 205.062582 -221.828868)
		(width 0.127)
		(layer "B.Cu")
		(net "PHY_SCC_B_TO_DRV_B_1_DN")
	)
	(segment
		(start 279.428448 -230.740712)
		(end 270.72463 -230.740712)
		(width 0.127)
		(layer "B.Cu")
		(net "PHY_SCC_B_TO_DRV_B_1_DN")
	)
	(segment
		(start 279.790652 -231.280716)
		(end 279.790652 -231.102916)
		(width 0.127)
		(layer "B.Cu")
		(net "PHY_SCC_B_TO_DRV_B_1_DN")
	)
	(segment
		(start 205.062582 -221.828868)
		(end 204.881734 -221.946216)
		(width 0.127)
		(layer "B.Cu")
		(net "PHY_SCC_B_TO_DRV_B_1_DN")
	)
	(segment
		(start 201.68235 -221.110302)
		(end 128.186688 -235.905802)
		(width 0.127)
		(layer "B.Cu")
		(net "PHY_SCC_B_TO_DRV_B_1_DN")
	)
	(segment
		(start 205.925166 -222.167958)
		(end 205.552548 -222.08871)
		(width 0.127)
		(layer "B.Cu")
		(net "PHY_SCC_B_TO_DRV_B_1_DN")
	)
	(arc
		(start 65.979802 -245.136924)
		(mid 65.877786 -245.17918)
		(end 65.83553 -245.281196)
		(width 0.127)
		(layer "B.Cu")
		(net "PHY_SCC_B_TO_DRV_B_1_DN")
	)
	(arc
		(start 279.576784 -231.494584)
		(mid 279.728012 -231.431944)
		(end 279.790652 -231.280716)
		(width 0.127)
		(layer "B.Cu")
		(net "PHY_SCC_B_TO_DRV_B_1_DN")
	)
	(arc
		(start 279.790652 -231.102916)
		(mid 279.684565 -230.846799)
		(end 279.428448 -230.740712)
		(width 0.127)
		(layer "B.Cu")
		(net "PHY_SCC_B_TO_DRV_B_1_DN")
	)
	(segment
		(start 33.323022 -244.844824)
		(end 34.126678 -244.844824)
		(width 0.127)
		(layer "F.Cu")
		(net "PHY_SCC_B_TO_DRV_B_0_DP")
	)
	(segment
		(start 32.742886 -244.660674)
		(end 33.138872 -244.660674)
		(width 0.127)
		(layer "F.Cu")
		(net "PHY_SCC_B_TO_DRV_B_0_DP")
	)
	(segment
		(start 33.138872 -244.660674)
		(end 33.323022 -244.844824)
		(width 0.127)
		(layer "F.Cu")
		(net "PHY_SCC_B_TO_DRV_B_0_DP")
	)
	(segment
		(start 34.285682 -244.68582)
		(end 34.285682 -244.419374)
		(width 0.127)
		(layer "F.Cu")
		(net "PHY_SCC_B_TO_DRV_B_0_DP")
	)
	(arc
		(start 34.126678 -244.844824)
		(mid 34.239111 -244.798253)
		(end 34.285682 -244.68582)
		(width 0.127)
		(layer "F.Cu")
		(net "PHY_SCC_B_TO_DRV_B_0_DP")
	)
	(segment
		(start 80.785462 -233.209338)
		(end 35.2552 -244.844824)
		(width 0.127)
		(layer "B.Cu")
		(net "PHY_SCC_B_TO_DRV_B_0_DP")
	)
	(segment
		(start 278.42845 -228.648514)
		(end 271.393666 -228.648514)
		(width 0.127)
		(layer "B.Cu")
		(net "PHY_SCC_B_TO_DRV_B_0_DP")
	)
	(segment
		(start 35.2552 -244.844824)
		(end 34.420302 -244.844824)
		(width 0.127)
		(layer "B.Cu")
		(net "PHY_SCC_B_TO_DRV_B_0_DP")
	)
	(segment
		(start 271.393666 -228.648514)
		(end 258.778248 -231.326944)
		(width 0.127)
		(layer "B.Cu")
		(net "PHY_SCC_B_TO_DRV_B_0_DP")
	)
	(segment
		(start 34.285682 -244.710204)
		(end 34.285682 -244.419374)
		(width 0.127)
		(layer "B.Cu")
		(net "PHY_SCC_B_TO_DRV_B_0_DP")
	)
	(segment
		(start 279.636728 -229.694486)
		(end 279.296622 -229.694486)
		(width 0.127)
		(layer "B.Cu")
		(net "PHY_SCC_B_TO_DRV_B_0_DP")
	)
	(segment
		(start 193.424556 -217.43543)
		(end 80.785462 -233.209338)
		(width 0.127)
		(layer "B.Cu")
		(net "PHY_SCC_B_TO_DRV_B_0_DP")
	)
	(segment
		(start 279.082754 -229.480618)
		(end 279.082754 -229.302818)
		(width 0.127)
		(layer "B.Cu")
		(net "PHY_SCC_B_TO_DRV_B_0_DP")
	)
	(segment
		(start 258.778248 -231.326944)
		(end 193.424556 -217.43543)
		(width 0.127)
		(layer "B.Cu")
		(net "PHY_SCC_B_TO_DRV_B_0_DP")
	)
	(arc
		(start 34.420302 -244.844824)
		(mid 34.325111 -244.805395)
		(end 34.285682 -244.710204)
		(width 0.127)
		(layer "B.Cu")
		(net "PHY_SCC_B_TO_DRV_B_0_DP")
	)
	(arc
		(start 279.082754 -229.302818)
		(mid 278.891113 -228.840155)
		(end 278.42845 -228.648514)
		(width 0.127)
		(layer "B.Cu")
		(net "PHY_SCC_B_TO_DRV_B_0_DP")
	)
	(arc
		(start 279.296622 -229.694486)
		(mid 279.145394 -229.631846)
		(end 279.082754 -229.480618)
		(width 0.127)
		(layer "B.Cu")
		(net "PHY_SCC_B_TO_DRV_B_0_DP")
	)
	(segment
		(start 33.205674 -245.136924)
		(end 34.126678 -245.136924)
		(width 0.127)
		(layer "F.Cu")
		(net "PHY_SCC_B_TO_DRV_B_0_DN")
	)
	(segment
		(start 34.285682 -245.295928)
		(end 34.285682 -245.562374)
		(width 0.127)
		(layer "F.Cu")
		(net "PHY_SCC_B_TO_DRV_B_0_DN")
	)
	(segment
		(start 32.742886 -245.219474)
		(end 33.123124 -245.219474)
		(width 0.127)
		(layer "F.Cu")
		(net "PHY_SCC_B_TO_DRV_B_0_DN")
	)
	(segment
		(start 33.123124 -245.219474)
		(end 33.205674 -245.136924)
		(width 0.127)
		(layer "F.Cu")
		(net "PHY_SCC_B_TO_DRV_B_0_DN")
	)
	(arc
		(start 34.126678 -245.136924)
		(mid 34.239111 -245.183495)
		(end 34.285682 -245.295928)
		(width 0.127)
		(layer "F.Cu")
		(net "PHY_SCC_B_TO_DRV_B_0_DN")
	)
	(segment
		(start 80.842104 -233.496358)
		(end 35.29203 -245.136924)
		(width 0.127)
		(layer "B.Cu")
		(net "PHY_SCC_B_TO_DRV_B_0_DN")
	)
	(segment
		(start 137.472674 -225.56597)
		(end 137.34288 -225.738182)
		(width 0.127)
		(layer "B.Cu")
		(net "PHY_SCC_B_TO_DRV_B_0_DN")
	)
	(segment
		(start 136.416034 -225.714052)
		(end 136.28624 -225.88601)
		(width 0.127)
		(layer "B.Cu")
		(net "PHY_SCC_B_TO_DRV_B_0_DN")
	)
	(segment
		(start 35.29203 -245.136924)
		(end 34.429954 -245.136924)
		(width 0.127)
		(layer "B.Cu")
		(net "PHY_SCC_B_TO_DRV_B_0_DN")
	)
	(segment
		(start 136.793478 -225.66122)
		(end 136.416034 -225.714052)
		(width 0.127)
		(layer "B.Cu")
		(net "PHY_SCC_B_TO_DRV_B_0_DN")
	)
	(segment
		(start 278.23668 -229.694486)
		(end 278.576786 -229.694486)
		(width 0.127)
		(layer "B.Cu")
		(net "PHY_SCC_B_TO_DRV_B_0_DN")
	)
	(segment
		(start 34.285682 -245.281196)
		(end 34.285682 -245.562374)
		(width 0.127)
		(layer "B.Cu")
		(net "PHY_SCC_B_TO_DRV_B_0_DN")
	)
	(segment
		(start 135.359648 -225.86188)
		(end 135.229854 -226.034092)
		(width 0.127)
		(layer "B.Cu")
		(net "PHY_SCC_B_TO_DRV_B_0_DN")
	)
	(segment
		(start 133.624066 -226.104958)
		(end 80.842104 -233.496358)
		(width 0.127)
		(layer "B.Cu")
		(net "PHY_SCC_B_TO_DRV_B_0_DN")
	)
	(segment
		(start 135.229854 -226.034092)
		(end 134.85241 -226.086924)
		(width 0.127)
		(layer "B.Cu")
		(net "PHY_SCC_B_TO_DRV_B_0_DN")
	)
	(segment
		(start 134.85241 -226.086924)
		(end 134.680452 -225.95713)
		(width 0.127)
		(layer "B.Cu")
		(net "PHY_SCC_B_TO_DRV_B_0_DN")
	)
	(segment
		(start 136.28624 -225.88601)
		(end 135.90905 -225.938842)
		(width 0.127)
		(layer "B.Cu")
		(net "PHY_SCC_B_TO_DRV_B_0_DN")
	)
	(segment
		(start 137.34288 -225.738182)
		(end 136.965436 -225.791014)
		(width 0.127)
		(layer "B.Cu")
		(net "PHY_SCC_B_TO_DRV_B_0_DN")
	)
	(segment
		(start 134.173214 -226.18192)
		(end 133.796024 -226.234752)
		(width 0.127)
		(layer "B.Cu")
		(net "PHY_SCC_B_TO_DRV_B_0_DN")
	)
	(segment
		(start 258.778248 -231.625648)
		(end 193.414142 -217.731848)
		(width 0.127)
		(layer "B.Cu")
		(net "PHY_SCC_B_TO_DRV_B_0_DN")
	)
	(segment
		(start 134.303008 -226.009962)
		(end 134.173214 -226.18192)
		(width 0.127)
		(layer "B.Cu")
		(net "PHY_SCC_B_TO_DRV_B_0_DN")
	)
	(segment
		(start 133.796024 -226.234752)
		(end 133.624066 -226.104958)
		(width 0.127)
		(layer "B.Cu")
		(net "PHY_SCC_B_TO_DRV_B_0_DN")
	)
	(segment
		(start 134.680452 -225.95713)
		(end 134.303008 -226.009962)
		(width 0.127)
		(layer "B.Cu")
		(net "PHY_SCC_B_TO_DRV_B_0_DN")
	)
	(segment
		(start 278.42845 -228.940614)
		(end 271.4244 -228.940614)
		(width 0.127)
		(layer "B.Cu")
		(net "PHY_SCC_B_TO_DRV_B_0_DN")
	)
	(segment
		(start 271.4244 -228.940614)
		(end 258.778248 -231.625648)
		(width 0.127)
		(layer "B.Cu")
		(net "PHY_SCC_B_TO_DRV_B_0_DN")
	)
	(segment
		(start 278.790654 -229.480618)
		(end 278.790654 -229.302818)
		(width 0.127)
		(layer "B.Cu")
		(net "PHY_SCC_B_TO_DRV_B_0_DN")
	)
	(segment
		(start 193.414142 -217.731848)
		(end 137.472674 -225.56597)
		(width 0.127)
		(layer "B.Cu")
		(net "PHY_SCC_B_TO_DRV_B_0_DN")
	)
	(segment
		(start 135.736838 -225.809048)
		(end 135.359648 -225.86188)
		(width 0.127)
		(layer "B.Cu")
		(net "PHY_SCC_B_TO_DRV_B_0_DN")
	)
	(segment
		(start 136.965436 -225.791014)
		(end 136.793478 -225.66122)
		(width 0.127)
		(layer "B.Cu")
		(net "PHY_SCC_B_TO_DRV_B_0_DN")
	)
	(segment
		(start 135.90905 -225.938842)
		(end 135.736838 -225.809048)
		(width 0.127)
		(layer "B.Cu")
		(net "PHY_SCC_B_TO_DRV_B_0_DN")
	)
	(arc
		(start 278.576786 -229.694486)
		(mid 278.728014 -229.631846)
		(end 278.790654 -229.480618)
		(width 0.127)
		(layer "B.Cu")
		(net "PHY_SCC_B_TO_DRV_B_0_DN")
	)
	(arc
		(start 278.790654 -229.302818)
		(mid 278.684567 -229.046701)
		(end 278.42845 -228.940614)
		(width 0.127)
		(layer "B.Cu")
		(net "PHY_SCC_B_TO_DRV_B_0_DN")
	)
	(arc
		(start 34.429954 -245.136924)
		(mid 34.327938 -245.17918)
		(end 34.285682 -245.281196)
		(width 0.127)
		(layer "B.Cu")
		(net "PHY_SCC_B_TO_DRV_B_0_DN")
	)
	(segment
		(start 420.563548 -249.037348)
		(end 420.422324 -248.896124)
		(width 0.127)
		(layer "F.Cu")
		(net "PHY_DRV_B_TO_SCC_B_9_DP")
	)
	(segment
		(start 420.563548 -249.258074)
		(end 420.563548 -249.037348)
		(width 0.127)
		(layer "F.Cu")
		(net "PHY_DRV_B_TO_SCC_B_9_DP")
	)
	(segment
		(start 420.422324 -248.896124)
		(end 418.366702 -248.896124)
		(width 0.127)
		(layer "F.Cu")
		(net "PHY_DRV_B_TO_SCC_B_9_DP")
	)
	(segment
		(start 420.690548 -249.385074)
		(end 420.563548 -249.258074)
		(width 0.127)
		(layer "F.Cu")
		(net "PHY_DRV_B_TO_SCC_B_9_DP")
	)
	(segment
		(start 418.239702 -249.023124)
		(end 418.239702 -249.385074)
		(width 0.127)
		(layer "F.Cu")
		(net "PHY_DRV_B_TO_SCC_B_9_DP")
	)
	(segment
		(start 422.025064 -249.385074)
		(end 420.690548 -249.385074)
		(width 0.127)
		(layer "F.Cu")
		(net "PHY_DRV_B_TO_SCC_B_9_DP")
	)
	(arc
		(start 418.366702 -248.896124)
		(mid 418.276899 -248.933321)
		(end 418.239702 -249.023124)
		(width 0.127)
		(layer "F.Cu")
		(net "PHY_DRV_B_TO_SCC_B_9_DP")
	)
	(segment
		(start 291.244782 -223.562672)
		(end 337.214464 -229.658926)
		(width 0.12065)
		(layer "In5.Cu")
		(net "PHY_DRV_B_TO_SCC_B_9_DP")
	)
	(segment
		(start 417.407598 -248.918222)
		(end 418.119052 -248.918222)
		(width 0.12065)
		(layer "In5.Cu")
		(net "PHY_DRV_B_TO_SCC_B_9_DP")
	)
	(segment
		(start 286.595058 -223.562672)
		(end 291.244782 -223.562672)
		(width 0.12065)
		(layer "In5.Cu")
		(net "PHY_DRV_B_TO_SCC_B_9_DP")
	)
	(segment
		(start 383.183892 -235.75518)
		(end 417.407598 -248.918222)
		(width 0.12065)
		(layer "In5.Cu")
		(net "PHY_DRV_B_TO_SCC_B_9_DP")
	)
	(segment
		(start 285.968186 -222.6818)
		(end 285.968186 -222.9358)
		(width 0.12065)
		(layer "In5.Cu")
		(net "PHY_DRV_B_TO_SCC_B_9_DP")
	)
	(segment
		(start 418.239702 -249.038872)
		(end 418.239702 -249.385074)
		(width 0.12065)
		(layer "In5.Cu")
		(net "PHY_DRV_B_TO_SCC_B_9_DP")
	)
	(segment
		(start 337.214464 -229.658926)
		(end 383.183892 -235.75518)
		(width 0.12065)
		(layer "In5.Cu")
		(net "PHY_DRV_B_TO_SCC_B_9_DP")
	)
	(segment
		(start 285.436564 -222.494348)
		(end 285.780734 -222.494348)
		(width 0.12065)
		(layer "In5.Cu")
		(net "PHY_DRV_B_TO_SCC_B_9_DP")
	)
	(arc
		(start 285.968186 -222.9358)
		(mid 286.151793 -223.379065)
		(end 286.595058 -223.562672)
		(width 0.12065)
		(layer "In5.Cu")
		(net "PHY_DRV_B_TO_SCC_B_9_DP")
	)
	(arc
		(start 285.780734 -222.494348)
		(mid 285.913283 -222.549251)
		(end 285.968186 -222.6818)
		(width 0.12065)
		(layer "In5.Cu")
		(net "PHY_DRV_B_TO_SCC_B_9_DP")
	)
	(arc
		(start 418.119052 -248.918222)
		(mid 418.204364 -248.95356)
		(end 418.239702 -249.038872)
		(width 0.12065)
		(layer "In5.Cu")
		(net "PHY_DRV_B_TO_SCC_B_9_DP")
	)
	(segment
		(start 420.563548 -248.497852)
		(end 420.457376 -248.604024)
		(width 0.127)
		(layer "F.Cu")
		(net "PHY_DRV_B_TO_SCC_B_9_DN")
	)
	(segment
		(start 420.457376 -248.604024)
		(end 418.366702 -248.604024)
		(width 0.127)
		(layer "F.Cu")
		(net "PHY_DRV_B_TO_SCC_B_9_DN")
	)
	(segment
		(start 418.239702 -248.477024)
		(end 418.239702 -248.115074)
		(width 0.127)
		(layer "F.Cu")
		(net "PHY_DRV_B_TO_SCC_B_9_DN")
	)
	(segment
		(start 420.690548 -248.115074)
		(end 420.563548 -248.242074)
		(width 0.127)
		(layer "F.Cu")
		(net "PHY_DRV_B_TO_SCC_B_9_DN")
	)
	(segment
		(start 420.563548 -248.242074)
		(end 420.563548 -248.497852)
		(width 0.127)
		(layer "F.Cu")
		(net "PHY_DRV_B_TO_SCC_B_9_DN")
	)
	(segment
		(start 422.025064 -248.115074)
		(end 420.690548 -248.115074)
		(width 0.127)
		(layer "F.Cu")
		(net "PHY_DRV_B_TO_SCC_B_9_DN")
	)
	(arc
		(start 418.366702 -248.604024)
		(mid 418.276899 -248.566827)
		(end 418.239702 -248.477024)
		(width 0.127)
		(layer "F.Cu")
		(net "PHY_DRV_B_TO_SCC_B_9_DN")
	)
	(segment
		(start 407.044144 -244.57152)
		(end 407.306526 -244.45468)
		(width 0.12065)
		(layer "In5.Cu")
		(net "PHY_DRV_B_TO_SCC_B_9_DN")
	)
	(segment
		(start 407.6446 -244.584728)
		(end 407.761186 -244.84711)
		(width 0.12065)
		(layer "In5.Cu")
		(net "PHY_DRV_B_TO_SCC_B_9_DN")
	)
	(segment
		(start 407.761186 -244.84711)
		(end 408.099006 -244.977158)
		(width 0.12065)
		(layer "In5.Cu")
		(net "PHY_DRV_B_TO_SCC_B_9_DN")
	)
	(segment
		(start 383.267712 -235.426504)
		(end 407.044144 -244.57152)
		(width 0.12065)
		(layer "In5.Cu")
		(net "PHY_DRV_B_TO_SCC_B_9_DN")
	)
	(segment
		(start 286.836612 -222.494348)
		(end 286.492188 -222.494348)
		(width 0.12065)
		(layer "In5.Cu")
		(net "PHY_DRV_B_TO_SCC_B_9_DN")
	)
	(segment
		(start 409.87091 -245.65864)
		(end 417.470336 -248.581672)
		(width 0.12065)
		(layer "In5.Cu")
		(net "PHY_DRV_B_TO_SCC_B_9_DN")
	)
	(segment
		(start 407.306526 -244.45468)
		(end 407.6446 -244.584728)
		(width 0.12065)
		(layer "In5.Cu")
		(net "PHY_DRV_B_TO_SCC_B_9_DN")
	)
	(segment
		(start 291.267134 -223.226122)
		(end 383.267712 -235.426504)
		(width 0.12065)
		(layer "In5.Cu")
		(net "PHY_DRV_B_TO_SCC_B_9_DN")
	)
	(segment
		(start 417.470336 -248.581672)
		(end 418.119052 -248.581672)
		(width 0.12065)
		(layer "In5.Cu")
		(net "PHY_DRV_B_TO_SCC_B_9_DN")
	)
	(segment
		(start 408.699462 -244.990366)
		(end 408.816048 -245.253002)
		(width 0.12065)
		(layer "In5.Cu")
		(net "PHY_DRV_B_TO_SCC_B_9_DN")
	)
	(segment
		(start 409.416504 -245.26621)
		(end 409.754324 -245.396258)
		(width 0.12065)
		(layer "In5.Cu")
		(net "PHY_DRV_B_TO_SCC_B_9_DN")
	)
	(segment
		(start 408.816048 -245.253002)
		(end 409.153868 -245.38305)
		(width 0.12065)
		(layer "In5.Cu")
		(net "PHY_DRV_B_TO_SCC_B_9_DN")
	)
	(segment
		(start 408.099006 -244.977158)
		(end 408.361642 -244.860572)
		(width 0.12065)
		(layer "In5.Cu")
		(net "PHY_DRV_B_TO_SCC_B_9_DN")
	)
	(segment
		(start 286.595058 -223.226122)
		(end 291.267134 -223.226122)
		(width 0.12065)
		(layer "In5.Cu")
		(net "PHY_DRV_B_TO_SCC_B_9_DN")
	)
	(segment
		(start 409.153868 -245.38305)
		(end 409.416504 -245.26621)
		(width 0.12065)
		(layer "In5.Cu")
		(net "PHY_DRV_B_TO_SCC_B_9_DN")
	)
	(segment
		(start 409.754324 -245.396258)
		(end 409.87091 -245.65864)
		(width 0.12065)
		(layer "In5.Cu")
		(net "PHY_DRV_B_TO_SCC_B_9_DN")
	)
	(segment
		(start 286.304736 -222.6818)
		(end 286.304736 -222.9358)
		(width 0.12065)
		(layer "In5.Cu")
		(net "PHY_DRV_B_TO_SCC_B_9_DN")
	)
	(segment
		(start 408.361642 -244.860572)
		(end 408.699462 -244.990366)
		(width 0.12065)
		(layer "In5.Cu")
		(net "PHY_DRV_B_TO_SCC_B_9_DN")
	)
	(segment
		(start 418.239702 -248.461022)
		(end 418.239702 -248.115074)
		(width 0.12065)
		(layer "In5.Cu")
		(net "PHY_DRV_B_TO_SCC_B_9_DN")
	)
	(arc
		(start 286.492188 -222.494348)
		(mid 286.359639 -222.549251)
		(end 286.304736 -222.6818)
		(width 0.12065)
		(layer "In5.Cu")
		(net "PHY_DRV_B_TO_SCC_B_9_DN")
	)
	(arc
		(start 286.304736 -222.9358)
		(mid 286.389769 -223.141089)
		(end 286.595058 -223.226122)
		(width 0.12065)
		(layer "In5.Cu")
		(net "PHY_DRV_B_TO_SCC_B_9_DN")
	)
	(arc
		(start 418.119052 -248.581672)
		(mid 418.204364 -248.546334)
		(end 418.239702 -248.461022)
		(width 0.12065)
		(layer "In5.Cu")
		(net "PHY_DRV_B_TO_SCC_B_9_DN")
	)
	(segment
		(start 388.875524 -248.896124)
		(end 386.8166 -248.896124)
		(width 0.127)
		(layer "F.Cu")
		(net "PHY_DRV_B_TO_SCC_B_8_DP")
	)
	(segment
		(start 389.013446 -249.258074)
		(end 389.013446 -249.034046)
		(width 0.127)
		(layer "F.Cu")
		(net "PHY_DRV_B_TO_SCC_B_8_DP")
	)
	(segment
		(start 389.013446 -249.034046)
		(end 388.875524 -248.896124)
		(width 0.127)
		(layer "F.Cu")
		(net "PHY_DRV_B_TO_SCC_B_8_DP")
	)
	(segment
		(start 390.474962 -249.385074)
		(end 389.140446 -249.385074)
		(width 0.127)
		(layer "F.Cu")
		(net "PHY_DRV_B_TO_SCC_B_8_DP")
	)
	(segment
		(start 389.140446 -249.385074)
		(end 389.013446 -249.258074)
		(width 0.127)
		(layer "F.Cu")
		(net "PHY_DRV_B_TO_SCC_B_8_DP")
	)
	(segment
		(start 386.6896 -249.023124)
		(end 386.6896 -249.385074)
		(width 0.127)
		(layer "F.Cu")
		(net "PHY_DRV_B_TO_SCC_B_8_DP")
	)
	(arc
		(start 386.8166 -248.896124)
		(mid 386.726797 -248.933321)
		(end 386.6896 -249.023124)
		(width 0.127)
		(layer "F.Cu")
		(net "PHY_DRV_B_TO_SCC_B_8_DP")
	)
	(segment
		(start 291.574728 -225.36277)
		(end 354.19792 -237.181136)
		(width 0.12065)
		(layer "In5.Cu")
		(net "PHY_DRV_B_TO_SCC_B_8_DP")
	)
	(segment
		(start 286.436562 -224.294446)
		(end 286.777684 -224.294446)
		(width 0.12065)
		(layer "In5.Cu")
		(net "PHY_DRV_B_TO_SCC_B_8_DP")
	)
	(segment
		(start 356.470204 -237.609888)
		(end 384.437636 -248.918222)
		(width 0.12065)
		(layer "In5.Cu")
		(net "PHY_DRV_B_TO_SCC_B_8_DP")
	)
	(segment
		(start 287.6296 -225.36277)
		(end 291.574728 -225.36277)
		(width 0.12065)
		(layer "In5.Cu")
		(net "PHY_DRV_B_TO_SCC_B_8_DP")
	)
	(segment
		(start 286.968184 -224.484946)
		(end 286.968184 -224.701354)
		(width 0.12065)
		(layer "In5.Cu")
		(net "PHY_DRV_B_TO_SCC_B_8_DP")
	)
	(segment
		(start 386.6896 -249.121422)
		(end 386.6896 -249.385074)
		(width 0.12065)
		(layer "In5.Cu")
		(net "PHY_DRV_B_TO_SCC_B_8_DP")
	)
	(segment
		(start 384.437636 -248.918222)
		(end 386.4864 -248.918222)
		(width 0.12065)
		(layer "In5.Cu")
		(net "PHY_DRV_B_TO_SCC_B_8_DP")
	)
	(segment
		(start 354.19792 -237.181136)
		(end 356.470204 -237.609888)
		(width 0.12065)
		(layer "In5.Cu")
		(net "PHY_DRV_B_TO_SCC_B_8_DP")
	)
	(arc
		(start 286.777684 -224.294446)
		(mid 286.912388 -224.350242)
		(end 286.968184 -224.484946)
		(width 0.12065)
		(layer "In5.Cu")
		(net "PHY_DRV_B_TO_SCC_B_8_DP")
	)
	(arc
		(start 286.968184 -224.701354)
		(mid 287.161908 -225.169046)
		(end 287.6296 -225.36277)
		(width 0.12065)
		(layer "In5.Cu")
		(net "PHY_DRV_B_TO_SCC_B_8_DP")
	)
	(arc
		(start 386.4864 -248.918222)
		(mid 386.630084 -248.977738)
		(end 386.6896 -249.121422)
		(width 0.12065)
		(layer "In5.Cu")
		(net "PHY_DRV_B_TO_SCC_B_8_DP")
	)
	(segment
		(start 388.886446 -248.604024)
		(end 386.8166 -248.604024)
		(width 0.127)
		(layer "F.Cu")
		(net "PHY_DRV_B_TO_SCC_B_8_DN")
	)
	(segment
		(start 389.013446 -248.477024)
		(end 388.886446 -248.604024)
		(width 0.127)
		(layer "F.Cu")
		(net "PHY_DRV_B_TO_SCC_B_8_DN")
	)
	(segment
		(start 389.120126 -248.115074)
		(end 389.013446 -248.221754)
		(width 0.127)
		(layer "F.Cu")
		(net "PHY_DRV_B_TO_SCC_B_8_DN")
	)
	(segment
		(start 386.6896 -248.477024)
		(end 386.6896 -248.115074)
		(width 0.127)
		(layer "F.Cu")
		(net "PHY_DRV_B_TO_SCC_B_8_DN")
	)
	(segment
		(start 389.013446 -248.221754)
		(end 389.013446 -248.477024)
		(width 0.127)
		(layer "F.Cu")
		(net "PHY_DRV_B_TO_SCC_B_8_DN")
	)
	(segment
		(start 390.474962 -248.115074)
		(end 389.120126 -248.115074)
		(width 0.127)
		(layer "F.Cu")
		(net "PHY_DRV_B_TO_SCC_B_8_DN")
	)
	(arc
		(start 386.8166 -248.604024)
		(mid 386.726797 -248.566827)
		(end 386.6896 -248.477024)
		(width 0.127)
		(layer "F.Cu")
		(net "PHY_DRV_B_TO_SCC_B_8_DN")
	)
	(segment
		(start 291.606224 -225.02622)
		(end 344.44686 -234.99826)
		(width 0.12065)
		(layer "In5.Cu")
		(net "PHY_DRV_B_TO_SCC_B_8_DN")
	)
	(segment
		(start 346.312744 -235.350304)
		(end 346.668344 -235.41736)
		(width 0.12065)
		(layer "In5.Cu")
		(net "PHY_DRV_B_TO_SCC_B_8_DN")
	)
	(segment
		(start 346.917518 -235.247434)
		(end 347.273372 -235.31449)
		(width 0.12065)
		(layer "In5.Cu")
		(net "PHY_DRV_B_TO_SCC_B_8_DN")
	)
	(segment
		(start 386.6896 -248.378726)
		(end 386.6896 -248.115074)
		(width 0.12065)
		(layer "In5.Cu")
		(net "PHY_DRV_B_TO_SCC_B_8_DN")
	)
	(segment
		(start 384.503168 -248.581672)
		(end 386.486654 -248.581672)
		(width 0.12065)
		(layer "In5.Cu")
		(net "PHY_DRV_B_TO_SCC_B_8_DN")
	)
	(segment
		(start 347.273372 -235.31449)
		(end 347.443298 -235.563664)
		(width 0.12065)
		(layer "In5.Cu")
		(net "PHY_DRV_B_TO_SCC_B_8_DN")
	)
	(segment
		(start 345.557602 -235.20781)
		(end 345.795092 -235.045758)
		(width 0.12065)
		(layer "In5.Cu")
		(net "PHY_DRV_B_TO_SCC_B_8_DN")
	)
	(segment
		(start 287.6296 -225.02622)
		(end 291.606224 -225.02622)
		(width 0.12065)
		(layer "In5.Cu")
		(net "PHY_DRV_B_TO_SCC_B_8_DN")
	)
	(segment
		(start 347.443298 -235.563664)
		(end 356.565454 -237.285276)
		(width 0.12065)
		(layer "In5.Cu")
		(net "PHY_DRV_B_TO_SCC_B_8_DN")
	)
	(segment
		(start 345.795092 -235.045758)
		(end 346.150692 -235.113068)
		(width 0.12065)
		(layer "In5.Cu")
		(net "PHY_DRV_B_TO_SCC_B_8_DN")
	)
	(segment
		(start 356.565454 -237.285276)
		(end 384.503168 -248.581672)
		(width 0.12065)
		(layer "In5.Cu")
		(net "PHY_DRV_B_TO_SCC_B_8_DN")
	)
	(segment
		(start 344.44686 -234.99826)
		(end 344.68435 -234.836208)
		(width 0.12065)
		(layer "In5.Cu")
		(net "PHY_DRV_B_TO_SCC_B_8_DN")
	)
	(segment
		(start 287.83661 -224.294446)
		(end 287.495488 -224.294446)
		(width 0.12065)
		(layer "In5.Cu")
		(net "PHY_DRV_B_TO_SCC_B_8_DN")
	)
	(segment
		(start 287.304734 -224.4852)
		(end 287.304734 -224.701354)
		(width 0.12065)
		(layer "In5.Cu")
		(net "PHY_DRV_B_TO_SCC_B_8_DN")
	)
	(segment
		(start 346.150692 -235.113068)
		(end 346.312744 -235.350304)
		(width 0.12065)
		(layer "In5.Cu")
		(net "PHY_DRV_B_TO_SCC_B_8_DN")
	)
	(segment
		(start 345.202002 -235.140754)
		(end 345.557602 -235.20781)
		(width 0.12065)
		(layer "In5.Cu")
		(net "PHY_DRV_B_TO_SCC_B_8_DN")
	)
	(segment
		(start 346.668344 -235.41736)
		(end 346.917518 -235.247434)
		(width 0.12065)
		(layer "In5.Cu")
		(net "PHY_DRV_B_TO_SCC_B_8_DN")
	)
	(segment
		(start 345.03995 -234.903518)
		(end 345.202002 -235.140754)
		(width 0.12065)
		(layer "In5.Cu")
		(net "PHY_DRV_B_TO_SCC_B_8_DN")
	)
	(segment
		(start 344.68435 -234.836208)
		(end 345.03995 -234.903518)
		(width 0.12065)
		(layer "In5.Cu")
		(net "PHY_DRV_B_TO_SCC_B_8_DN")
	)
	(arc
		(start 386.486654 -248.581672)
		(mid 386.630158 -248.52223)
		(end 386.6896 -248.378726)
		(width 0.12065)
		(layer "In5.Cu")
		(net "PHY_DRV_B_TO_SCC_B_8_DN")
	)
	(arc
		(start 287.304734 -224.701354)
		(mid 287.399885 -224.931069)
		(end 287.6296 -225.02622)
		(width 0.12065)
		(layer "In5.Cu")
		(net "PHY_DRV_B_TO_SCC_B_8_DN")
	)
	(arc
		(start 287.495488 -224.294446)
		(mid 287.360605 -224.350317)
		(end 287.304734 -224.4852)
		(width 0.12065)
		(layer "In5.Cu")
		(net "PHY_DRV_B_TO_SCC_B_8_DN")
	)
	(segment
		(start 357.463598 -249.056398)
		(end 357.303324 -248.896124)
		(width 0.127)
		(layer "F.Cu")
		(net "PHY_DRV_B_TO_SCC_B_7_DP")
	)
	(segment
		(start 357.463598 -249.258074)
		(end 357.463598 -249.056398)
		(width 0.127)
		(layer "F.Cu")
		(net "PHY_DRV_B_TO_SCC_B_7_DP")
	)
	(segment
		(start 357.303324 -248.896124)
		(end 355.266752 -248.896124)
		(width 0.127)
		(layer "F.Cu")
		(net "PHY_DRV_B_TO_SCC_B_7_DP")
	)
	(segment
		(start 357.590598 -249.385074)
		(end 357.463598 -249.258074)
		(width 0.127)
		(layer "F.Cu")
		(net "PHY_DRV_B_TO_SCC_B_7_DP")
	)
	(segment
		(start 358.925114 -249.385074)
		(end 357.590598 -249.385074)
		(width 0.127)
		(layer "F.Cu")
		(net "PHY_DRV_B_TO_SCC_B_7_DP")
	)
	(segment
		(start 355.139752 -249.023124)
		(end 355.139752 -249.385074)
		(width 0.127)
		(layer "F.Cu")
		(net "PHY_DRV_B_TO_SCC_B_7_DP")
	)
	(arc
		(start 355.266752 -248.896124)
		(mid 355.176949 -248.933321)
		(end 355.139752 -249.023124)
		(width 0.127)
		(layer "F.Cu")
		(net "PHY_DRV_B_TO_SCC_B_7_DP")
	)
	(segment
		(start 286.588454 -227.162868)
		(end 290.542218 -227.162868)
		(width 0.12065)
		(layer "In5.Cu")
		(net "PHY_DRV_B_TO_SCC_B_7_DP")
	)
	(segment
		(start 352.04527 -248.918222)
		(end 355.019102 -248.918222)
		(width 0.12065)
		(layer "In5.Cu")
		(net "PHY_DRV_B_TO_SCC_B_7_DP")
	)
	(segment
		(start 290.542218 -227.162868)
		(end 319.811908 -234.71632)
		(width 0.12065)
		(layer "In5.Cu")
		(net "PHY_DRV_B_TO_SCC_B_7_DP")
	)
	(segment
		(start 285.436564 -226.094544)
		(end 285.72333 -226.094544)
		(width 0.12065)
		(layer "In5.Cu")
		(net "PHY_DRV_B_TO_SCC_B_7_DP")
	)
	(segment
		(start 285.968186 -226.3394)
		(end 285.968186 -226.5426)
		(width 0.12065)
		(layer "In5.Cu")
		(net "PHY_DRV_B_TO_SCC_B_7_DP")
	)
	(segment
		(start 319.811908 -234.71632)
		(end 352.04527 -248.918222)
		(width 0.12065)
		(layer "In5.Cu")
		(net "PHY_DRV_B_TO_SCC_B_7_DP")
	)
	(segment
		(start 355.139752 -249.038872)
		(end 355.139752 -249.385074)
		(width 0.12065)
		(layer "In5.Cu")
		(net "PHY_DRV_B_TO_SCC_B_7_DP")
	)
	(arc
		(start 285.72333 -226.094544)
		(mid 285.896469 -226.166261)
		(end 285.968186 -226.3394)
		(width 0.12065)
		(layer "In5.Cu")
		(net "PHY_DRV_B_TO_SCC_B_7_DP")
	)
	(arc
		(start 285.968186 -226.5426)
		(mid 286.149858 -226.981196)
		(end 286.588454 -227.162868)
		(width 0.12065)
		(layer "In5.Cu")
		(net "PHY_DRV_B_TO_SCC_B_7_DP")
	)
	(arc
		(start 355.019102 -248.918222)
		(mid 355.104414 -248.95356)
		(end 355.139752 -249.038872)
		(width 0.12065)
		(layer "In5.Cu")
		(net "PHY_DRV_B_TO_SCC_B_7_DP")
	)
	(segment
		(start 355.139752 -248.477024)
		(end 355.139752 -248.115074)
		(width 0.127)
		(layer "F.Cu")
		(net "PHY_DRV_B_TO_SCC_B_7_DN")
	)
	(segment
		(start 357.463598 -248.242074)
		(end 357.463598 -248.477024)
		(width 0.127)
		(layer "F.Cu")
		(net "PHY_DRV_B_TO_SCC_B_7_DN")
	)
	(segment
		(start 357.336598 -248.604024)
		(end 355.266752 -248.604024)
		(width 0.127)
		(layer "F.Cu")
		(net "PHY_DRV_B_TO_SCC_B_7_DN")
	)
	(segment
		(start 358.925114 -248.115074)
		(end 357.590598 -248.115074)
		(width 0.127)
		(layer "F.Cu")
		(net "PHY_DRV_B_TO_SCC_B_7_DN")
	)
	(segment
		(start 357.590598 -248.115074)
		(end 357.463598 -248.242074)
		(width 0.127)
		(layer "F.Cu")
		(net "PHY_DRV_B_TO_SCC_B_7_DN")
	)
	(segment
		(start 357.463598 -248.477024)
		(end 357.336598 -248.604024)
		(width 0.127)
		(layer "F.Cu")
		(net "PHY_DRV_B_TO_SCC_B_7_DN")
	)
	(arc
		(start 355.266752 -248.604024)
		(mid 355.176949 -248.566827)
		(end 355.139752 -248.477024)
		(width 0.127)
		(layer "F.Cu")
		(net "PHY_DRV_B_TO_SCC_B_7_DN")
	)
	(segment
		(start 346.096082 -245.707154)
		(end 346.200222 -245.97487)
		(width 0.12065)
		(layer "In5.Cu")
		(net "PHY_DRV_B_TO_SCC_B_7_DN")
	)
	(segment
		(start 346.200222 -245.97487)
		(end 346.531438 -246.12092)
		(width 0.12065)
		(layer "In5.Cu")
		(net "PHY_DRV_B_TO_SCC_B_7_DN")
	)
	(segment
		(start 348.268798 -246.886476)
		(end 352.116136 -248.581672)
		(width 0.12065)
		(layer "In5.Cu")
		(net "PHY_DRV_B_TO_SCC_B_7_DN")
	)
	(segment
		(start 347.13037 -246.16283)
		(end 347.23451 -246.430546)
		(width 0.12065)
		(layer "In5.Cu")
		(net "PHY_DRV_B_TO_SCC_B_7_DN")
	)
	(segment
		(start 345.49715 -245.665244)
		(end 345.764866 -245.561104)
		(width 0.12065)
		(layer "In5.Cu")
		(net "PHY_DRV_B_TO_SCC_B_7_DN")
	)
	(segment
		(start 319.923668 -234.39755)
		(end 345.49715 -245.665244)
		(width 0.12065)
		(layer "In5.Cu")
		(net "PHY_DRV_B_TO_SCC_B_7_DN")
	)
	(segment
		(start 352.116136 -248.581672)
		(end 355.019102 -248.581672)
		(width 0.12065)
		(layer "In5.Cu")
		(net "PHY_DRV_B_TO_SCC_B_7_DN")
	)
	(segment
		(start 286.836612 -226.094544)
		(end 286.549592 -226.094544)
		(width 0.12065)
		(layer "In5.Cu")
		(net "PHY_DRV_B_TO_SCC_B_7_DN")
	)
	(segment
		(start 347.565726 -246.576596)
		(end 347.833442 -246.47271)
		(width 0.12065)
		(layer "In5.Cu")
		(net "PHY_DRV_B_TO_SCC_B_7_DN")
	)
	(segment
		(start 286.588454 -226.826318)
		(end 290.585144 -226.826318)
		(width 0.12065)
		(layer "In5.Cu")
		(net "PHY_DRV_B_TO_SCC_B_7_DN")
	)
	(segment
		(start 346.799154 -246.01678)
		(end 347.13037 -246.16283)
		(width 0.12065)
		(layer "In5.Cu")
		(net "PHY_DRV_B_TO_SCC_B_7_DN")
	)
	(segment
		(start 348.164658 -246.618506)
		(end 348.268798 -246.886476)
		(width 0.12065)
		(layer "In5.Cu")
		(net "PHY_DRV_B_TO_SCC_B_7_DN")
	)
	(segment
		(start 286.304736 -226.3394)
		(end 286.304736 -226.5426)
		(width 0.12065)
		(layer "In5.Cu")
		(net "PHY_DRV_B_TO_SCC_B_7_DN")
	)
	(segment
		(start 355.139752 -248.461022)
		(end 355.139752 -248.115074)
		(width 0.12065)
		(layer "In5.Cu")
		(net "PHY_DRV_B_TO_SCC_B_7_DN")
	)
	(segment
		(start 347.23451 -246.430546)
		(end 347.565726 -246.576596)
		(width 0.12065)
		(layer "In5.Cu")
		(net "PHY_DRV_B_TO_SCC_B_7_DN")
	)
	(segment
		(start 346.531438 -246.12092)
		(end 346.799154 -246.01678)
		(width 0.12065)
		(layer "In5.Cu")
		(net "PHY_DRV_B_TO_SCC_B_7_DN")
	)
	(segment
		(start 290.585144 -226.826318)
		(end 305.261264 -230.613712)
		(width 0.12065)
		(layer "In5.Cu")
		(net "PHY_DRV_B_TO_SCC_B_7_DN")
	)
	(segment
		(start 345.764866 -245.561104)
		(end 346.096082 -245.707154)
		(width 0.12065)
		(layer "In5.Cu")
		(net "PHY_DRV_B_TO_SCC_B_7_DN")
	)
	(segment
		(start 305.261264 -230.613712)
		(end 319.923668 -234.39755)
		(width 0.12065)
		(layer "In5.Cu")
		(net "PHY_DRV_B_TO_SCC_B_7_DN")
	)
	(segment
		(start 347.833442 -246.47271)
		(end 348.164658 -246.618506)
		(width 0.12065)
		(layer "In5.Cu")
		(net "PHY_DRV_B_TO_SCC_B_7_DN")
	)
	(arc
		(start 286.549592 -226.094544)
		(mid 286.376453 -226.166261)
		(end 286.304736 -226.3394)
		(width 0.12065)
		(layer "In5.Cu")
		(net "PHY_DRV_B_TO_SCC_B_7_DN")
	)
	(arc
		(start 286.304736 -226.5426)
		(mid 286.387835 -226.743219)
		(end 286.588454 -226.826318)
		(width 0.12065)
		(layer "In5.Cu")
		(net "PHY_DRV_B_TO_SCC_B_7_DN")
	)
	(arc
		(start 355.019102 -248.581672)
		(mid 355.104414 -248.546334)
		(end 355.139752 -248.461022)
		(width 0.12065)
		(layer "In5.Cu")
		(net "PHY_DRV_B_TO_SCC_B_7_DN")
	)
	(segment
		(start 325.913496 -249.053096)
		(end 325.756524 -248.896124)
		(width 0.127)
		(layer "F.Cu")
		(net "PHY_DRV_B_TO_SCC_B_6_DP")
	)
	(segment
		(start 327.375012 -249.385074)
		(end 326.040496 -249.385074)
		(width 0.127)
		(layer "F.Cu")
		(net "PHY_DRV_B_TO_SCC_B_6_DP")
	)
	(segment
		(start 326.040496 -249.385074)
		(end 325.913496 -249.258074)
		(width 0.127)
		(layer "F.Cu")
		(net "PHY_DRV_B_TO_SCC_B_6_DP")
	)
	(segment
		(start 325.913496 -249.258074)
		(end 325.913496 -249.053096)
		(width 0.127)
		(layer "F.Cu")
		(net "PHY_DRV_B_TO_SCC_B_6_DP")
	)
	(segment
		(start 323.58965 -249.023124)
		(end 323.58965 -249.385074)
		(width 0.127)
		(layer "F.Cu")
		(net "PHY_DRV_B_TO_SCC_B_6_DP")
	)
	(segment
		(start 325.756524 -248.896124)
		(end 323.71665 -248.896124)
		(width 0.127)
		(layer "F.Cu")
		(net "PHY_DRV_B_TO_SCC_B_6_DP")
	)
	(arc
		(start 323.71665 -248.896124)
		(mid 323.626847 -248.933321)
		(end 323.58965 -249.023124)
		(width 0.127)
		(layer "F.Cu")
		(net "PHY_DRV_B_TO_SCC_B_6_DP")
	)
	(segment
		(start 286.436562 -227.894388)
		(end 286.770572 -227.894388)
		(width 0.12065)
		(layer "In5.Cu")
		(net "PHY_DRV_B_TO_SCC_B_6_DP")
	)
	(segment
		(start 321.673982 -248.918222)
		(end 323.469 -248.918222)
		(width 0.12065)
		(layer "In5.Cu")
		(net "PHY_DRV_B_TO_SCC_B_6_DP")
	)
	(segment
		(start 290.944808 -228.962712)
		(end 321.673982 -248.918222)
		(width 0.12065)
		(layer "In5.Cu")
		(net "PHY_DRV_B_TO_SCC_B_6_DP")
	)
	(segment
		(start 287.610296 -228.962712)
		(end 290.944808 -228.962712)
		(width 0.12065)
		(layer "In5.Cu")
		(net "PHY_DRV_B_TO_SCC_B_6_DP")
	)
	(segment
		(start 286.968184 -228.092)
		(end 286.968184 -228.3206)
		(width 0.12065)
		(layer "In5.Cu")
		(net "PHY_DRV_B_TO_SCC_B_6_DP")
	)
	(segment
		(start 323.58965 -249.038872)
		(end 323.58965 -249.385074)
		(width 0.12065)
		(layer "In5.Cu")
		(net "PHY_DRV_B_TO_SCC_B_6_DP")
	)
	(arc
		(start 286.968184 -228.3206)
		(mid 287.156254 -228.774642)
		(end 287.610296 -228.962712)
		(width 0.12065)
		(layer "In5.Cu")
		(net "PHY_DRV_B_TO_SCC_B_6_DP")
	)
	(arc
		(start 286.770572 -227.894388)
		(mid 286.910305 -227.952267)
		(end 286.968184 -228.092)
		(width 0.12065)
		(layer "In5.Cu")
		(net "PHY_DRV_B_TO_SCC_B_6_DP")
	)
	(arc
		(start 323.469 -248.918222)
		(mid 323.554312 -248.95356)
		(end 323.58965 -249.038872)
		(width 0.12065)
		(layer "In5.Cu")
		(net "PHY_DRV_B_TO_SCC_B_6_DP")
	)
	(segment
		(start 323.58965 -248.477024)
		(end 323.58965 -248.115074)
		(width 0.127)
		(layer "F.Cu")
		(net "PHY_DRV_B_TO_SCC_B_6_DN")
	)
	(segment
		(start 327.375012 -248.115074)
		(end 326.040496 -248.115074)
		(width 0.127)
		(layer "F.Cu")
		(net "PHY_DRV_B_TO_SCC_B_6_DN")
	)
	(segment
		(start 325.786496 -248.604024)
		(end 323.71665 -248.604024)
		(width 0.127)
		(layer "F.Cu")
		(net "PHY_DRV_B_TO_SCC_B_6_DN")
	)
	(segment
		(start 325.913496 -248.477024)
		(end 325.786496 -248.604024)
		(width 0.127)
		(layer "F.Cu")
		(net "PHY_DRV_B_TO_SCC_B_6_DN")
	)
	(segment
		(start 325.913496 -248.242074)
		(end 325.913496 -248.477024)
		(width 0.127)
		(layer "F.Cu")
		(net "PHY_DRV_B_TO_SCC_B_6_DN")
	)
	(segment
		(start 326.040496 -248.115074)
		(end 325.913496 -248.242074)
		(width 0.127)
		(layer "F.Cu")
		(net "PHY_DRV_B_TO_SCC_B_6_DN")
	)
	(arc
		(start 323.71665 -248.604024)
		(mid 323.626847 -248.566827)
		(end 323.58965 -248.477024)
		(width 0.127)
		(layer "F.Cu")
		(net "PHY_DRV_B_TO_SCC_B_6_DN")
	)
	(segment
		(start 313.53887 -243.233702)
		(end 321.773804 -248.581672)
		(width 0.12065)
		(layer "In5.Cu")
		(net "PHY_DRV_B_TO_SCC_B_6_DN")
	)
	(segment
		(start 311.58307 -241.721386)
		(end 311.64276 -242.002564)
		(width 0.12065)
		(layer "In5.Cu")
		(net "PHY_DRV_B_TO_SCC_B_6_DN")
	)
	(segment
		(start 312.530998 -242.337082)
		(end 312.590942 -242.61826)
		(width 0.12065)
		(layer "In5.Cu")
		(net "PHY_DRV_B_TO_SCC_B_6_DN")
	)
	(segment
		(start 310.998362 -241.583972)
		(end 311.27954 -241.524282)
		(width 0.12065)
		(layer "In5.Cu")
		(net "PHY_DRV_B_TO_SCC_B_6_DN")
	)
	(segment
		(start 311.946544 -242.199668)
		(end 312.227468 -242.139978)
		(width 0.12065)
		(layer "In5.Cu")
		(net "PHY_DRV_B_TO_SCC_B_6_DN")
	)
	(segment
		(start 287.610296 -228.626162)
		(end 291.04463 -228.626162)
		(width 0.12065)
		(layer "In5.Cu")
		(net "PHY_DRV_B_TO_SCC_B_6_DN")
	)
	(segment
		(start 312.590942 -242.61826)
		(end 312.894472 -242.815364)
		(width 0.12065)
		(layer "In5.Cu")
		(net "PHY_DRV_B_TO_SCC_B_6_DN")
	)
	(segment
		(start 287.83661 -227.894388)
		(end 287.502346 -227.894388)
		(width 0.12065)
		(layer "In5.Cu")
		(net "PHY_DRV_B_TO_SCC_B_6_DN")
	)
	(segment
		(start 291.04463 -228.626162)
		(end 310.998362 -241.583972)
		(width 0.12065)
		(layer "In5.Cu")
		(net "PHY_DRV_B_TO_SCC_B_6_DN")
	)
	(segment
		(start 311.27954 -241.524282)
		(end 311.58307 -241.721386)
		(width 0.12065)
		(layer "In5.Cu")
		(net "PHY_DRV_B_TO_SCC_B_6_DN")
	)
	(segment
		(start 312.227468 -242.139978)
		(end 312.530998 -242.337082)
		(width 0.12065)
		(layer "In5.Cu")
		(net "PHY_DRV_B_TO_SCC_B_6_DN")
	)
	(segment
		(start 313.175396 -242.75542)
		(end 313.478926 -242.952778)
		(width 0.12065)
		(layer "In5.Cu")
		(net "PHY_DRV_B_TO_SCC_B_6_DN")
	)
	(segment
		(start 311.64276 -242.002564)
		(end 311.946544 -242.199668)
		(width 0.12065)
		(layer "In5.Cu")
		(net "PHY_DRV_B_TO_SCC_B_6_DN")
	)
	(segment
		(start 321.773804 -248.581672)
		(end 323.469 -248.581672)
		(width 0.12065)
		(layer "In5.Cu")
		(net "PHY_DRV_B_TO_SCC_B_6_DN")
	)
	(segment
		(start 323.58965 -248.461022)
		(end 323.58965 -248.115074)
		(width 0.12065)
		(layer "In5.Cu")
		(net "PHY_DRV_B_TO_SCC_B_6_DN")
	)
	(segment
		(start 312.894472 -242.815364)
		(end 313.175396 -242.75542)
		(width 0.12065)
		(layer "In5.Cu")
		(net "PHY_DRV_B_TO_SCC_B_6_DN")
	)
	(segment
		(start 313.478926 -242.952778)
		(end 313.53887 -243.233702)
		(width 0.12065)
		(layer "In5.Cu")
		(net "PHY_DRV_B_TO_SCC_B_6_DN")
	)
	(segment
		(start 287.304734 -228.092)
		(end 287.304734 -228.3206)
		(width 0.12065)
		(layer "In5.Cu")
		(net "PHY_DRV_B_TO_SCC_B_6_DN")
	)
	(arc
		(start 323.469 -248.581672)
		(mid 323.554312 -248.546334)
		(end 323.58965 -248.461022)
		(width 0.12065)
		(layer "In5.Cu")
		(net "PHY_DRV_B_TO_SCC_B_6_DN")
	)
	(arc
		(start 287.304734 -228.3206)
		(mid 287.394231 -228.536665)
		(end 287.610296 -228.626162)
		(width 0.12065)
		(layer "In5.Cu")
		(net "PHY_DRV_B_TO_SCC_B_6_DN")
	)
	(arc
		(start 287.502346 -227.894388)
		(mid 287.362613 -227.952267)
		(end 287.304734 -228.092)
		(width 0.12065)
		(layer "In5.Cu")
		(net "PHY_DRV_B_TO_SCC_B_6_DN")
	)
	(segment
		(start 190.258954 -249.023124)
		(end 190.258954 -249.385074)
		(width 0.127)
		(layer "F.Cu")
		(net "PHY_DRV_B_TO_SCC_B_5_DP")
	)
	(segment
		(start 189.109604 -249.385074)
		(end 189.236604 -249.258074)
		(width 0.127)
		(layer "F.Cu")
		(net "PHY_DRV_B_TO_SCC_B_5_DP")
	)
	(segment
		(start 187.775088 -249.385074)
		(end 189.109604 -249.385074)
		(width 0.127)
		(layer "F.Cu")
		(net "PHY_DRV_B_TO_SCC_B_5_DP")
	)
	(segment
		(start 189.330076 -248.896124)
		(end 190.131954 -248.896124)
		(width 0.127)
		(layer "F.Cu")
		(net "PHY_DRV_B_TO_SCC_B_5_DP")
	)
	(segment
		(start 189.236604 -248.989596)
		(end 189.330076 -248.896124)
		(width 0.127)
		(layer "F.Cu")
		(net "PHY_DRV_B_TO_SCC_B_5_DP")
	)
	(segment
		(start 189.236604 -249.258074)
		(end 189.236604 -248.989596)
		(width 0.127)
		(layer "F.Cu")
		(net "PHY_DRV_B_TO_SCC_B_5_DP")
	)
	(arc
		(start 190.131954 -248.896124)
		(mid 190.221757 -248.933321)
		(end 190.258954 -249.023124)
		(width 0.127)
		(layer "F.Cu")
		(net "PHY_DRV_B_TO_SCC_B_5_DP")
	)
	(segment
		(start 194.03949 -248.214642)
		(end 193.88836 -248.45899)
		(width 0.12065)
		(layer "In5.Cu")
		(net "PHY_DRV_B_TO_SCC_B_5_DP")
	)
	(segment
		(start 193.88836 -248.45899)
		(end 193.536062 -248.542048)
		(width 0.12065)
		(layer "In5.Cu")
		(net "PHY_DRV_B_TO_SCC_B_5_DP")
	)
	(segment
		(start 195.73621 -248.02338)
		(end 195.491862 -247.87225)
		(width 0.12065)
		(layer "In5.Cu")
		(net "PHY_DRV_B_TO_SCC_B_5_DP")
	)
	(segment
		(start 193.29146 -248.390918)
		(end 191.054482 -248.918222)
		(width 0.12065)
		(layer "In5.Cu")
		(net "PHY_DRV_B_TO_SCC_B_5_DP")
	)
	(segment
		(start 195.491862 -247.87225)
		(end 195.139564 -247.955308)
		(width 0.12065)
		(layer "In5.Cu")
		(net "PHY_DRV_B_TO_SCC_B_5_DP")
	)
	(segment
		(start 194.636136 -248.282714)
		(end 194.391788 -248.131584)
		(width 0.12065)
		(layer "In5.Cu")
		(net "PHY_DRV_B_TO_SCC_B_5_DP")
	)
	(segment
		(start 191.054482 -248.918222)
		(end 190.379604 -248.918222)
		(width 0.12065)
		(layer "In5.Cu")
		(net "PHY_DRV_B_TO_SCC_B_5_DP")
	)
	(segment
		(start 196.088508 -247.940322)
		(end 195.73621 -248.02338)
		(width 0.12065)
		(layer "In5.Cu")
		(net "PHY_DRV_B_TO_SCC_B_5_DP")
	)
	(segment
		(start 194.391788 -248.131584)
		(end 194.03949 -248.214642)
		(width 0.12065)
		(layer "In5.Cu")
		(net "PHY_DRV_B_TO_SCC_B_5_DP")
	)
	(segment
		(start 286.628078 -237.962694)
		(end 251.273056 -237.962694)
		(width 0.12065)
		(layer "In5.Cu")
		(net "PHY_DRV_B_TO_SCC_B_5_DP")
	)
	(segment
		(start 190.258954 -249.038872)
		(end 190.258954 -249.385074)
		(width 0.12065)
		(layer "In5.Cu")
		(net "PHY_DRV_B_TO_SCC_B_5_DP")
	)
	(segment
		(start 196.239638 -247.695974)
		(end 196.088508 -247.940322)
		(width 0.12065)
		(layer "In5.Cu")
		(net "PHY_DRV_B_TO_SCC_B_5_DP")
	)
	(segment
		(start 286.968184 -238.5314)
		(end 286.968184 -238.3028)
		(width 0.12065)
		(layer "In5.Cu")
		(net "PHY_DRV_B_TO_SCC_B_5_DP")
	)
	(segment
		(start 194.988434 -248.199656)
		(end 194.636136 -248.282714)
		(width 0.12065)
		(layer "In5.Cu")
		(net "PHY_DRV_B_TO_SCC_B_5_DP")
	)
	(segment
		(start 195.139564 -247.955308)
		(end 194.988434 -248.199656)
		(width 0.12065)
		(layer "In5.Cu")
		(net "PHY_DRV_B_TO_SCC_B_5_DP")
	)
	(segment
		(start 193.536062 -248.542048)
		(end 193.29146 -248.390918)
		(width 0.12065)
		(layer "In5.Cu")
		(net "PHY_DRV_B_TO_SCC_B_5_DP")
	)
	(segment
		(start 286.436562 -238.694468)
		(end 286.805116 -238.694468)
		(width 0.12065)
		(layer "In5.Cu")
		(net "PHY_DRV_B_TO_SCC_B_5_DP")
	)
	(segment
		(start 244.046756 -236.426756)
		(end 196.239638 -247.695974)
		(width 0.12065)
		(layer "In5.Cu")
		(net "PHY_DRV_B_TO_SCC_B_5_DP")
	)
	(segment
		(start 251.273056 -237.962694)
		(end 244.046756 -236.426756)
		(width 0.12065)
		(layer "In5.Cu")
		(net "PHY_DRV_B_TO_SCC_B_5_DP")
	)
	(arc
		(start 286.805116 -238.694468)
		(mid 286.920422 -238.646706)
		(end 286.968184 -238.5314)
		(width 0.12065)
		(layer "In5.Cu")
		(net "PHY_DRV_B_TO_SCC_B_5_DP")
	)
	(arc
		(start 286.968184 -238.3028)
		(mid 286.868569 -238.062309)
		(end 286.628078 -237.962694)
		(width 0.12065)
		(layer "In5.Cu")
		(net "PHY_DRV_B_TO_SCC_B_5_DP")
	)
	(arc
		(start 190.379604 -248.918222)
		(mid 190.294292 -248.95356)
		(end 190.258954 -249.038872)
		(width 0.12065)
		(layer "In5.Cu")
		(net "PHY_DRV_B_TO_SCC_B_5_DP")
	)
	(segment
		(start 189.236604 -248.477024)
		(end 189.363604 -248.604024)
		(width 0.127)
		(layer "F.Cu")
		(net "PHY_DRV_B_TO_SCC_B_5_DN")
	)
	(segment
		(start 189.109604 -248.115074)
		(end 189.236604 -248.242074)
		(width 0.127)
		(layer "F.Cu")
		(net "PHY_DRV_B_TO_SCC_B_5_DN")
	)
	(segment
		(start 189.363604 -248.604024)
		(end 190.131954 -248.604024)
		(width 0.127)
		(layer "F.Cu")
		(net "PHY_DRV_B_TO_SCC_B_5_DN")
	)
	(segment
		(start 189.236604 -248.242074)
		(end 189.236604 -248.477024)
		(width 0.127)
		(layer "F.Cu")
		(net "PHY_DRV_B_TO_SCC_B_5_DN")
	)
	(segment
		(start 187.775088 -248.115074)
		(end 189.109604 -248.115074)
		(width 0.127)
		(layer "F.Cu")
		(net "PHY_DRV_B_TO_SCC_B_5_DN")
	)
	(segment
		(start 190.258954 -248.477024)
		(end 190.258954 -248.115074)
		(width 0.127)
		(layer "F.Cu")
		(net "PHY_DRV_B_TO_SCC_B_5_DN")
	)
	(arc
		(start 190.131954 -248.604024)
		(mid 190.221757 -248.566827)
		(end 190.258954 -248.477024)
		(width 0.127)
		(layer "F.Cu")
		(net "PHY_DRV_B_TO_SCC_B_5_DN")
	)
	(segment
		(start 251.308616 -237.626144)
		(end 247.73001 -236.865414)
		(width 0.12065)
		(layer "In5.Cu")
		(net "PHY_DRV_B_TO_SCC_B_5_DN")
	)
	(segment
		(start 286.628078 -237.626144)
		(end 251.308616 -237.626144)
		(width 0.12065)
		(layer "In5.Cu")
		(net "PHY_DRV_B_TO_SCC_B_5_DN")
	)
	(segment
		(start 190.258954 -248.461022)
		(end 190.258954 -248.115074)
		(width 0.12065)
		(layer "In5.Cu")
		(net "PHY_DRV_B_TO_SCC_B_5_DN")
	)
	(segment
		(start 244.042946 -236.081824)
		(end 191.015112 -248.581672)
		(width 0.12065)
		(layer "In5.Cu")
		(net "PHY_DRV_B_TO_SCC_B_5_DN")
	)
	(segment
		(start 287.83661 -238.694468)
		(end 287.467802 -238.694468)
		(width 0.12065)
		(layer "In5.Cu")
		(net "PHY_DRV_B_TO_SCC_B_5_DN")
	)
	(segment
		(start 191.015112 -248.581672)
		(end 190.379604 -248.581672)
		(width 0.12065)
		(layer "In5.Cu")
		(net "PHY_DRV_B_TO_SCC_B_5_DN")
	)
	(segment
		(start 247.73001 -236.865414)
		(end 244.042946 -236.081824)
		(width 0.12065)
		(layer "In5.Cu")
		(net "PHY_DRV_B_TO_SCC_B_5_DN")
	)
	(segment
		(start 287.304734 -238.5314)
		(end 287.304734 -238.3028)
		(width 0.12065)
		(layer "In5.Cu")
		(net "PHY_DRV_B_TO_SCC_B_5_DN")
	)
	(arc
		(start 190.379604 -248.581672)
		(mid 190.294292 -248.546334)
		(end 190.258954 -248.461022)
		(width 0.12065)
		(layer "In5.Cu")
		(net "PHY_DRV_B_TO_SCC_B_5_DN")
	)
	(arc
		(start 287.467802 -238.694468)
		(mid 287.352496 -238.646706)
		(end 287.304734 -238.5314)
		(width 0.12065)
		(layer "In5.Cu")
		(net "PHY_DRV_B_TO_SCC_B_5_DN")
	)
	(arc
		(start 287.304734 -238.3028)
		(mid 287.106546 -237.824332)
		(end 286.628078 -237.626144)
		(width 0.12065)
		(layer "In5.Cu")
		(net "PHY_DRV_B_TO_SCC_B_5_DN")
	)
	(segment
		(start 158.708852 -249.023124)
		(end 158.708852 -249.385074)
		(width 0.127)
		(layer "F.Cu")
		(net "PHY_DRV_B_TO_SCC_B_4_DP")
	)
	(segment
		(start 156.224986 -249.385074)
		(end 157.559502 -249.385074)
		(width 0.127)
		(layer "F.Cu")
		(net "PHY_DRV_B_TO_SCC_B_4_DP")
	)
	(segment
		(start 157.6832 -249.026426)
		(end 157.813502 -248.896124)
		(width 0.127)
		(layer "F.Cu")
		(net "PHY_DRV_B_TO_SCC_B_4_DP")
	)
	(segment
		(start 157.813502 -248.896124)
		(end 158.581852 -248.896124)
		(width 0.127)
		(layer "F.Cu")
		(net "PHY_DRV_B_TO_SCC_B_4_DP")
	)
	(segment
		(start 157.6832 -249.261376)
		(end 157.6832 -249.026426)
		(width 0.127)
		(layer "F.Cu")
		(net "PHY_DRV_B_TO_SCC_B_4_DP")
	)
	(segment
		(start 157.559502 -249.385074)
		(end 157.6832 -249.261376)
		(width 0.127)
		(layer "F.Cu")
		(net "PHY_DRV_B_TO_SCC_B_4_DP")
	)
	(arc
		(start 158.581852 -248.896124)
		(mid 158.671655 -248.933321)
		(end 158.708852 -249.023124)
		(width 0.127)
		(layer "F.Cu")
		(net "PHY_DRV_B_TO_SCC_B_4_DP")
	)
	(segment
		(start 158.708852 -249.038872)
		(end 158.708852 -249.385074)
		(width 0.12065)
		(layer "In5.Cu")
		(net "PHY_DRV_B_TO_SCC_B_4_DP")
	)
	(segment
		(start 161.406078 -248.891298)
		(end 161.050732 -248.960132)
		(width 0.12065)
		(layer "In5.Cu")
		(net "PHY_DRV_B_TO_SCC_B_4_DP")
	)
	(segment
		(start 161.050732 -248.960132)
		(end 160.812734 -248.799096)
		(width 0.12065)
		(layer "In5.Cu")
		(net "PHY_DRV_B_TO_SCC_B_4_DP")
	)
	(segment
		(start 163.270184 -248.530618)
		(end 163.032186 -248.369582)
		(width 0.12065)
		(layer "In5.Cu")
		(net "PHY_DRV_B_TO_SCC_B_4_DP")
	)
	(segment
		(start 161.567114 -248.653046)
		(end 161.406078 -248.891298)
		(width 0.12065)
		(layer "In5.Cu")
		(net "PHY_DRV_B_TO_SCC_B_4_DP")
	)
	(segment
		(start 255.113536 -236.162596)
		(end 251.86894 -236.85246)
		(width 0.12065)
		(layer "In5.Cu")
		(net "PHY_DRV_B_TO_SCC_B_4_DP")
	)
	(segment
		(start 205.087474 -239.841024)
		(end 184.5945 -244.19687)
		(width 0.12065)
		(layer "In5.Cu")
		(net "PHY_DRV_B_TO_SCC_B_4_DP")
	)
	(segment
		(start 251.86894 -236.85246)
		(end 244.221762 -235.227368)
		(width 0.12065)
		(layer "In5.Cu")
		(net "PHY_DRV_B_TO_SCC_B_4_DP")
	)
	(segment
		(start 162.515804 -248.676414)
		(end 162.160458 -248.745248)
		(width 0.12065)
		(layer "In5.Cu")
		(net "PHY_DRV_B_TO_SCC_B_4_DP")
	)
	(segment
		(start 162.160458 -248.745248)
		(end 161.92246 -248.584466)
		(width 0.12065)
		(layer "In5.Cu")
		(net "PHY_DRV_B_TO_SCC_B_4_DP")
	)
	(segment
		(start 244.221762 -235.227368)
		(end 214.029798 -241.644932)
		(width 0.12065)
		(layer "In5.Cu")
		(net "PHY_DRV_B_TO_SCC_B_4_DP")
	)
	(segment
		(start 163.62553 -248.461784)
		(end 163.270184 -248.530618)
		(width 0.12065)
		(layer "In5.Cu")
		(net "PHY_DRV_B_TO_SCC_B_4_DP")
	)
	(segment
		(start 285.436564 -236.89437)
		(end 285.805118 -236.89437)
		(width 0.12065)
		(layer "In5.Cu")
		(net "PHY_DRV_B_TO_SCC_B_4_DP")
	)
	(segment
		(start 162.676586 -248.438416)
		(end 162.515804 -248.676414)
		(width 0.12065)
		(layer "In5.Cu")
		(net "PHY_DRV_B_TO_SCC_B_4_DP")
	)
	(segment
		(start 163.032186 -248.369582)
		(end 162.676586 -248.438416)
		(width 0.12065)
		(layer "In5.Cu")
		(net "PHY_DRV_B_TO_SCC_B_4_DP")
	)
	(segment
		(start 184.5945 -244.19687)
		(end 163.786312 -248.223532)
		(width 0.12065)
		(layer "In5.Cu")
		(net "PHY_DRV_B_TO_SCC_B_4_DP")
	)
	(segment
		(start 214.029798 -241.644932)
		(end 205.087474 -239.841024)
		(width 0.12065)
		(layer "In5.Cu")
		(net "PHY_DRV_B_TO_SCC_B_4_DP")
	)
	(segment
		(start 285.968186 -236.731302)
		(end 285.968186 -236.502702)
		(width 0.12065)
		(layer "In5.Cu")
		(net "PHY_DRV_B_TO_SCC_B_4_DP")
	)
	(segment
		(start 161.92246 -248.584466)
		(end 161.567114 -248.653046)
		(width 0.12065)
		(layer "In5.Cu")
		(net "PHY_DRV_B_TO_SCC_B_4_DP")
	)
	(segment
		(start 285.62808 -236.162596)
		(end 255.113536 -236.162596)
		(width 0.12065)
		(layer "In5.Cu")
		(net "PHY_DRV_B_TO_SCC_B_4_DP")
	)
	(segment
		(start 160.197038 -248.918222)
		(end 158.829502 -248.918222)
		(width 0.12065)
		(layer "In5.Cu")
		(net "PHY_DRV_B_TO_SCC_B_4_DP")
	)
	(segment
		(start 160.812734 -248.799096)
		(end 160.197038 -248.918222)
		(width 0.12065)
		(layer "In5.Cu")
		(net "PHY_DRV_B_TO_SCC_B_4_DP")
	)
	(segment
		(start 163.786312 -248.223532)
		(end 163.62553 -248.461784)
		(width 0.12065)
		(layer "In5.Cu")
		(net "PHY_DRV_B_TO_SCC_B_4_DP")
	)
	(arc
		(start 285.805118 -236.89437)
		(mid 285.920424 -236.846608)
		(end 285.968186 -236.731302)
		(width 0.12065)
		(layer "In5.Cu")
		(net "PHY_DRV_B_TO_SCC_B_4_DP")
	)
	(arc
		(start 285.968186 -236.502702)
		(mid 285.868571 -236.262211)
		(end 285.62808 -236.162596)
		(width 0.12065)
		(layer "In5.Cu")
		(net "PHY_DRV_B_TO_SCC_B_4_DP")
	)
	(arc
		(start 158.829502 -248.918222)
		(mid 158.74419 -248.95356)
		(end 158.708852 -249.038872)
		(width 0.12065)
		(layer "In5.Cu")
		(net "PHY_DRV_B_TO_SCC_B_4_DP")
	)
	(segment
		(start 157.559502 -248.115074)
		(end 157.686502 -248.242074)
		(width 0.127)
		(layer "F.Cu")
		(net "PHY_DRV_B_TO_SCC_B_4_DN")
	)
	(segment
		(start 157.813502 -248.604024)
		(end 158.581852 -248.604024)
		(width 0.127)
		(layer "F.Cu")
		(net "PHY_DRV_B_TO_SCC_B_4_DN")
	)
	(segment
		(start 157.686502 -248.242074)
		(end 157.686502 -248.477024)
		(width 0.127)
		(layer "F.Cu")
		(net "PHY_DRV_B_TO_SCC_B_4_DN")
	)
	(segment
		(start 158.708852 -248.477024)
		(end 158.708852 -248.115074)
		(width 0.127)
		(layer "F.Cu")
		(net "PHY_DRV_B_TO_SCC_B_4_DN")
	)
	(segment
		(start 156.224986 -248.115074)
		(end 157.559502 -248.115074)
		(width 0.127)
		(layer "F.Cu")
		(net "PHY_DRV_B_TO_SCC_B_4_DN")
	)
	(segment
		(start 157.686502 -248.477024)
		(end 157.813502 -248.604024)
		(width 0.127)
		(layer "F.Cu")
		(net "PHY_DRV_B_TO_SCC_B_4_DN")
	)
	(arc
		(start 158.581852 -248.604024)
		(mid 158.671655 -248.566827)
		(end 158.708852 -248.477024)
		(width 0.127)
		(layer "F.Cu")
		(net "PHY_DRV_B_TO_SCC_B_4_DN")
	)
	(segment
		(start 184.634378 -243.844064)
		(end 160.16478 -248.581672)
		(width 0.12065)
		(layer "In5.Cu")
		(net "PHY_DRV_B_TO_SCC_B_4_DN")
	)
	(segment
		(start 158.708852 -248.461022)
		(end 158.708852 -248.115074)
		(width 0.12065)
		(layer "In5.Cu")
		(net "PHY_DRV_B_TO_SCC_B_4_DN")
	)
	(segment
		(start 285.62808 -235.826046)
		(end 255.077976 -235.826046)
		(width 0.12065)
		(layer "In5.Cu")
		(net "PHY_DRV_B_TO_SCC_B_4_DN")
	)
	(segment
		(start 255.077976 -235.826046)
		(end 251.86894 -236.50829)
		(width 0.12065)
		(layer "In5.Cu")
		(net "PHY_DRV_B_TO_SCC_B_4_DN")
	)
	(segment
		(start 205.085696 -239.497108)
		(end 184.634378 -243.844064)
		(width 0.12065)
		(layer "In5.Cu")
		(net "PHY_DRV_B_TO_SCC_B_4_DN")
	)
	(segment
		(start 286.304736 -236.731302)
		(end 286.304736 -236.502702)
		(width 0.12065)
		(layer "In5.Cu")
		(net "PHY_DRV_B_TO_SCC_B_4_DN")
	)
	(segment
		(start 214.02802 -241.301016)
		(end 205.085696 -239.497108)
		(width 0.12065)
		(layer "In5.Cu")
		(net "PHY_DRV_B_TO_SCC_B_4_DN")
	)
	(segment
		(start 286.836612 -236.89437)
		(end 286.467804 -236.89437)
		(width 0.12065)
		(layer "In5.Cu")
		(net "PHY_DRV_B_TO_SCC_B_4_DN")
	)
	(segment
		(start 160.16478 -248.581672)
		(end 158.829502 -248.581672)
		(width 0.12065)
		(layer "In5.Cu")
		(net "PHY_DRV_B_TO_SCC_B_4_DN")
	)
	(segment
		(start 244.221762 -234.883198)
		(end 214.02802 -241.301016)
		(width 0.12065)
		(layer "In5.Cu")
		(net "PHY_DRV_B_TO_SCC_B_4_DN")
	)
	(segment
		(start 251.86894 -236.50829)
		(end 244.221762 -234.883198)
		(width 0.12065)
		(layer "In5.Cu")
		(net "PHY_DRV_B_TO_SCC_B_4_DN")
	)
	(arc
		(start 158.829502 -248.581672)
		(mid 158.74419 -248.546334)
		(end 158.708852 -248.461022)
		(width 0.12065)
		(layer "In5.Cu")
		(net "PHY_DRV_B_TO_SCC_B_4_DN")
	)
	(arc
		(start 286.467804 -236.89437)
		(mid 286.352498 -236.846608)
		(end 286.304736 -236.731302)
		(width 0.12065)
		(layer "In5.Cu")
		(net "PHY_DRV_B_TO_SCC_B_4_DN")
	)
	(arc
		(start 286.304736 -236.502702)
		(mid 286.106548 -236.024234)
		(end 285.62808 -235.826046)
		(width 0.12065)
		(layer "In5.Cu")
		(net "PHY_DRV_B_TO_SCC_B_4_DN")
	)
	(segment
		(start 483.485698 -18.845276)
		(end 481.32492 -18.845276)
		(width 0.127)
		(layer "F.Cu")
		(net "PHY_DRV_B_TO_SCC_B_35_DP")
	)
	(segment
		(start 485.125014 -19.385026)
		(end 483.790498 -19.385026)
		(width 0.127)
		(layer "F.Cu")
		(net "PHY_DRV_B_TO_SCC_B_35_DP")
	)
	(segment
		(start 481.32492 -18.845276)
		(end 480.920552 -18.440908)
		(width 0.127)
		(layer "F.Cu")
		(net "PHY_DRV_B_TO_SCC_B_35_DP")
	)
	(segment
		(start 483.663498 -19.258026)
		(end 483.663498 -19.023076)
		(width 0.127)
		(layer "F.Cu")
		(net "PHY_DRV_B_TO_SCC_B_35_DP")
	)
	(segment
		(start 483.790498 -19.385026)
		(end 483.663498 -19.258026)
		(width 0.127)
		(layer "F.Cu")
		(net "PHY_DRV_B_TO_SCC_B_35_DP")
	)
	(segment
		(start 480.7585 -17.4371)
		(end 480.431602 -17.4371)
		(width 0.127)
		(layer "F.Cu")
		(net "PHY_DRV_B_TO_SCC_B_35_DP")
	)
	(segment
		(start 483.663498 -19.023076)
		(end 483.485698 -18.845276)
		(width 0.127)
		(layer "F.Cu")
		(net "PHY_DRV_B_TO_SCC_B_35_DP")
	)
	(segment
		(start 480.920552 -18.440908)
		(end 480.920552 -17.599152)
		(width 0.127)
		(layer "F.Cu")
		(net "PHY_DRV_B_TO_SCC_B_35_DP")
	)
	(arc
		(start 480.920552 -17.599152)
		(mid 480.873088 -17.484564)
		(end 480.7585 -17.4371)
		(width 0.127)
		(layer "F.Cu")
		(net "PHY_DRV_B_TO_SCC_B_35_DP")
	)
	(segment
		(start 433.226718 -41.21531)
		(end 468.986616 -33.613852)
		(width 0.12065)
		(layer "In5.Cu")
		(net "PHY_DRV_B_TO_SCC_B_35_DP")
	)
	(segment
		(start 316.766702 -140.40485)
		(end 321.588892 -129.332482)
		(width 0.12065)
		(layer "In5.Cu")
		(net "PHY_DRV_B_TO_SCC_B_35_DP")
	)
	(segment
		(start 321.588892 -129.332482)
		(end 351.502472 -109.906816)
		(width 0.12065)
		(layer "In5.Cu")
		(net "PHY_DRV_B_TO_SCC_B_35_DP")
	)
	(segment
		(start 480.7585 -17.4371)
		(end 480.431602 -17.4371)
		(width 0.12065)
		(layer "In5.Cu")
		(net "PHY_DRV_B_TO_SCC_B_35_DP")
	)
	(segment
		(start 474.656404 -29.931868)
		(end 480.24034 -21.334476)
		(width 0.12065)
		(layer "In5.Cu")
		(net "PHY_DRV_B_TO_SCC_B_35_DP")
	)
	(segment
		(start 480.8982 -18.240248)
		(end 480.8982 -17.5768)
		(width 0.12065)
		(layer "In5.Cu")
		(net "PHY_DRV_B_TO_SCC_B_35_DP")
	)
	(segment
		(start 399.159476 -78.958948)
		(end 416.697668 -51.949096)
		(width 0.12065)
		(layer "In5.Cu")
		(net "PHY_DRV_B_TO_SCC_B_35_DP")
	)
	(segment
		(start 286.436562 -184.694576)
		(end 286.779208 -184.694576)
		(width 0.12065)
		(layer "In5.Cu")
		(net "PHY_DRV_B_TO_SCC_B_35_DP")
	)
	(segment
		(start 351.502218 -109.906816)
		(end 399.159476 -78.958948)
		(width 0.12065)
		(layer "In5.Cu")
		(net "PHY_DRV_B_TO_SCC_B_35_DP")
	)
	(segment
		(start 287.542732 -183.626252)
		(end 290.088828 -183.626252)
		(width 0.12065)
		(layer "In5.Cu")
		(net "PHY_DRV_B_TO_SCC_B_35_DP")
	)
	(segment
		(start 311.971182 -162.96513)
		(end 316.766702 -140.40485)
		(width 0.12065)
		(layer "In5.Cu")
		(net "PHY_DRV_B_TO_SCC_B_35_DP")
	)
	(segment
		(start 304.728372 -174.118778)
		(end 311.971182 -162.96513)
		(width 0.12065)
		(layer "In5.Cu")
		(net "PHY_DRV_B_TO_SCC_B_35_DP")
	)
	(segment
		(start 468.986616 -33.613852)
		(end 474.656404 -29.931868)
		(width 0.12065)
		(layer "In5.Cu")
		(net "PHY_DRV_B_TO_SCC_B_35_DP")
	)
	(segment
		(start 290.088828 -183.626252)
		(end 304.728372 -174.118778)
		(width 0.12065)
		(layer "In5.Cu")
		(net "PHY_DRV_B_TO_SCC_B_35_DP")
	)
	(segment
		(start 480.24034 -21.334476)
		(end 480.8982 -18.240248)
		(width 0.12065)
		(layer "In5.Cu")
		(net "PHY_DRV_B_TO_SCC_B_35_DP")
	)
	(segment
		(start 351.502472 -109.906816)
		(end 351.502218 -109.906816)
		(width 0.12065)
		(layer "In5.Cu")
		(net "PHY_DRV_B_TO_SCC_B_35_DP")
	)
	(segment
		(start 416.697668 -51.949096)
		(end 433.226718 -41.21531)
		(width 0.12065)
		(layer "In5.Cu")
		(net "PHY_DRV_B_TO_SCC_B_35_DP")
	)
	(segment
		(start 286.968184 -184.5056)
		(end 286.968184 -184.2008)
		(width 0.12065)
		(layer "In5.Cu")
		(net "PHY_DRV_B_TO_SCC_B_35_DP")
	)
	(arc
		(start 286.968184 -184.2008)
		(mid 287.136465 -183.794533)
		(end 287.542732 -183.626252)
		(width 0.12065)
		(layer "In5.Cu")
		(net "PHY_DRV_B_TO_SCC_B_35_DP")
	)
	(arc
		(start 286.779208 -184.694576)
		(mid 286.912834 -184.639226)
		(end 286.968184 -184.5056)
		(width 0.12065)
		(layer "In5.Cu")
		(net "PHY_DRV_B_TO_SCC_B_35_DP")
	)
	(arc
		(start 480.8982 -17.5768)
		(mid 480.857283 -17.478017)
		(end 480.7585 -17.4371)
		(width 0.12065)
		(layer "In5.Cu")
		(net "PHY_DRV_B_TO_SCC_B_35_DP")
	)
	(segment
		(start 481.3935 -17.4371)
		(end 481.701602 -17.4371)
		(width 0.127)
		(layer "F.Cu")
		(net "PHY_DRV_B_TO_SCC_B_35_DN")
	)
	(segment
		(start 483.790498 -18.115026)
		(end 483.663498 -18.242026)
		(width 0.127)
		(layer "F.Cu")
		(net "PHY_DRV_B_TO_SCC_B_35_DN")
	)
	(segment
		(start 483.587298 -18.553176)
		(end 481.446078 -18.553176)
		(width 0.127)
		(layer "F.Cu")
		(net "PHY_DRV_B_TO_SCC_B_35_DN")
	)
	(segment
		(start 485.125014 -18.115026)
		(end 483.790498 -18.115026)
		(width 0.127)
		(layer "F.Cu")
		(net "PHY_DRV_B_TO_SCC_B_35_DN")
	)
	(segment
		(start 481.212652 -18.31975)
		(end 481.212652 -17.617948)
		(width 0.127)
		(layer "F.Cu")
		(net "PHY_DRV_B_TO_SCC_B_35_DN")
	)
	(segment
		(start 481.446078 -18.553176)
		(end 481.212652 -18.31975)
		(width 0.127)
		(layer "F.Cu")
		(net "PHY_DRV_B_TO_SCC_B_35_DN")
	)
	(segment
		(start 483.663498 -18.242026)
		(end 483.663498 -18.476976)
		(width 0.127)
		(layer "F.Cu")
		(net "PHY_DRV_B_TO_SCC_B_35_DN")
	)
	(segment
		(start 483.663498 -18.476976)
		(end 483.587298 -18.553176)
		(width 0.127)
		(layer "F.Cu")
		(net "PHY_DRV_B_TO_SCC_B_35_DN")
	)
	(arc
		(start 481.212652 -17.617948)
		(mid 481.265621 -17.490069)
		(end 481.3935 -17.4371)
		(width 0.127)
		(layer "F.Cu")
		(net "PHY_DRV_B_TO_SCC_B_35_DN")
	)
	(segment
		(start 416.941 -52.192428)
		(end 433.357782 -41.53154)
		(width 0.12065)
		(layer "In5.Cu")
		(net "PHY_DRV_B_TO_SCC_B_35_DN")
	)
	(segment
		(start 350.658176 -111.111284)
		(end 350.720914 -110.816136)
		(width 0.12065)
		(layer "In5.Cu")
		(net "PHY_DRV_B_TO_SCC_B_35_DN")
	)
	(segment
		(start 287.542732 -183.962802)
		(end 290.18865 -183.962802)
		(width 0.12065)
		(layer "In5.Cu")
		(net "PHY_DRV_B_TO_SCC_B_35_DN")
	)
	(segment
		(start 290.18865 -183.962802)
		(end 304.971704 -174.36211)
		(width 0.12065)
		(layer "In5.Cu")
		(net "PHY_DRV_B_TO_SCC_B_35_DN")
	)
	(segment
		(start 469.11768 -33.930082)
		(end 474.899736 -30.1752)
		(width 0.12065)
		(layer "In5.Cu")
		(net "PHY_DRV_B_TO_SCC_B_35_DN")
	)
	(segment
		(start 351.623122 -110.484412)
		(end 351.68586 -110.189264)
		(width 0.12065)
		(layer "In5.Cu")
		(net "PHY_DRV_B_TO_SCC_B_35_DN")
	)
	(segment
		(start 287.304734 -184.5056)
		(end 287.304734 -184.2008)
		(width 0.12065)
		(layer "In5.Cu")
		(net "PHY_DRV_B_TO_SCC_B_35_DN")
	)
	(segment
		(start 312.287412 -163.096194)
		(end 317.089028 -140.508228)
		(width 0.12065)
		(layer "In5.Cu")
		(net "PHY_DRV_B_TO_SCC_B_35_DN")
	)
	(segment
		(start 321.857116 -129.559812)
		(end 349.094552 -111.872268)
		(width 0.12065)
		(layer "In5.Cu")
		(net "PHY_DRV_B_TO_SCC_B_35_DN")
	)
	(segment
		(start 304.971704 -174.36211)
		(end 312.287412 -163.096194)
		(width 0.12065)
		(layer "In5.Cu")
		(net "PHY_DRV_B_TO_SCC_B_35_DN")
	)
	(segment
		(start 350.354646 -111.308388)
		(end 350.658176 -111.111284)
		(width 0.12065)
		(layer "In5.Cu")
		(net "PHY_DRV_B_TO_SCC_B_35_DN")
	)
	(segment
		(start 317.089028 -140.508228)
		(end 321.857116 -129.559812)
		(width 0.12065)
		(layer "In5.Cu")
		(net "PHY_DRV_B_TO_SCC_B_35_DN")
	)
	(segment
		(start 481.23475 -18.275808)
		(end 481.23475 -17.59585)
		(width 0.12065)
		(layer "In5.Cu")
		(net "PHY_DRV_B_TO_SCC_B_35_DN")
	)
	(segment
		(start 433.357782 -41.53154)
		(end 469.11768 -33.930082)
		(width 0.12065)
		(layer "In5.Cu")
		(net "PHY_DRV_B_TO_SCC_B_35_DN")
	)
	(segment
		(start 350.720914 -110.816136)
		(end 351.024444 -110.619032)
		(width 0.12065)
		(layer "In5.Cu")
		(net "PHY_DRV_B_TO_SCC_B_35_DN")
	)
	(segment
		(start 399.402808 -79.20228)
		(end 416.941 -52.192428)
		(width 0.12065)
		(layer "In5.Cu")
		(net "PHY_DRV_B_TO_SCC_B_35_DN")
	)
	(segment
		(start 349.69323 -111.737902)
		(end 349.755968 -111.442754)
		(width 0.12065)
		(layer "In5.Cu")
		(net "PHY_DRV_B_TO_SCC_B_35_DN")
	)
	(segment
		(start 480.522788 -21.51761)
		(end 480.55657 -21.46554)
		(width 0.12065)
		(layer "In5.Cu")
		(net "PHY_DRV_B_TO_SCC_B_35_DN")
	)
	(segment
		(start 351.319592 -110.68177)
		(end 351.623122 -110.484412)
		(width 0.12065)
		(layer "In5.Cu")
		(net "PHY_DRV_B_TO_SCC_B_35_DN")
	)
	(segment
		(start 480.55657 -21.46554)
		(end 481.23475 -18.275808)
		(width 0.12065)
		(layer "In5.Cu")
		(net "PHY_DRV_B_TO_SCC_B_35_DN")
	)
	(segment
		(start 349.755968 -111.442754)
		(end 350.059498 -111.24565)
		(width 0.12065)
		(layer "In5.Cu")
		(net "PHY_DRV_B_TO_SCC_B_35_DN")
	)
	(segment
		(start 481.3935 -17.4371)
		(end 481.701602 -17.4371)
		(width 0.12065)
		(layer "In5.Cu")
		(net "PHY_DRV_B_TO_SCC_B_35_DN")
	)
	(segment
		(start 351.68586 -110.189264)
		(end 399.402808 -79.20228)
		(width 0.12065)
		(layer "In5.Cu")
		(net "PHY_DRV_B_TO_SCC_B_35_DN")
	)
	(segment
		(start 349.094552 -111.872268)
		(end 349.3897 -111.935006)
		(width 0.12065)
		(layer "In5.Cu")
		(net "PHY_DRV_B_TO_SCC_B_35_DN")
	)
	(segment
		(start 349.3897 -111.935006)
		(end 349.69323 -111.737902)
		(width 0.12065)
		(layer "In5.Cu")
		(net "PHY_DRV_B_TO_SCC_B_35_DN")
	)
	(segment
		(start 350.059498 -111.24565)
		(end 350.354646 -111.308388)
		(width 0.12065)
		(layer "In5.Cu")
		(net "PHY_DRV_B_TO_SCC_B_35_DN")
	)
	(segment
		(start 351.024444 -110.619032)
		(end 351.319592 -110.68177)
		(width 0.12065)
		(layer "In5.Cu")
		(net "PHY_DRV_B_TO_SCC_B_35_DN")
	)
	(segment
		(start 474.899736 -30.1752)
		(end 480.522788 -21.51761)
		(width 0.12065)
		(layer "In5.Cu")
		(net "PHY_DRV_B_TO_SCC_B_35_DN")
	)
	(segment
		(start 287.83661 -184.694576)
		(end 287.49371 -184.694576)
		(width 0.12065)
		(layer "In5.Cu")
		(net "PHY_DRV_B_TO_SCC_B_35_DN")
	)
	(arc
		(start 287.49371 -184.694576)
		(mid 287.360084 -184.639226)
		(end 287.304734 -184.5056)
		(width 0.12065)
		(layer "In5.Cu")
		(net "PHY_DRV_B_TO_SCC_B_35_DN")
	)
	(arc
		(start 287.304734 -184.2008)
		(mid 287.374442 -184.03251)
		(end 287.542732 -183.962802)
		(width 0.12065)
		(layer "In5.Cu")
		(net "PHY_DRV_B_TO_SCC_B_35_DN")
	)
	(arc
		(start 481.23475 -17.59585)
		(mid 481.281247 -17.483597)
		(end 481.3935 -17.4371)
		(width 0.12065)
		(layer "In5.Cu")
		(net "PHY_DRV_B_TO_SCC_B_35_DN")
	)
	(segment
		(start 452.240396 -19.385026)
		(end 452.113396 -19.258026)
		(width 0.127)
		(layer "F.Cu")
		(net "PHY_DRV_B_TO_SCC_B_34_DP")
	)
	(segment
		(start 451.991476 -18.870676)
		(end 449.800218 -18.870676)
		(width 0.127)
		(layer "F.Cu")
		(net "PHY_DRV_B_TO_SCC_B_34_DP")
	)
	(segment
		(start 449.208398 -17.4371)
		(end 448.8815 -17.4371)
		(width 0.127)
		(layer "F.Cu")
		(net "PHY_DRV_B_TO_SCC_B_34_DP")
	)
	(segment
		(start 449.800218 -18.870676)
		(end 449.37045 -18.440908)
		(width 0.127)
		(layer "F.Cu")
		(net "PHY_DRV_B_TO_SCC_B_34_DP")
	)
	(segment
		(start 452.113396 -19.258026)
		(end 452.113396 -18.992596)
		(width 0.127)
		(layer "F.Cu")
		(net "PHY_DRV_B_TO_SCC_B_34_DP")
	)
	(segment
		(start 452.113396 -18.992596)
		(end 451.991476 -18.870676)
		(width 0.127)
		(layer "F.Cu")
		(net "PHY_DRV_B_TO_SCC_B_34_DP")
	)
	(segment
		(start 453.574912 -19.385026)
		(end 452.240396 -19.385026)
		(width 0.127)
		(layer "F.Cu")
		(net "PHY_DRV_B_TO_SCC_B_34_DP")
	)
	(segment
		(start 449.37045 -18.440908)
		(end 449.37045 -17.599152)
		(width 0.127)
		(layer "F.Cu")
		(net "PHY_DRV_B_TO_SCC_B_34_DP")
	)
	(arc
		(start 449.37045 -17.599152)
		(mid 449.322986 -17.484564)
		(end 449.208398 -17.4371)
		(width 0.127)
		(layer "F.Cu")
		(net "PHY_DRV_B_TO_SCC_B_34_DP")
	)
	(segment
		(start 448.67957 -19.393408)
		(end 449.348098 -18.356072)
		(width 0.12065)
		(layer "In5.Cu")
		(net "PHY_DRV_B_TO_SCC_B_34_DP")
	)
	(segment
		(start 309.17007 -164.493956)
		(end 316.642242 -129.333752)
		(width 0.12065)
		(layer "In5.Cu")
		(net "PHY_DRV_B_TO_SCC_B_34_DP")
	)
	(segment
		(start 289.998912 -181.826154)
		(end 303.686464 -172.938186)
		(width 0.12065)
		(layer "In5.Cu")
		(net "PHY_DRV_B_TO_SCC_B_34_DP")
	)
	(segment
		(start 449.348098 -18.356072)
		(end 449.348098 -17.5768)
		(width 0.12065)
		(layer "In5.Cu")
		(net "PHY_DRV_B_TO_SCC_B_34_DP")
	)
	(segment
		(start 285.968186 -182.705502)
		(end 285.968186 -182.400702)
		(width 0.12065)
		(layer "In5.Cu")
		(net "PHY_DRV_B_TO_SCC_B_34_DP")
	)
	(segment
		(start 425.701714 -34.315146)
		(end 435.432454 -27.996134)
		(width 0.12065)
		(layer "In5.Cu")
		(net "PHY_DRV_B_TO_SCC_B_34_DP")
	)
	(segment
		(start 316.642242 -129.333752)
		(end 316.658244 -129.258314)
		(width 0.12065)
		(layer "In5.Cu")
		(net "PHY_DRV_B_TO_SCC_B_34_DP")
	)
	(segment
		(start 306.427886 -168.716198)
		(end 307.112924 -167.661082)
		(width 0.12065)
		(layer "In5.Cu")
		(net "PHY_DRV_B_TO_SCC_B_34_DP")
	)
	(segment
		(start 317.362332 -128.353058)
		(end 317.616078 -128.026922)
		(width 0.12065)
		(layer "In5.Cu")
		(net "PHY_DRV_B_TO_SCC_B_34_DP")
	)
	(segment
		(start 286.542734 -181.826154)
		(end 289.998912 -181.826154)
		(width 0.12065)
		(layer "In5.Cu")
		(net "PHY_DRV_B_TO_SCC_B_34_DP")
	)
	(segment
		(start 307.112924 -167.661082)
		(end 307.113178 -167.661336)
		(width 0.12065)
		(layer "In5.Cu")
		(net "PHY_DRV_B_TO_SCC_B_34_DP")
	)
	(segment
		(start 307.113178 -167.661336)
		(end 309.17007 -164.493956)
		(width 0.12065)
		(layer "In5.Cu")
		(net "PHY_DRV_B_TO_SCC_B_34_DP")
	)
	(segment
		(start 399.47723 -74.865738)
		(end 425.701714 -34.315146)
		(width 0.12065)
		(layer "In5.Cu")
		(net "PHY_DRV_B_TO_SCC_B_34_DP")
	)
	(segment
		(start 285.436564 -182.894478)
		(end 285.77921 -182.894478)
		(width 0.12065)
		(layer "In5.Cu")
		(net "PHY_DRV_B_TO_SCC_B_34_DP")
	)
	(segment
		(start 317.616078 -128.026922)
		(end 399.47723 -74.865738)
		(width 0.12065)
		(layer "In5.Cu")
		(net "PHY_DRV_B_TO_SCC_B_34_DP")
	)
	(segment
		(start 303.686464 -172.938186)
		(end 306.427886 -168.716198)
		(width 0.12065)
		(layer "In5.Cu")
		(net "PHY_DRV_B_TO_SCC_B_34_DP")
	)
	(segment
		(start 435.432454 -27.996134)
		(end 435.4322 -27.996134)
		(width 0.12065)
		(layer "In5.Cu")
		(net "PHY_DRV_B_TO_SCC_B_34_DP")
	)
	(segment
		(start 316.658244 -129.258314)
		(end 317.362332 -128.353058)
		(width 0.12065)
		(layer "In5.Cu")
		(net "PHY_DRV_B_TO_SCC_B_34_DP")
	)
	(segment
		(start 449.208398 -17.4371)
		(end 448.8815 -17.4371)
		(width 0.12065)
		(layer "In5.Cu")
		(net "PHY_DRV_B_TO_SCC_B_34_DP")
	)
	(segment
		(start 435.4322 -27.996134)
		(end 448.67957 -19.393408)
		(width 0.12065)
		(layer "In5.Cu")
		(net "PHY_DRV_B_TO_SCC_B_34_DP")
	)
	(arc
		(start 449.348098 -17.5768)
		(mid 449.307181 -17.478017)
		(end 449.208398 -17.4371)
		(width 0.12065)
		(layer "In5.Cu")
		(net "PHY_DRV_B_TO_SCC_B_34_DP")
	)
	(arc
		(start 285.77921 -182.894478)
		(mid 285.912836 -182.839128)
		(end 285.968186 -182.705502)
		(width 0.12065)
		(layer "In5.Cu")
		(net "PHY_DRV_B_TO_SCC_B_34_DP")
	)
	(arc
		(start 285.968186 -182.400702)
		(mid 286.136467 -181.994435)
		(end 286.542734 -181.826154)
		(width 0.12065)
		(layer "In5.Cu")
		(net "PHY_DRV_B_TO_SCC_B_34_DP")
	)
	(segment
		(start 449.921376 -18.578576)
		(end 449.66255 -18.31975)
		(width 0.127)
		(layer "F.Cu")
		(net "PHY_DRV_B_TO_SCC_B_34_DN")
	)
	(segment
		(start 452.113396 -18.242026)
		(end 452.113396 -18.476976)
		(width 0.127)
		(layer "F.Cu")
		(net "PHY_DRV_B_TO_SCC_B_34_DN")
	)
	(segment
		(start 449.66255 -18.31975)
		(end 449.66255 -17.599152)
		(width 0.127)
		(layer "F.Cu")
		(net "PHY_DRV_B_TO_SCC_B_34_DN")
	)
	(segment
		(start 452.113396 -18.476976)
		(end 452.011796 -18.578576)
		(width 0.127)
		(layer "F.Cu")
		(net "PHY_DRV_B_TO_SCC_B_34_DN")
	)
	(segment
		(start 452.011796 -18.578576)
		(end 449.921376 -18.578576)
		(width 0.127)
		(layer "F.Cu")
		(net "PHY_DRV_B_TO_SCC_B_34_DN")
	)
	(segment
		(start 453.574912 -18.115026)
		(end 452.240396 -18.115026)
		(width 0.127)
		(layer "F.Cu")
		(net "PHY_DRV_B_TO_SCC_B_34_DN")
	)
	(segment
		(start 452.240396 -18.115026)
		(end 452.113396 -18.242026)
		(width 0.127)
		(layer "F.Cu")
		(net "PHY_DRV_B_TO_SCC_B_34_DN")
	)
	(segment
		(start 449.824602 -17.4371)
		(end 450.1515 -17.4371)
		(width 0.127)
		(layer "F.Cu")
		(net "PHY_DRV_B_TO_SCC_B_34_DN")
	)
	(arc
		(start 449.66255 -17.599152)
		(mid 449.710014 -17.484564)
		(end 449.824602 -17.4371)
		(width 0.127)
		(layer "F.Cu")
		(net "PHY_DRV_B_TO_SCC_B_34_DN")
	)
	(segment
		(start 435.556152 -28.559506)
		(end 435.615842 -28.278582)
		(width 0.12065)
		(layer "In5.Cu")
		(net "PHY_DRV_B_TO_SCC_B_34_DN")
	)
	(segment
		(start 290.098734 -182.162704)
		(end 303.929796 -173.181518)
		(width 0.12065)
		(layer "In5.Cu")
		(net "PHY_DRV_B_TO_SCC_B_34_DN")
	)
	(segment
		(start 434.608224 -29.175202)
		(end 434.667914 -28.894024)
		(width 0.12065)
		(layer "In5.Cu")
		(net "PHY_DRV_B_TO_SCC_B_34_DN")
	)
	(segment
		(start 286.304736 -182.705502)
		(end 286.304736 -182.400702)
		(width 0.12065)
		(layer "In5.Cu")
		(net "PHY_DRV_B_TO_SCC_B_34_DN")
	)
	(segment
		(start 434.023516 -29.312616)
		(end 434.304694 -29.372306)
		(width 0.12065)
		(layer "In5.Cu")
		(net "PHY_DRV_B_TO_SCC_B_34_DN")
	)
	(segment
		(start 316.971426 -129.403856)
		(end 317.409322 -128.841246)
		(width 0.12065)
		(layer "In5.Cu")
		(net "PHY_DRV_B_TO_SCC_B_34_DN")
	)
	(segment
		(start 433.660296 -29.790898)
		(end 433.719986 -29.50972)
		(width 0.12065)
		(layer "In5.Cu")
		(net "PHY_DRV_B_TO_SCC_B_34_DN")
	)
	(segment
		(start 433.719986 -29.50972)
		(end 434.023516 -29.312616)
		(width 0.12065)
		(layer "In5.Cu")
		(net "PHY_DRV_B_TO_SCC_B_34_DN")
	)
	(segment
		(start 435.252622 -28.756864)
		(end 435.556152 -28.559506)
		(width 0.12065)
		(layer "In5.Cu")
		(net "PHY_DRV_B_TO_SCC_B_34_DN")
	)
	(segment
		(start 434.304694 -29.372306)
		(end 434.608224 -29.175202)
		(width 0.12065)
		(layer "In5.Cu")
		(net "PHY_DRV_B_TO_SCC_B_34_DN")
	)
	(segment
		(start 433.356766 -29.988002)
		(end 433.660296 -29.790898)
		(width 0.12065)
		(layer "In5.Cu")
		(net "PHY_DRV_B_TO_SCC_B_34_DN")
	)
	(segment
		(start 303.929796 -173.181518)
		(end 309.4863 -164.62502)
		(width 0.12065)
		(layer "In5.Cu")
		(net "PHY_DRV_B_TO_SCC_B_34_DN")
	)
	(segment
		(start 434.971444 -28.69692)
		(end 435.252622 -28.756864)
		(width 0.12065)
		(layer "In5.Cu")
		(net "PHY_DRV_B_TO_SCC_B_34_DN")
	)
	(segment
		(start 286.836612 -182.894478)
		(end 286.493712 -182.894478)
		(width 0.12065)
		(layer "In5.Cu")
		(net "PHY_DRV_B_TO_SCC_B_34_DN")
	)
	(segment
		(start 433.075588 -29.928312)
		(end 433.356766 -29.988002)
		(width 0.12065)
		(layer "In5.Cu")
		(net "PHY_DRV_B_TO_SCC_B_34_DN")
	)
	(segment
		(start 435.615842 -28.278582)
		(end 448.92341 -19.636486)
		(width 0.12065)
		(layer "In5.Cu")
		(net "PHY_DRV_B_TO_SCC_B_34_DN")
	)
	(segment
		(start 448.92341 -19.636486)
		(end 449.684648 -18.455132)
		(width 0.12065)
		(layer "In5.Cu")
		(net "PHY_DRV_B_TO_SCC_B_34_DN")
	)
	(segment
		(start 449.824602 -17.4371)
		(end 450.1515 -17.4371)
		(width 0.12065)
		(layer "In5.Cu")
		(net "PHY_DRV_B_TO_SCC_B_34_DN")
	)
	(segment
		(start 425.945554 -34.558478)
		(end 433.075588 -29.928312)
		(width 0.12065)
		(layer "In5.Cu")
		(net "PHY_DRV_B_TO_SCC_B_34_DN")
	)
	(segment
		(start 317.846964 -128.278382)
		(end 399.72107 -75.10907)
		(width 0.12065)
		(layer "In5.Cu")
		(net "PHY_DRV_B_TO_SCC_B_34_DN")
	)
	(segment
		(start 317.409322 -128.841246)
		(end 317.846964 -128.278382)
		(width 0.12065)
		(layer "In5.Cu")
		(net "PHY_DRV_B_TO_SCC_B_34_DN")
	)
	(segment
		(start 434.667914 -28.894024)
		(end 434.971444 -28.69692)
		(width 0.12065)
		(layer "In5.Cu")
		(net "PHY_DRV_B_TO_SCC_B_34_DN")
	)
	(segment
		(start 309.4863 -164.62502)
		(end 316.971426 -129.403856)
		(width 0.12065)
		(layer "In5.Cu")
		(net "PHY_DRV_B_TO_SCC_B_34_DN")
	)
	(segment
		(start 449.684648 -18.455132)
		(end 449.684648 -17.577054)
		(width 0.12065)
		(layer "In5.Cu")
		(net "PHY_DRV_B_TO_SCC_B_34_DN")
	)
	(segment
		(start 286.542734 -182.162704)
		(end 290.098734 -182.162704)
		(width 0.12065)
		(layer "In5.Cu")
		(net "PHY_DRV_B_TO_SCC_B_34_DN")
	)
	(segment
		(start 399.72107 -75.10907)
		(end 425.945554 -34.558478)
		(width 0.12065)
		(layer "In5.Cu")
		(net "PHY_DRV_B_TO_SCC_B_34_DN")
	)
	(arc
		(start 286.304736 -182.400702)
		(mid 286.374444 -182.232412)
		(end 286.542734 -182.162704)
		(width 0.12065)
		(layer "In5.Cu")
		(net "PHY_DRV_B_TO_SCC_B_34_DN")
	)
	(arc
		(start 286.493712 -182.894478)
		(mid 286.360086 -182.839128)
		(end 286.304736 -182.705502)
		(width 0.12065)
		(layer "In5.Cu")
		(net "PHY_DRV_B_TO_SCC_B_34_DN")
	)
	(arc
		(start 449.684648 -17.577054)
		(mid 449.72564 -17.478092)
		(end 449.824602 -17.4371)
		(width 0.12065)
		(layer "In5.Cu")
		(net "PHY_DRV_B_TO_SCC_B_34_DN")
	)
	(segment
		(start 420.563548 -19.258026)
		(end 420.563548 -19.023076)
		(width 0.127)
		(layer "F.Cu")
		(net "PHY_DRV_B_TO_SCC_B_33_DP")
	)
	(segment
		(start 417.820602 -18.38706)
		(end 417.820602 -17.599152)
		(width 0.127)
		(layer "F.Cu")
		(net "PHY_DRV_B_TO_SCC_B_33_DP")
	)
	(segment
		(start 420.563548 -19.023076)
		(end 420.411148 -18.870676)
		(width 0.127)
		(layer "F.Cu")
		(net "PHY_DRV_B_TO_SCC_B_33_DP")
	)
	(segment
		(start 418.304218 -18.870676)
		(end 417.820602 -18.38706)
		(width 0.127)
		(layer "F.Cu")
		(net "PHY_DRV_B_TO_SCC_B_33_DP")
	)
	(segment
		(start 420.411148 -18.870676)
		(end 418.304218 -18.870676)
		(width 0.127)
		(layer "F.Cu")
		(net "PHY_DRV_B_TO_SCC_B_33_DP")
	)
	(segment
		(start 417.65855 -17.4371)
		(end 417.331652 -17.4371)
		(width 0.127)
		(layer "F.Cu")
		(net "PHY_DRV_B_TO_SCC_B_33_DP")
	)
	(segment
		(start 420.690548 -19.385026)
		(end 420.563548 -19.258026)
		(width 0.127)
		(layer "F.Cu")
		(net "PHY_DRV_B_TO_SCC_B_33_DP")
	)
	(segment
		(start 422.025064 -19.385026)
		(end 420.690548 -19.385026)
		(width 0.127)
		(layer "F.Cu")
		(net "PHY_DRV_B_TO_SCC_B_33_DP")
	)
	(arc
		(start 417.820602 -17.599152)
		(mid 417.773138 -17.484564)
		(end 417.65855 -17.4371)
		(width 0.127)
		(layer "F.Cu")
		(net "PHY_DRV_B_TO_SCC_B_33_DP")
	)
	(segment
		(start 417.65855 -17.4371)
		(end 417.331652 -17.4371)
		(width 0.12065)
		(layer "In5.Cu")
		(net "PHY_DRV_B_TO_SCC_B_33_DP")
	)
	(segment
		(start 417.79825 -18.325338)
		(end 417.79825 -17.5768)
		(width 0.12065)
		(layer "In5.Cu")
		(net "PHY_DRV_B_TO_SCC_B_33_DP")
	)
	(segment
		(start 314.320936 -128.909826)
		(end 361.353354 -59.181492)
		(width 0.12065)
		(layer "In5.Cu")
		(net "PHY_DRV_B_TO_SCC_B_33_DP")
	)
	(segment
		(start 286.968184 -180.905404)
		(end 286.968184 -180.600604)
		(width 0.12065)
		(layer "In5.Cu")
		(net "PHY_DRV_B_TO_SCC_B_33_DP")
	)
	(segment
		(start 286.436562 -181.09438)
		(end 286.779208 -181.09438)
		(width 0.12065)
		(layer "In5.Cu")
		(net "PHY_DRV_B_TO_SCC_B_33_DP")
	)
	(segment
		(start 306.639468 -165.048946)
		(end 314.320936 -128.909826)
		(width 0.12065)
		(layer "In5.Cu")
		(net "PHY_DRV_B_TO_SCC_B_33_DP")
	)
	(segment
		(start 414.375092 -23.908512)
		(end 417.699952 -18.787618)
		(width 0.12065)
		(layer "In5.Cu")
		(net "PHY_DRV_B_TO_SCC_B_33_DP")
	)
	(segment
		(start 290.095686 -180.026056)
		(end 301.88535 -172.370242)
		(width 0.12065)
		(layer "In5.Cu")
		(net "PHY_DRV_B_TO_SCC_B_33_DP")
	)
	(segment
		(start 301.885096 -172.370242)
		(end 306.639468 -165.048946)
		(width 0.12065)
		(layer "In5.Cu")
		(net "PHY_DRV_B_TO_SCC_B_33_DP")
	)
	(segment
		(start 361.353354 -59.181492)
		(end 414.375092 -23.908512)
		(width 0.12065)
		(layer "In5.Cu")
		(net "PHY_DRV_B_TO_SCC_B_33_DP")
	)
	(segment
		(start 287.542732 -180.026056)
		(end 290.095686 -180.026056)
		(width 0.12065)
		(layer "In5.Cu")
		(net "PHY_DRV_B_TO_SCC_B_33_DP")
	)
	(segment
		(start 301.88535 -172.370242)
		(end 301.885096 -172.370242)
		(width 0.12065)
		(layer "In5.Cu")
		(net "PHY_DRV_B_TO_SCC_B_33_DP")
	)
	(segment
		(start 417.699952 -18.787618)
		(end 417.79825 -18.325338)
		(width 0.12065)
		(layer "In5.Cu")
		(net "PHY_DRV_B_TO_SCC_B_33_DP")
	)
	(arc
		(start 417.79825 -17.5768)
		(mid 417.757333 -17.478017)
		(end 417.65855 -17.4371)
		(width 0.12065)
		(layer "In5.Cu")
		(net "PHY_DRV_B_TO_SCC_B_33_DP")
	)
	(arc
		(start 286.968184 -180.600604)
		(mid 287.136465 -180.194337)
		(end 287.542732 -180.026056)
		(width 0.12065)
		(layer "In5.Cu")
		(net "PHY_DRV_B_TO_SCC_B_33_DP")
	)
	(arc
		(start 286.779208 -181.09438)
		(mid 286.912834 -181.03903)
		(end 286.968184 -180.905404)
		(width 0.12065)
		(layer "In5.Cu")
		(net "PHY_DRV_B_TO_SCC_B_33_DP")
	)
	(segment
		(start 420.461948 -18.578576)
		(end 418.425376 -18.578576)
		(width 0.127)
		(layer "F.Cu")
		(net "PHY_DRV_B_TO_SCC_B_33_DN")
	)
	(segment
		(start 418.112702 -18.265902)
		(end 418.112702 -17.599152)
		(width 0.127)
		(layer "F.Cu")
		(net "PHY_DRV_B_TO_SCC_B_33_DN")
	)
	(segment
		(start 418.425376 -18.578576)
		(end 418.112702 -18.265902)
		(width 0.127)
		(layer "F.Cu")
		(net "PHY_DRV_B_TO_SCC_B_33_DN")
	)
	(segment
		(start 420.690548 -18.115026)
		(end 420.563548 -18.242026)
		(width 0.127)
		(layer "F.Cu")
		(net "PHY_DRV_B_TO_SCC_B_33_DN")
	)
	(segment
		(start 420.563548 -18.476976)
		(end 420.461948 -18.578576)
		(width 0.127)
		(layer "F.Cu")
		(net "PHY_DRV_B_TO_SCC_B_33_DN")
	)
	(segment
		(start 422.025064 -18.115026)
		(end 420.690548 -18.115026)
		(width 0.127)
		(layer "F.Cu")
		(net "PHY_DRV_B_TO_SCC_B_33_DN")
	)
	(segment
		(start 418.274754 -17.4371)
		(end 418.601652 -17.4371)
		(width 0.127)
		(layer "F.Cu")
		(net "PHY_DRV_B_TO_SCC_B_33_DN")
	)
	(segment
		(start 420.563548 -18.242026)
		(end 420.563548 -18.476976)
		(width 0.127)
		(layer "F.Cu")
		(net "PHY_DRV_B_TO_SCC_B_33_DN")
	)
	(arc
		(start 418.112702 -17.599152)
		(mid 418.160166 -17.484564)
		(end 418.274754 -17.4371)
		(width 0.127)
		(layer "F.Cu")
		(net "PHY_DRV_B_TO_SCC_B_33_DN")
	)
	(segment
		(start 306.955698 -165.18001)
		(end 314.636658 -129.043938)
		(width 0.12065)
		(layer "In5.Cu")
		(net "PHY_DRV_B_TO_SCC_B_33_DN")
	)
	(segment
		(start 377.560332 -49.048416)
		(end 377.616974 -48.76673)
		(width 0.12065)
		(layer "In5.Cu")
		(net "PHY_DRV_B_TO_SCC_B_33_DN")
	)
	(segment
		(start 377.616974 -48.76673)
		(end 377.918472 -48.56607)
		(width 0.12065)
		(layer "In5.Cu")
		(net "PHY_DRV_B_TO_SCC_B_33_DN")
	)
	(segment
		(start 414.619694 -24.15032)
		(end 418.016182 -18.918682)
		(width 0.12065)
		(layer "In5.Cu")
		(net "PHY_DRV_B_TO_SCC_B_33_DN")
	)
	(segment
		(start 290.195508 -180.362606)
		(end 302.128682 -172.613574)
		(width 0.12065)
		(layer "In5.Cu")
		(net "PHY_DRV_B_TO_SCC_B_33_DN")
	)
	(segment
		(start 376.977402 -49.19218)
		(end 377.259088 -49.248822)
		(width 0.12065)
		(layer "In5.Cu")
		(net "PHY_DRV_B_TO_SCC_B_33_DN")
	)
	(segment
		(start 378.200158 -48.622712)
		(end 378.501402 -48.422306)
		(width 0.12065)
		(layer "In5.Cu")
		(net "PHY_DRV_B_TO_SCC_B_33_DN")
	)
	(segment
		(start 287.83661 -181.09438)
		(end 287.49371 -181.09438)
		(width 0.12065)
		(layer "In5.Cu")
		(net "PHY_DRV_B_TO_SCC_B_33_DN")
	)
	(segment
		(start 314.636658 -129.043938)
		(end 361.595416 -59.425078)
		(width 0.12065)
		(layer "In5.Cu")
		(net "PHY_DRV_B_TO_SCC_B_33_DN")
	)
	(segment
		(start 302.128682 -172.613574)
		(end 306.955698 -165.18001)
		(width 0.12065)
		(layer "In5.Cu")
		(net "PHY_DRV_B_TO_SCC_B_33_DN")
	)
	(segment
		(start 379.499114 -47.51451)
		(end 414.619694 -24.15032)
		(width 0.12065)
		(layer "In5.Cu")
		(net "PHY_DRV_B_TO_SCC_B_33_DN")
	)
	(segment
		(start 378.501402 -48.422306)
		(end 378.558044 -48.14062)
		(width 0.12065)
		(layer "In5.Cu")
		(net "PHY_DRV_B_TO_SCC_B_33_DN")
	)
	(segment
		(start 287.304734 -180.905404)
		(end 287.304734 -180.600604)
		(width 0.12065)
		(layer "In5.Cu")
		(net "PHY_DRV_B_TO_SCC_B_33_DN")
	)
	(segment
		(start 377.918472 -48.56607)
		(end 378.200158 -48.622712)
		(width 0.12065)
		(layer "In5.Cu")
		(net "PHY_DRV_B_TO_SCC_B_33_DN")
	)
	(segment
		(start 379.442472 -47.796196)
		(end 379.499114 -47.51451)
		(width 0.12065)
		(layer "In5.Cu")
		(net "PHY_DRV_B_TO_SCC_B_33_DN")
	)
	(segment
		(start 287.542732 -180.362606)
		(end 290.195508 -180.362606)
		(width 0.12065)
		(layer "In5.Cu")
		(net "PHY_DRV_B_TO_SCC_B_33_DN")
	)
	(segment
		(start 378.558044 -48.14062)
		(end 378.859542 -47.93996)
		(width 0.12065)
		(layer "In5.Cu")
		(net "PHY_DRV_B_TO_SCC_B_33_DN")
	)
	(segment
		(start 377.259088 -49.248822)
		(end 377.560332 -49.048416)
		(width 0.12065)
		(layer "In5.Cu")
		(net "PHY_DRV_B_TO_SCC_B_33_DN")
	)
	(segment
		(start 379.141228 -47.996602)
		(end 379.442472 -47.796196)
		(width 0.12065)
		(layer "In5.Cu")
		(net "PHY_DRV_B_TO_SCC_B_33_DN")
	)
	(segment
		(start 418.016182 -18.918682)
		(end 418.1348 -18.360898)
		(width 0.12065)
		(layer "In5.Cu")
		(net "PHY_DRV_B_TO_SCC_B_33_DN")
	)
	(segment
		(start 418.1348 -18.360898)
		(end 418.1348 -17.577054)
		(width 0.12065)
		(layer "In5.Cu")
		(net "PHY_DRV_B_TO_SCC_B_33_DN")
	)
	(segment
		(start 378.859542 -47.93996)
		(end 379.141228 -47.996602)
		(width 0.12065)
		(layer "In5.Cu")
		(net "PHY_DRV_B_TO_SCC_B_33_DN")
	)
	(segment
		(start 418.274754 -17.4371)
		(end 418.601652 -17.4371)
		(width 0.12065)
		(layer "In5.Cu")
		(net "PHY_DRV_B_TO_SCC_B_33_DN")
	)
	(segment
		(start 361.595416 -59.425078)
		(end 376.977402 -49.19218)
		(width 0.12065)
		(layer "In5.Cu")
		(net "PHY_DRV_B_TO_SCC_B_33_DN")
	)
	(arc
		(start 418.1348 -17.577054)
		(mid 418.175792 -17.478092)
		(end 418.274754 -17.4371)
		(width 0.12065)
		(layer "In5.Cu")
		(net "PHY_DRV_B_TO_SCC_B_33_DN")
	)
	(arc
		(start 287.49371 -181.09438)
		(mid 287.360084 -181.03903)
		(end 287.304734 -180.905404)
		(width 0.12065)
		(layer "In5.Cu")
		(net "PHY_DRV_B_TO_SCC_B_33_DN")
	)
	(arc
		(start 287.304734 -180.600604)
		(mid 287.374442 -180.432314)
		(end 287.542732 -180.362606)
		(width 0.12065)
		(layer "In5.Cu")
		(net "PHY_DRV_B_TO_SCC_B_33_DN")
	)
	(segment
		(start 386.2705 -18.440908)
		(end 386.2705 -17.599152)
		(width 0.127)
		(layer "F.Cu")
		(net "PHY_DRV_B_TO_SCC_B_32_DP")
	)
	(segment
		(start 389.013446 -19.291046)
		(end 389.013446 -19.011646)
		(width 0.127)
		(layer "F.Cu")
		(net "PHY_DRV_B_TO_SCC_B_32_DP")
	)
	(segment
		(start 386.108448 -17.4371)
		(end 385.78155 -17.4371)
		(width 0.127)
		(layer "F.Cu")
		(net "PHY_DRV_B_TO_SCC_B_32_DP")
	)
	(segment
		(start 389.013446 -19.011646)
		(end 388.897876 -18.896076)
		(width 0.127)
		(layer "F.Cu")
		(net "PHY_DRV_B_TO_SCC_B_32_DP")
	)
	(segment
		(start 386.725668 -18.896076)
		(end 386.2705 -18.440908)
		(width 0.127)
		(layer "F.Cu")
		(net "PHY_DRV_B_TO_SCC_B_32_DP")
	)
	(segment
		(start 388.897876 -18.896076)
		(end 386.725668 -18.896076)
		(width 0.127)
		(layer "F.Cu")
		(net "PHY_DRV_B_TO_SCC_B_32_DP")
	)
	(segment
		(start 390.474962 -19.385026)
		(end 389.107426 -19.385026)
		(width 0.127)
		(layer "F.Cu")
		(net "PHY_DRV_B_TO_SCC_B_32_DP")
	)
	(segment
		(start 389.107426 -19.385026)
		(end 389.013446 -19.291046)
		(width 0.127)
		(layer "F.Cu")
		(net "PHY_DRV_B_TO_SCC_B_32_DP")
	)
	(arc
		(start 386.2705 -17.599152)
		(mid 386.223036 -17.484564)
		(end 386.108448 -17.4371)
		(width 0.127)
		(layer "F.Cu")
		(net "PHY_DRV_B_TO_SCC_B_32_DP")
	)
	(segment
		(start 386.108448 -17.4371)
		(end 385.78155 -17.4371)
		(width 0.12065)
		(layer "In5.Cu")
		(net "PHY_DRV_B_TO_SCC_B_32_DP")
	)
	(segment
		(start 386.248148 -18.53946)
		(end 386.248148 -17.5768)
		(width 0.12065)
		(layer "In5.Cu")
		(net "PHY_DRV_B_TO_SCC_B_32_DP")
	)
	(segment
		(start 289.905186 -178.226212)
		(end 300.79061 -171.1579)
		(width 0.12065)
		(layer "In5.Cu")
		(net "PHY_DRV_B_TO_SCC_B_32_DP")
	)
	(segment
		(start 304.860706 -164.889942)
		(end 312.636916 -128.300734)
		(width 0.12065)
		(layer "In5.Cu")
		(net "PHY_DRV_B_TO_SCC_B_32_DP")
	)
	(segment
		(start 300.79061 -171.1579)
		(end 304.860706 -164.889942)
		(width 0.12065)
		(layer "In5.Cu")
		(net "PHY_DRV_B_TO_SCC_B_32_DP")
	)
	(segment
		(start 286.542734 -178.226212)
		(end 289.905186 -178.226212)
		(width 0.12065)
		(layer "In5.Cu")
		(net "PHY_DRV_B_TO_SCC_B_32_DP")
	)
	(segment
		(start 285.436564 -179.294536)
		(end 285.77921 -179.294536)
		(width 0.12065)
		(layer "In5.Cu")
		(net "PHY_DRV_B_TO_SCC_B_32_DP")
	)
	(segment
		(start 312.636916 -128.300734)
		(end 386.07619 -19.423634)
		(width 0.12065)
		(layer "In5.Cu")
		(net "PHY_DRV_B_TO_SCC_B_32_DP")
	)
	(segment
		(start 386.07619 -19.423634)
		(end 386.248148 -18.53946)
		(width 0.12065)
		(layer "In5.Cu")
		(net "PHY_DRV_B_TO_SCC_B_32_DP")
	)
	(segment
		(start 285.968186 -179.10556)
		(end 285.968186 -178.80076)
		(width 0.12065)
		(layer "In5.Cu")
		(net "PHY_DRV_B_TO_SCC_B_32_DP")
	)
	(arc
		(start 285.968186 -178.80076)
		(mid 286.136467 -178.394493)
		(end 286.542734 -178.226212)
		(width 0.12065)
		(layer "In5.Cu")
		(net "PHY_DRV_B_TO_SCC_B_32_DP")
	)
	(arc
		(start 285.77921 -179.294536)
		(mid 285.912836 -179.239186)
		(end 285.968186 -179.10556)
		(width 0.12065)
		(layer "In5.Cu")
		(net "PHY_DRV_B_TO_SCC_B_32_DP")
	)
	(arc
		(start 386.248148 -17.5768)
		(mid 386.207231 -17.478017)
		(end 386.108448 -17.4371)
		(width 0.12065)
		(layer "In5.Cu")
		(net "PHY_DRV_B_TO_SCC_B_32_DP")
	)
	(segment
		(start 388.886446 -18.603976)
		(end 386.846826 -18.603976)
		(width 0.127)
		(layer "F.Cu")
		(net "PHY_DRV_B_TO_SCC_B_32_DN")
	)
	(segment
		(start 389.013446 -18.476976)
		(end 388.886446 -18.603976)
		(width 0.127)
		(layer "F.Cu")
		(net "PHY_DRV_B_TO_SCC_B_32_DN")
	)
	(segment
		(start 386.5626 -18.31975)
		(end 386.5626 -17.599152)
		(width 0.127)
		(layer "F.Cu")
		(net "PHY_DRV_B_TO_SCC_B_32_DN")
	)
	(segment
		(start 389.140446 -18.115026)
		(end 389.013446 -18.242026)
		(width 0.127)
		(layer "F.Cu")
		(net "PHY_DRV_B_TO_SCC_B_32_DN")
	)
	(segment
		(start 386.846826 -18.603976)
		(end 386.5626 -18.31975)
		(width 0.127)
		(layer "F.Cu")
		(net "PHY_DRV_B_TO_SCC_B_32_DN")
	)
	(segment
		(start 389.013446 -18.242026)
		(end 389.013446 -18.476976)
		(width 0.127)
		(layer "F.Cu")
		(net "PHY_DRV_B_TO_SCC_B_32_DN")
	)
	(segment
		(start 390.474962 -18.115026)
		(end 389.140446 -18.115026)
		(width 0.127)
		(layer "F.Cu")
		(net "PHY_DRV_B_TO_SCC_B_32_DN")
	)
	(segment
		(start 386.724652 -17.4371)
		(end 387.05155 -17.4371)
		(width 0.127)
		(layer "F.Cu")
		(net "PHY_DRV_B_TO_SCC_B_32_DN")
	)
	(arc
		(start 386.5626 -17.599152)
		(mid 386.610064 -17.484564)
		(end 386.724652 -17.4371)
		(width 0.127)
		(layer "F.Cu")
		(net "PHY_DRV_B_TO_SCC_B_32_DN")
	)
	(segment
		(start 286.304736 -179.10556)
		(end 286.304736 -178.80076)
		(width 0.12065)
		(layer "In5.Cu")
		(net "PHY_DRV_B_TO_SCC_B_32_DN")
	)
	(segment
		(start 377.83262 -32.610806)
		(end 377.777756 -32.328612)
		(width 0.12065)
		(layer "In5.Cu")
		(net "PHY_DRV_B_TO_SCC_B_32_DN")
	)
	(segment
		(start 386.39369 -19.554952)
		(end 386.584698 -18.571972)
		(width 0.12065)
		(layer "In5.Cu")
		(net "PHY_DRV_B_TO_SCC_B_32_DN")
	)
	(segment
		(start 290.005008 -178.562762)
		(end 301.033942 -171.401232)
		(width 0.12065)
		(layer "In5.Cu")
		(net "PHY_DRV_B_TO_SCC_B_32_DN")
	)
	(segment
		(start 378.89434 -31.036768)
		(end 379.096778 -30.73654)
		(width 0.12065)
		(layer "In5.Cu")
		(net "PHY_DRV_B_TO_SCC_B_32_DN")
	)
	(segment
		(start 378.262134 -31.973774)
		(end 378.464572 -31.673546)
		(width 0.12065)
		(layer "In5.Cu")
		(net "PHY_DRV_B_TO_SCC_B_32_DN")
	)
	(segment
		(start 301.033942 -171.401232)
		(end 305.176936 -165.021006)
		(width 0.12065)
		(layer "In5.Cu")
		(net "PHY_DRV_B_TO_SCC_B_32_DN")
	)
	(segment
		(start 377.347988 -32.965644)
		(end 377.630182 -32.91078)
		(width 0.12065)
		(layer "In5.Cu")
		(net "PHY_DRV_B_TO_SCC_B_32_DN")
	)
	(segment
		(start 378.612146 -31.091378)
		(end 378.89434 -31.036768)
		(width 0.12065)
		(layer "In5.Cu")
		(net "PHY_DRV_B_TO_SCC_B_32_DN")
	)
	(segment
		(start 378.464572 -31.673546)
		(end 378.409708 -31.391606)
		(width 0.12065)
		(layer "In5.Cu")
		(net "PHY_DRV_B_TO_SCC_B_32_DN")
	)
	(segment
		(start 379.041914 -30.4546)
		(end 386.39369 -19.554952)
		(width 0.12065)
		(layer "In5.Cu")
		(net "PHY_DRV_B_TO_SCC_B_32_DN")
	)
	(segment
		(start 378.409708 -31.391606)
		(end 378.612146 -31.091378)
		(width 0.12065)
		(layer "In5.Cu")
		(net "PHY_DRV_B_TO_SCC_B_32_DN")
	)
	(segment
		(start 377.980194 -32.028638)
		(end 378.262134 -31.973774)
		(width 0.12065)
		(layer "In5.Cu")
		(net "PHY_DRV_B_TO_SCC_B_32_DN")
	)
	(segment
		(start 386.724652 -17.4371)
		(end 387.05155 -17.4371)
		(width 0.12065)
		(layer "In5.Cu")
		(net "PHY_DRV_B_TO_SCC_B_32_DN")
	)
	(segment
		(start 312.952638 -128.434592)
		(end 377.347988 -32.965644)
		(width 0.12065)
		(layer "In5.Cu")
		(net "PHY_DRV_B_TO_SCC_B_32_DN")
	)
	(segment
		(start 379.096778 -30.73654)
		(end 379.041914 -30.4546)
		(width 0.12065)
		(layer "In5.Cu")
		(net "PHY_DRV_B_TO_SCC_B_32_DN")
	)
	(segment
		(start 377.777756 -32.328612)
		(end 377.980194 -32.028638)
		(width 0.12065)
		(layer "In5.Cu")
		(net "PHY_DRV_B_TO_SCC_B_32_DN")
	)
	(segment
		(start 286.836612 -179.294536)
		(end 286.493712 -179.294536)
		(width 0.12065)
		(layer "In5.Cu")
		(net "PHY_DRV_B_TO_SCC_B_32_DN")
	)
	(segment
		(start 286.542734 -178.562762)
		(end 290.005008 -178.562762)
		(width 0.12065)
		(layer "In5.Cu")
		(net "PHY_DRV_B_TO_SCC_B_32_DN")
	)
	(segment
		(start 305.176936 -165.021006)
		(end 312.952638 -128.434592)
		(width 0.12065)
		(layer "In5.Cu")
		(net "PHY_DRV_B_TO_SCC_B_32_DN")
	)
	(segment
		(start 386.584698 -18.571972)
		(end 386.584698 -17.577054)
		(width 0.12065)
		(layer "In5.Cu")
		(net "PHY_DRV_B_TO_SCC_B_32_DN")
	)
	(segment
		(start 377.630182 -32.91078)
		(end 377.83262 -32.610806)
		(width 0.12065)
		(layer "In5.Cu")
		(net "PHY_DRV_B_TO_SCC_B_32_DN")
	)
	(arc
		(start 386.584698 -17.577054)
		(mid 386.62569 -17.478092)
		(end 386.724652 -17.4371)
		(width 0.12065)
		(layer "In5.Cu")
		(net "PHY_DRV_B_TO_SCC_B_32_DN")
	)
	(arc
		(start 286.493712 -179.294536)
		(mid 286.360086 -179.239186)
		(end 286.304736 -179.10556)
		(width 0.12065)
		(layer "In5.Cu")
		(net "PHY_DRV_B_TO_SCC_B_32_DN")
	)
	(arc
		(start 286.304736 -178.80076)
		(mid 286.374444 -178.63247)
		(end 286.542734 -178.562762)
		(width 0.12065)
		(layer "In5.Cu")
		(net "PHY_DRV_B_TO_SCC_B_32_DN")
	)
	(segment
		(start 354.5459 -17.4371)
		(end 354.231702 -17.4371)
		(width 0.127)
		(layer "F.Cu")
		(net "PHY_DRV_B_TO_SCC_B_31_DP")
	)
	(segment
		(start 357.463598 -19.023076)
		(end 357.311198 -18.870676)
		(width 0.127)
		(layer "F.Cu")
		(net "PHY_DRV_B_TO_SCC_B_31_DP")
	)
	(segment
		(start 357.311198 -18.870676)
		(end 355.15042 -18.870676)
		(width 0.127)
		(layer "F.Cu")
		(net "PHY_DRV_B_TO_SCC_B_31_DP")
	)
	(segment
		(start 357.590598 -19.385026)
		(end 357.463598 -19.258026)
		(width 0.127)
		(layer "F.Cu")
		(net "PHY_DRV_B_TO_SCC_B_31_DP")
	)
	(segment
		(start 355.15042 -18.870676)
		(end 354.720652 -18.440908)
		(width 0.127)
		(layer "F.Cu")
		(net "PHY_DRV_B_TO_SCC_B_31_DP")
	)
	(segment
		(start 358.925114 -19.385026)
		(end 357.590598 -19.385026)
		(width 0.127)
		(layer "F.Cu")
		(net "PHY_DRV_B_TO_SCC_B_31_DP")
	)
	(segment
		(start 357.463598 -19.258026)
		(end 357.463598 -19.023076)
		(width 0.127)
		(layer "F.Cu")
		(net "PHY_DRV_B_TO_SCC_B_31_DP")
	)
	(segment
		(start 354.720652 -18.440908)
		(end 354.720652 -17.611852)
		(width 0.127)
		(layer "F.Cu")
		(net "PHY_DRV_B_TO_SCC_B_31_DP")
	)
	(arc
		(start 354.720652 -17.611852)
		(mid 354.669468 -17.488284)
		(end 354.5459 -17.4371)
		(width 0.127)
		(layer "F.Cu")
		(net "PHY_DRV_B_TO_SCC_B_31_DP")
	)
	(segment
		(start 342.313768 -76.451714)
		(end 354.6983 -18.2118)
		(width 0.12065)
		(layer "In5.Cu")
		(net "PHY_DRV_B_TO_SCC_B_31_DP")
	)
	(segment
		(start 286.436562 -177.494438)
		(end 286.779208 -177.494438)
		(width 0.12065)
		(layer "In5.Cu")
		(net "PHY_DRV_B_TO_SCC_B_31_DP")
	)
	(segment
		(start 297.148504 -170.715432)
		(end 303.481486 -160.965134)
		(width 0.12065)
		(layer "In5.Cu")
		(net "PHY_DRV_B_TO_SCC_B_31_DP")
	)
	(segment
		(start 354.6983 -18.2118)
		(end 354.6983 -17.5895)
		(width 0.12065)
		(layer "In5.Cu")
		(net "PHY_DRV_B_TO_SCC_B_31_DP")
	)
	(segment
		(start 303.481486 -160.965134)
		(end 311.290208 -124.222002)
		(width 0.12065)
		(layer "In5.Cu")
		(net "PHY_DRV_B_TO_SCC_B_31_DP")
	)
	(segment
		(start 311.290208 -124.222002)
		(end 342.313768 -76.451714)
		(width 0.12065)
		(layer "In5.Cu")
		(net "PHY_DRV_B_TO_SCC_B_31_DP")
	)
	(segment
		(start 354.5459 -17.4371)
		(end 354.231702 -17.4371)
		(width 0.12065)
		(layer "In5.Cu")
		(net "PHY_DRV_B_TO_SCC_B_31_DP")
	)
	(segment
		(start 288.355786 -176.426114)
		(end 297.148504 -170.715432)
		(width 0.12065)
		(layer "In5.Cu")
		(net "PHY_DRV_B_TO_SCC_B_31_DP")
	)
	(segment
		(start 286.968184 -177.305462)
		(end 286.968184 -177.000662)
		(width 0.12065)
		(layer "In5.Cu")
		(net "PHY_DRV_B_TO_SCC_B_31_DP")
	)
	(segment
		(start 287.542732 -176.426114)
		(end 288.355786 -176.426114)
		(width 0.12065)
		(layer "In5.Cu")
		(net "PHY_DRV_B_TO_SCC_B_31_DP")
	)
	(arc
		(start 286.968184 -177.000662)
		(mid 287.136465 -176.594395)
		(end 287.542732 -176.426114)
		(width 0.12065)
		(layer "In5.Cu")
		(net "PHY_DRV_B_TO_SCC_B_31_DP")
	)
	(arc
		(start 354.6983 -17.5895)
		(mid 354.653663 -17.481737)
		(end 354.5459 -17.4371)
		(width 0.12065)
		(layer "In5.Cu")
		(net "PHY_DRV_B_TO_SCC_B_31_DP")
	)
	(arc
		(start 286.779208 -177.494438)
		(mid 286.912834 -177.439088)
		(end 286.968184 -177.305462)
		(width 0.12065)
		(layer "In5.Cu")
		(net "PHY_DRV_B_TO_SCC_B_31_DP")
	)
	(segment
		(start 358.925114 -18.115026)
		(end 357.590598 -18.115026)
		(width 0.127)
		(layer "F.Cu")
		(net "PHY_DRV_B_TO_SCC_B_31_DN")
	)
	(segment
		(start 357.361998 -18.578576)
		(end 355.271578 -18.578576)
		(width 0.127)
		(layer "F.Cu")
		(net "PHY_DRV_B_TO_SCC_B_31_DN")
	)
	(segment
		(start 355.271578 -18.578576)
		(end 355.012752 -18.31975)
		(width 0.127)
		(layer "F.Cu")
		(net "PHY_DRV_B_TO_SCC_B_31_DN")
	)
	(segment
		(start 355.187504 -17.4371)
		(end 355.501702 -17.4371)
		(width 0.127)
		(layer "F.Cu")
		(net "PHY_DRV_B_TO_SCC_B_31_DN")
	)
	(segment
		(start 357.590598 -18.115026)
		(end 357.463598 -18.242026)
		(width 0.127)
		(layer "F.Cu")
		(net "PHY_DRV_B_TO_SCC_B_31_DN")
	)
	(segment
		(start 357.463598 -18.476976)
		(end 357.361998 -18.578576)
		(width 0.127)
		(layer "F.Cu")
		(net "PHY_DRV_B_TO_SCC_B_31_DN")
	)
	(segment
		(start 355.012752 -18.31975)
		(end 355.012752 -17.611852)
		(width 0.127)
		(layer "F.Cu")
		(net "PHY_DRV_B_TO_SCC_B_31_DN")
	)
	(segment
		(start 357.463598 -18.242026)
		(end 357.463598 -18.476976)
		(width 0.127)
		(layer "F.Cu")
		(net "PHY_DRV_B_TO_SCC_B_31_DN")
	)
	(arc
		(start 355.012752 -17.611852)
		(mid 355.063936 -17.488284)
		(end 355.187504 -17.4371)
		(width 0.127)
		(layer "F.Cu")
		(net "PHY_DRV_B_TO_SCC_B_31_DN")
	)
	(segment
		(start 332.864714 -91.99245)
		(end 332.805024 -91.711526)
		(width 0.12065)
		(layer "In5.Cu")
		(net "PHY_DRV_B_TO_SCC_B_31_DN")
	)
	(segment
		(start 297.391836 -170.958764)
		(end 303.797716 -161.096198)
		(width 0.12065)
		(layer "In5.Cu")
		(net "PHY_DRV_B_TO_SCC_B_31_DN")
	)
	(segment
		(start 333.420466 -90.763598)
		(end 333.617824 -90.460068)
		(width 0.12065)
		(layer "In5.Cu")
		(net "PHY_DRV_B_TO_SCC_B_31_DN")
	)
	(segment
		(start 332.386432 -92.355924)
		(end 332.66761 -92.29598)
		(width 0.12065)
		(layer "In5.Cu")
		(net "PHY_DRV_B_TO_SCC_B_31_DN")
	)
	(segment
		(start 333.48041 -91.044522)
		(end 333.420466 -90.763598)
		(width 0.12065)
		(layer "In5.Cu")
		(net "PHY_DRV_B_TO_SCC_B_31_DN")
	)
	(segment
		(start 333.898748 -90.400124)
		(end 334.095852 -90.096594)
		(width 0.12065)
		(layer "In5.Cu")
		(net "PHY_DRV_B_TO_SCC_B_31_DN")
	)
	(segment
		(start 311.606438 -124.353066)
		(end 332.386432 -92.355924)
		(width 0.12065)
		(layer "In5.Cu")
		(net "PHY_DRV_B_TO_SCC_B_31_DN")
	)
	(segment
		(start 333.617824 -90.460068)
		(end 333.898748 -90.400124)
		(width 0.12065)
		(layer "In5.Cu")
		(net "PHY_DRV_B_TO_SCC_B_31_DN")
	)
	(segment
		(start 333.002128 -91.407996)
		(end 333.283052 -91.348052)
		(width 0.12065)
		(layer "In5.Cu")
		(net "PHY_DRV_B_TO_SCC_B_31_DN")
	)
	(segment
		(start 344.592402 -67.354704)
		(end 355.03485 -18.24736)
		(width 0.12065)
		(layer "In5.Cu")
		(net "PHY_DRV_B_TO_SCC_B_31_DN")
	)
	(segment
		(start 342.629998 -76.582778)
		(end 344.592402 -67.354704)
		(width 0.12065)
		(layer "In5.Cu")
		(net "PHY_DRV_B_TO_SCC_B_31_DN")
	)
	(segment
		(start 332.66761 -92.29598)
		(end 332.864714 -91.99245)
		(width 0.12065)
		(layer "In5.Cu")
		(net "PHY_DRV_B_TO_SCC_B_31_DN")
	)
	(segment
		(start 287.83661 -177.494438)
		(end 287.49371 -177.494438)
		(width 0.12065)
		(layer "In5.Cu")
		(net "PHY_DRV_B_TO_SCC_B_31_DN")
	)
	(segment
		(start 288.455608 -176.762664)
		(end 297.391836 -170.958764)
		(width 0.12065)
		(layer "In5.Cu")
		(net "PHY_DRV_B_TO_SCC_B_31_DN")
	)
	(segment
		(start 333.283052 -91.348052)
		(end 333.48041 -91.044522)
		(width 0.12065)
		(layer "In5.Cu")
		(net "PHY_DRV_B_TO_SCC_B_31_DN")
	)
	(segment
		(start 355.03485 -18.24736)
		(end 355.03485 -17.589754)
		(width 0.12065)
		(layer "In5.Cu")
		(net "PHY_DRV_B_TO_SCC_B_31_DN")
	)
	(segment
		(start 287.542732 -176.762664)
		(end 288.455608 -176.762664)
		(width 0.12065)
		(layer "In5.Cu")
		(net "PHY_DRV_B_TO_SCC_B_31_DN")
	)
	(segment
		(start 332.805024 -91.711526)
		(end 333.002128 -91.407996)
		(width 0.12065)
		(layer "In5.Cu")
		(net "PHY_DRV_B_TO_SCC_B_31_DN")
	)
	(segment
		(start 303.797716 -161.096198)
		(end 311.606438 -124.353066)
		(width 0.12065)
		(layer "In5.Cu")
		(net "PHY_DRV_B_TO_SCC_B_31_DN")
	)
	(segment
		(start 334.036162 -89.81567)
		(end 342.629998 -76.582778)
		(width 0.12065)
		(layer "In5.Cu")
		(net "PHY_DRV_B_TO_SCC_B_31_DN")
	)
	(segment
		(start 287.304734 -177.305462)
		(end 287.304734 -177.000662)
		(width 0.12065)
		(layer "In5.Cu")
		(net "PHY_DRV_B_TO_SCC_B_31_DN")
	)
	(segment
		(start 334.095852 -90.096594)
		(end 334.036162 -89.81567)
		(width 0.12065)
		(layer "In5.Cu")
		(net "PHY_DRV_B_TO_SCC_B_31_DN")
	)
	(segment
		(start 355.187504 -17.4371)
		(end 355.501702 -17.4371)
		(width 0.12065)
		(layer "In5.Cu")
		(net "PHY_DRV_B_TO_SCC_B_31_DN")
	)
	(arc
		(start 355.03485 -17.589754)
		(mid 355.079561 -17.481811)
		(end 355.187504 -17.4371)
		(width 0.12065)
		(layer "In5.Cu")
		(net "PHY_DRV_B_TO_SCC_B_31_DN")
	)
	(arc
		(start 287.49371 -177.494438)
		(mid 287.360084 -177.439088)
		(end 287.304734 -177.305462)
		(width 0.12065)
		(layer "In5.Cu")
		(net "PHY_DRV_B_TO_SCC_B_31_DN")
	)
	(arc
		(start 287.304734 -177.000662)
		(mid 287.374442 -176.832372)
		(end 287.542732 -176.762664)
		(width 0.12065)
		(layer "In5.Cu")
		(net "PHY_DRV_B_TO_SCC_B_31_DN")
	)
	(segment
		(start 325.750936 -18.860516)
		(end 323.590158 -18.860516)
		(width 0.127)
		(layer "F.Cu")
		(net "PHY_DRV_B_TO_SCC_B_30_DP")
	)
	(segment
		(start 323.17055 -18.440908)
		(end 323.17055 -17.60855)
		(width 0.127)
		(layer "F.Cu")
		(net "PHY_DRV_B_TO_SCC_B_30_DP")
	)
	(segment
		(start 326.040496 -19.385026)
		(end 325.913496 -19.258026)
		(width 0.127)
		(layer "F.Cu")
		(net "PHY_DRV_B_TO_SCC_B_30_DP")
	)
	(segment
		(start 322.9991 -17.4371)
		(end 322.6816 -17.4371)
		(width 0.127)
		(layer "F.Cu")
		(net "PHY_DRV_B_TO_SCC_B_30_DP")
	)
	(segment
		(start 327.375012 -19.385026)
		(end 326.040496 -19.385026)
		(width 0.127)
		(layer "F.Cu")
		(net "PHY_DRV_B_TO_SCC_B_30_DP")
	)
	(segment
		(start 325.913496 -19.023076)
		(end 325.750936 -18.860516)
		(width 0.127)
		(layer "F.Cu")
		(net "PHY_DRV_B_TO_SCC_B_30_DP")
	)
	(segment
		(start 325.913496 -19.258026)
		(end 325.913496 -19.023076)
		(width 0.127)
		(layer "F.Cu")
		(net "PHY_DRV_B_TO_SCC_B_30_DP")
	)
	(segment
		(start 323.590158 -18.860516)
		(end 323.17055 -18.440908)
		(width 0.127)
		(layer "F.Cu")
		(net "PHY_DRV_B_TO_SCC_B_30_DP")
	)
	(arc
		(start 323.17055 -17.60855)
		(mid 323.120333 -17.487317)
		(end 322.9991 -17.4371)
		(width 0.127)
		(layer "F.Cu")
		(net "PHY_DRV_B_TO_SCC_B_30_DP")
	)
	(segment
		(start 285.968186 -175.505618)
		(end 285.968186 -175.200564)
		(width 0.12065)
		(layer "In5.Cu")
		(net "PHY_DRV_B_TO_SCC_B_30_DP")
	)
	(segment
		(start 286.106108 -174.867824)
		(end 286.138112 -174.835566)
		(width 0.12065)
		(layer "In5.Cu")
		(net "PHY_DRV_B_TO_SCC_B_30_DP")
	)
	(segment
		(start 300.694344 -161.678874)
		(end 323.148198 -39.500048)
		(width 0.12065)
		(layer "In5.Cu")
		(net "PHY_DRV_B_TO_SCC_B_30_DP")
	)
	(segment
		(start 294.945816 -170.53052)
		(end 300.694344 -161.678874)
		(width 0.12065)
		(layer "In5.Cu")
		(net "PHY_DRV_B_TO_SCC_B_30_DP")
	)
	(segment
		(start 322.9991 -17.4371)
		(end 322.6816 -17.4371)
		(width 0.12065)
		(layer "In5.Cu")
		(net "PHY_DRV_B_TO_SCC_B_30_DP")
	)
	(segment
		(start 323.148198 -39.500048)
		(end 323.148198 -17.586198)
		(width 0.12065)
		(layer "In5.Cu")
		(net "PHY_DRV_B_TO_SCC_B_30_DP")
	)
	(segment
		(start 291.482018 -172.779436)
		(end 294.945816 -170.53052)
		(width 0.12065)
		(layer "In5.Cu")
		(net "PHY_DRV_B_TO_SCC_B_30_DP")
	)
	(segment
		(start 286.301434 -174.672244)
		(end 291.482018 -172.779436)
		(width 0.12065)
		(layer "In5.Cu")
		(net "PHY_DRV_B_TO_SCC_B_30_DP")
	)
	(segment
		(start 285.436564 -175.694594)
		(end 285.77921 -175.694594)
		(width 0.12065)
		(layer "In5.Cu")
		(net "PHY_DRV_B_TO_SCC_B_30_DP")
	)
	(segment
		(start 286.138112 -174.835566)
		(end 286.301434 -174.672244)
		(width 0.12065)
		(layer "In5.Cu")
		(net "PHY_DRV_B_TO_SCC_B_30_DP")
	)
	(arc
		(start 285.968186 -175.200564)
		(mid 286.004134 -175.020514)
		(end 286.106108 -174.867824)
		(width 0.12065)
		(layer "In5.Cu")
		(net "PHY_DRV_B_TO_SCC_B_30_DP")
	)
	(arc
		(start 323.148198 -17.586198)
		(mid 323.104528 -17.48077)
		(end 322.9991 -17.4371)
		(width 0.12065)
		(layer "In5.Cu")
		(net "PHY_DRV_B_TO_SCC_B_30_DP")
	)
	(arc
		(start 285.77921 -175.694594)
		(mid 285.912836 -175.639244)
		(end 285.968186 -175.505618)
		(width 0.12065)
		(layer "In5.Cu")
		(net "PHY_DRV_B_TO_SCC_B_30_DP")
	)
	(segment
		(start 327.375012 -18.115026)
		(end 326.040496 -18.115026)
		(width 0.127)
		(layer "F.Cu")
		(net "PHY_DRV_B_TO_SCC_B_30_DN")
	)
	(segment
		(start 323.711316 -18.568416)
		(end 323.46265 -18.31975)
		(width 0.127)
		(layer "F.Cu")
		(net "PHY_DRV_B_TO_SCC_B_30_DN")
	)
	(segment
		(start 325.913496 -18.476976)
		(end 325.822056 -18.568416)
		(width 0.127)
		(layer "F.Cu")
		(net "PHY_DRV_B_TO_SCC_B_30_DN")
	)
	(segment
		(start 325.913496 -18.242026)
		(end 325.913496 -18.476976)
		(width 0.127)
		(layer "F.Cu")
		(net "PHY_DRV_B_TO_SCC_B_30_DN")
	)
	(segment
		(start 323.46265 -18.31975)
		(end 323.46265 -17.60855)
		(width 0.127)
		(layer "F.Cu")
		(net "PHY_DRV_B_TO_SCC_B_30_DN")
	)
	(segment
		(start 323.6341 -17.4371)
		(end 323.9516 -17.4371)
		(width 0.127)
		(layer "F.Cu")
		(net "PHY_DRV_B_TO_SCC_B_30_DN")
	)
	(segment
		(start 325.822056 -18.568416)
		(end 323.711316 -18.568416)
		(width 0.127)
		(layer "F.Cu")
		(net "PHY_DRV_B_TO_SCC_B_30_DN")
	)
	(segment
		(start 326.040496 -18.115026)
		(end 325.913496 -18.242026)
		(width 0.127)
		(layer "F.Cu")
		(net "PHY_DRV_B_TO_SCC_B_30_DN")
	)
	(arc
		(start 323.46265 -17.60855)
		(mid 323.512867 -17.487317)
		(end 323.6341 -17.4371)
		(width 0.127)
		(layer "F.Cu")
		(net "PHY_DRV_B_TO_SCC_B_30_DN")
	)
	(segment
		(start 321.815714 -49.737772)
		(end 321.880992 -49.381664)
		(width 0.12065)
		(layer "In5.Cu")
		(net "PHY_DRV_B_TO_SCC_B_30_DN")
	)
	(segment
		(start 321.717924 -49.14519)
		(end 321.783456 -48.789336)
		(width 0.12065)
		(layer "In5.Cu")
		(net "PHY_DRV_B_TO_SCC_B_30_DN")
	)
	(segment
		(start 321.92214 -48.033432)
		(end 323.484748 -39.530782)
		(width 0.12065)
		(layer "In5.Cu")
		(net "PHY_DRV_B_TO_SCC_B_30_DN")
	)
	(segment
		(start 321.676776 -50.493422)
		(end 321.513708 -50.256948)
		(width 0.12065)
		(layer "In5.Cu")
		(net "PHY_DRV_B_TO_SCC_B_30_DN")
	)
	(segment
		(start 286.304736 -175.505618)
		(end 286.304736 -175.200818)
		(width 0.12065)
		(layer "In5.Cu")
		(net "PHY_DRV_B_TO_SCC_B_30_DN")
	)
	(segment
		(start 286.389064 -175.06061)
		(end 286.486854 -174.96282)
		(width 0.12065)
		(layer "In5.Cu")
		(net "PHY_DRV_B_TO_SCC_B_30_DN")
	)
	(segment
		(start 323.6341 -17.4371)
		(end 323.9516 -17.4371)
		(width 0.12065)
		(layer "In5.Cu")
		(net "PHY_DRV_B_TO_SCC_B_30_DN")
	)
	(segment
		(start 321.513708 -50.256948)
		(end 321.578986 -49.90084)
		(width 0.12065)
		(layer "In5.Cu")
		(net "PHY_DRV_B_TO_SCC_B_30_DN")
	)
	(segment
		(start 286.486854 -174.96282)
		(end 291.633402 -173.082458)
		(width 0.12065)
		(layer "In5.Cu")
		(net "PHY_DRV_B_TO_SCC_B_30_DN")
	)
	(segment
		(start 286.34436 -175.105568)
		(end 286.389064 -175.06061)
		(width 0.12065)
		(layer "In5.Cu")
		(net "PHY_DRV_B_TO_SCC_B_30_DN")
	)
	(segment
		(start 295.189148 -170.773852)
		(end 301.013368 -161.805874)
		(width 0.12065)
		(layer "In5.Cu")
		(net "PHY_DRV_B_TO_SCC_B_30_DN")
	)
	(segment
		(start 323.484748 -39.530782)
		(end 323.484748 -17.586452)
		(width 0.12065)
		(layer "In5.Cu")
		(net "PHY_DRV_B_TO_SCC_B_30_DN")
	)
	(segment
		(start 286.836612 -175.694594)
		(end 286.493712 -175.694594)
		(width 0.12065)
		(layer "In5.Cu")
		(net "PHY_DRV_B_TO_SCC_B_30_DN")
	)
	(segment
		(start 321.37477 -51.012598)
		(end 321.611244 -50.84953)
		(width 0.12065)
		(layer "In5.Cu")
		(net "PHY_DRV_B_TO_SCC_B_30_DN")
	)
	(segment
		(start 321.880992 -49.381664)
		(end 321.717924 -49.14519)
		(width 0.12065)
		(layer "In5.Cu")
		(net "PHY_DRV_B_TO_SCC_B_30_DN")
	)
	(segment
		(start 321.578986 -49.90084)
		(end 321.815714 -49.737772)
		(width 0.12065)
		(layer "In5.Cu")
		(net "PHY_DRV_B_TO_SCC_B_30_DN")
	)
	(segment
		(start 301.013368 -161.805874)
		(end 321.37477 -51.012598)
		(width 0.12065)
		(layer "In5.Cu")
		(net "PHY_DRV_B_TO_SCC_B_30_DN")
	)
	(segment
		(start 322.085208 -48.27016)
		(end 321.92214 -48.033432)
		(width 0.12065)
		(layer "In5.Cu")
		(net "PHY_DRV_B_TO_SCC_B_30_DN")
	)
	(segment
		(start 321.783456 -48.789336)
		(end 322.01993 -48.626014)
		(width 0.12065)
		(layer "In5.Cu")
		(net "PHY_DRV_B_TO_SCC_B_30_DN")
	)
	(segment
		(start 291.633402 -173.082458)
		(end 295.189148 -170.773852)
		(width 0.12065)
		(layer "In5.Cu")
		(net "PHY_DRV_B_TO_SCC_B_30_DN")
	)
	(segment
		(start 322.01993 -48.626014)
		(end 322.085208 -48.27016)
		(width 0.12065)
		(layer "In5.Cu")
		(net "PHY_DRV_B_TO_SCC_B_30_DN")
	)
	(segment
		(start 321.611244 -50.84953)
		(end 321.676776 -50.493422)
		(width 0.12065)
		(layer "In5.Cu")
		(net "PHY_DRV_B_TO_SCC_B_30_DN")
	)
	(arc
		(start 323.484748 -17.586452)
		(mid 323.528492 -17.480844)
		(end 323.6341 -17.4371)
		(width 0.12065)
		(layer "In5.Cu")
		(net "PHY_DRV_B_TO_SCC_B_30_DN")
	)
	(arc
		(start 286.304736 -175.200818)
		(mid 286.315086 -175.149258)
		(end 286.34436 -175.105568)
		(width 0.12065)
		(layer "In5.Cu")
		(net "PHY_DRV_B_TO_SCC_B_30_DN")
	)
	(arc
		(start 286.493712 -175.694594)
		(mid 286.360086 -175.639244)
		(end 286.304736 -175.505618)
		(width 0.12065)
		(layer "In5.Cu")
		(net "PHY_DRV_B_TO_SCC_B_30_DN")
	)
	(segment
		(start 127.15875 -249.023124)
		(end 127.15875 -249.385074)
		(width 0.127)
		(layer "F.Cu")
		(net "PHY_DRV_B_TO_SCC_B_3_DP")
	)
	(segment
		(start 126.2634 -248.896124)
		(end 127.03175 -248.896124)
		(width 0.127)
		(layer "F.Cu")
		(net "PHY_DRV_B_TO_SCC_B_3_DP")
	)
	(segment
		(start 126.0094 -249.385074)
		(end 126.1364 -249.258074)
		(width 0.127)
		(layer "F.Cu")
		(net "PHY_DRV_B_TO_SCC_B_3_DP")
	)
	(segment
		(start 126.1364 -249.023124)
		(end 126.2634 -248.896124)
		(width 0.127)
		(layer "F.Cu")
		(net "PHY_DRV_B_TO_SCC_B_3_DP")
	)
	(segment
		(start 126.1364 -249.258074)
		(end 126.1364 -249.023124)
		(width 0.127)
		(layer "F.Cu")
		(net "PHY_DRV_B_TO_SCC_B_3_DP")
	)
	(segment
		(start 124.674884 -249.385074)
		(end 126.0094 -249.385074)
		(width 0.127)
		(layer "F.Cu")
		(net "PHY_DRV_B_TO_SCC_B_3_DP")
	)
	(arc
		(start 127.03175 -248.896124)
		(mid 127.121553 -248.933321)
		(end 127.15875 -249.023124)
		(width 0.127)
		(layer "F.Cu")
		(net "PHY_DRV_B_TO_SCC_B_3_DP")
	)
	(segment
		(start 166.002716 -240.978436)
		(end 165.837616 -241.230912)
		(width 0.12065)
		(layer "In5.Cu")
		(net "PHY_DRV_B_TO_SCC_B_3_DP")
	)
	(segment
		(start 165.23081 -241.140488)
		(end 164.87648 -241.214656)
		(width 0.12065)
		(layer "In5.Cu")
		(net "PHY_DRV_B_TO_SCC_B_3_DP")
	)
	(segment
		(start 286.436562 -235.094526)
		(end 286.805116 -235.094526)
		(width 0.12065)
		(layer "In5.Cu")
		(net "PHY_DRV_B_TO_SCC_B_3_DP")
	)
	(segment
		(start 128.178052 -248.918222)
		(end 127.2794 -248.918222)
		(width 0.12065)
		(layer "In5.Cu")
		(net "PHY_DRV_B_TO_SCC_B_3_DP")
	)
	(segment
		(start 252.05309 -235.318554)
		(end 244.580156 -233.729784)
		(width 0.12065)
		(layer "In5.Cu")
		(net "PHY_DRV_B_TO_SCC_B_3_DP")
	)
	(segment
		(start 164.711634 -241.467386)
		(end 164.357304 -241.541808)
		(width 0.12065)
		(layer "In5.Cu")
		(net "PHY_DRV_B_TO_SCC_B_3_DP")
	)
	(segment
		(start 286.628078 -234.362752)
		(end 256.54889 -234.362752)
		(width 0.12065)
		(layer "In5.Cu")
		(net "PHY_DRV_B_TO_SCC_B_3_DP")
	)
	(segment
		(start 256.54889 -234.362752)
		(end 252.05309 -235.318554)
		(width 0.12065)
		(layer "In5.Cu")
		(net "PHY_DRV_B_TO_SCC_B_3_DP")
	)
	(segment
		(start 165.837616 -241.230912)
		(end 165.48354 -241.305334)
		(width 0.12065)
		(layer "In5.Cu")
		(net "PHY_DRV_B_TO_SCC_B_3_DP")
	)
	(segment
		(start 286.968184 -234.931458)
		(end 286.968184 -234.702858)
		(width 0.12065)
		(layer "In5.Cu")
		(net "PHY_DRV_B_TO_SCC_B_3_DP")
	)
	(segment
		(start 164.104828 -241.376708)
		(end 163.750498 -241.45113)
		(width 0.12065)
		(layer "In5.Cu")
		(net "PHY_DRV_B_TO_SCC_B_3_DP")
	)
	(segment
		(start 162.978592 -241.613182)
		(end 128.178052 -248.918222)
		(width 0.12065)
		(layer "In5.Cu")
		(net "PHY_DRV_B_TO_SCC_B_3_DP")
	)
	(segment
		(start 223.256348 -238.26216)
		(end 201.349102 -233.558588)
		(width 0.12065)
		(layer "In5.Cu")
		(net "PHY_DRV_B_TO_SCC_B_3_DP")
	)
	(segment
		(start 201.349102 -233.558588)
		(end 166.002716 -240.978436)
		(width 0.12065)
		(layer "In5.Cu")
		(net "PHY_DRV_B_TO_SCC_B_3_DP")
	)
	(segment
		(start 163.750498 -241.45113)
		(end 163.585652 -241.70386)
		(width 0.12065)
		(layer "In5.Cu")
		(net "PHY_DRV_B_TO_SCC_B_3_DP")
	)
	(segment
		(start 163.585652 -241.70386)
		(end 163.231322 -241.778028)
		(width 0.12065)
		(layer "In5.Cu")
		(net "PHY_DRV_B_TO_SCC_B_3_DP")
	)
	(segment
		(start 244.580156 -233.729784)
		(end 223.256348 -238.26216)
		(width 0.12065)
		(layer "In5.Cu")
		(net "PHY_DRV_B_TO_SCC_B_3_DP")
	)
	(segment
		(start 163.231322 -241.778028)
		(end 162.978592 -241.613182)
		(width 0.12065)
		(layer "In5.Cu")
		(net "PHY_DRV_B_TO_SCC_B_3_DP")
	)
	(segment
		(start 165.48354 -241.305334)
		(end 165.23081 -241.140488)
		(width 0.12065)
		(layer "In5.Cu")
		(net "PHY_DRV_B_TO_SCC_B_3_DP")
	)
	(segment
		(start 164.357304 -241.541808)
		(end 164.104828 -241.376708)
		(width 0.12065)
		(layer "In5.Cu")
		(net "PHY_DRV_B_TO_SCC_B_3_DP")
	)
	(segment
		(start 164.87648 -241.214656)
		(end 164.711634 -241.467386)
		(width 0.12065)
		(layer "In5.Cu")
		(net "PHY_DRV_B_TO_SCC_B_3_DP")
	)
	(segment
		(start 127.15875 -249.038872)
		(end 127.15875 -249.385074)
		(width 0.12065)
		(layer "In5.Cu")
		(net "PHY_DRV_B_TO_SCC_B_3_DP")
	)
	(arc
		(start 127.2794 -248.918222)
		(mid 127.194088 -248.95356)
		(end 127.15875 -249.038872)
		(width 0.12065)
		(layer "In5.Cu")
		(net "PHY_DRV_B_TO_SCC_B_3_DP")
	)
	(arc
		(start 286.805116 -235.094526)
		(mid 286.920422 -235.046764)
		(end 286.968184 -234.931458)
		(width 0.12065)
		(layer "In5.Cu")
		(net "PHY_DRV_B_TO_SCC_B_3_DP")
	)
	(arc
		(start 286.968184 -234.702858)
		(mid 286.868569 -234.462367)
		(end 286.628078 -234.362752)
		(width 0.12065)
		(layer "In5.Cu")
		(net "PHY_DRV_B_TO_SCC_B_3_DP")
	)
	(segment
		(start 126.1364 -248.477024)
		(end 126.2634 -248.604024)
		(width 0.127)
		(layer "F.Cu")
		(net "PHY_DRV_B_TO_SCC_B_3_DN")
	)
	(segment
		(start 124.674884 -248.115074)
		(end 126.0094 -248.115074)
		(width 0.127)
		(layer "F.Cu")
		(net "PHY_DRV_B_TO_SCC_B_3_DN")
	)
	(segment
		(start 126.2634 -248.604024)
		(end 127.03175 -248.604024)
		(width 0.127)
		(layer "F.Cu")
		(net "PHY_DRV_B_TO_SCC_B_3_DN")
	)
	(segment
		(start 127.15875 -248.477024)
		(end 127.15875 -248.115074)
		(width 0.127)
		(layer "F.Cu")
		(net "PHY_DRV_B_TO_SCC_B_3_DN")
	)
	(segment
		(start 126.1364 -248.242074)
		(end 126.1364 -248.477024)
		(width 0.127)
		(layer "F.Cu")
		(net "PHY_DRV_B_TO_SCC_B_3_DN")
	)
	(segment
		(start 126.0094 -248.115074)
		(end 126.1364 -248.242074)
		(width 0.127)
		(layer "F.Cu")
		(net "PHY_DRV_B_TO_SCC_B_3_DN")
	)
	(arc
		(start 127.03175 -248.604024)
		(mid 127.121553 -248.566827)
		(end 127.15875 -248.477024)
		(width 0.127)
		(layer "F.Cu")
		(net "PHY_DRV_B_TO_SCC_B_3_DN")
	)
	(segment
		(start 223.256602 -237.91799)
		(end 201.349864 -233.214418)
		(width 0.12065)
		(layer "In5.Cu")
		(net "PHY_DRV_B_TO_SCC_B_3_DN")
	)
	(segment
		(start 244.580156 -233.385614)
		(end 223.256602 -237.91799)
		(width 0.12065)
		(layer "In5.Cu")
		(net "PHY_DRV_B_TO_SCC_B_3_DN")
	)
	(segment
		(start 287.83661 -235.094526)
		(end 287.467802 -235.094526)
		(width 0.12065)
		(layer "In5.Cu")
		(net "PHY_DRV_B_TO_SCC_B_3_DN")
	)
	(segment
		(start 128.143 -248.581672)
		(end 127.2794 -248.581672)
		(width 0.12065)
		(layer "In5.Cu")
		(net "PHY_DRV_B_TO_SCC_B_3_DN")
	)
	(segment
		(start 287.304734 -234.931458)
		(end 287.304734 -234.702858)
		(width 0.12065)
		(layer "In5.Cu")
		(net "PHY_DRV_B_TO_SCC_B_3_DN")
	)
	(segment
		(start 201.349864 -233.214418)
		(end 165.79723 -240.677446)
		(width 0.12065)
		(layer "In5.Cu")
		(net "PHY_DRV_B_TO_SCC_B_3_DN")
	)
	(segment
		(start 165.79723 -240.677192)
		(end 128.143 -248.581672)
		(width 0.12065)
		(layer "In5.Cu")
		(net "PHY_DRV_B_TO_SCC_B_3_DN")
	)
	(segment
		(start 127.15875 -248.461022)
		(end 127.15875 -248.115074)
		(width 0.12065)
		(layer "In5.Cu")
		(net "PHY_DRV_B_TO_SCC_B_3_DN")
	)
	(segment
		(start 286.628078 -234.026202)
		(end 256.51333 -234.026202)
		(width 0.12065)
		(layer "In5.Cu")
		(net "PHY_DRV_B_TO_SCC_B_3_DN")
	)
	(segment
		(start 252.05309 -234.974384)
		(end 244.580156 -233.385614)
		(width 0.12065)
		(layer "In5.Cu")
		(net "PHY_DRV_B_TO_SCC_B_3_DN")
	)
	(segment
		(start 256.51333 -234.026202)
		(end 252.05309 -234.974384)
		(width 0.12065)
		(layer "In5.Cu")
		(net "PHY_DRV_B_TO_SCC_B_3_DN")
	)
	(segment
		(start 165.79723 -240.677446)
		(end 165.79723 -240.677192)
		(width 0.12065)
		(layer "In5.Cu")
		(net "PHY_DRV_B_TO_SCC_B_3_DN")
	)
	(arc
		(start 127.2794 -248.581672)
		(mid 127.194088 -248.546334)
		(end 127.15875 -248.461022)
		(width 0.12065)
		(layer "In5.Cu")
		(net "PHY_DRV_B_TO_SCC_B_3_DN")
	)
	(arc
		(start 287.467802 -235.094526)
		(mid 287.352496 -235.046764)
		(end 287.304734 -234.931458)
		(width 0.12065)
		(layer "In5.Cu")
		(net "PHY_DRV_B_TO_SCC_B_3_DN")
	)
	(arc
		(start 287.304734 -234.702858)
		(mid 287.106546 -234.22439)
		(end 286.628078 -234.026202)
		(width 0.12065)
		(layer "In5.Cu")
		(net "PHY_DRV_B_TO_SCC_B_3_DN")
	)
	(segment
		(start 189.109604 -19.385026)
		(end 189.236604 -19.258026)
		(width 0.127)
		(layer "F.Cu")
		(net "PHY_DRV_B_TO_SCC_B_29_DP")
	)
	(segment
		(start 189.333124 -18.896076)
		(end 190.131954 -18.896076)
		(width 0.127)
		(layer "F.Cu")
		(net "PHY_DRV_B_TO_SCC_B_29_DP")
	)
	(segment
		(start 189.236604 -19.258026)
		(end 189.236604 -18.992596)
		(width 0.127)
		(layer "F.Cu")
		(net "PHY_DRV_B_TO_SCC_B_29_DP")
	)
	(segment
		(start 187.775088 -19.385026)
		(end 189.109604 -19.385026)
		(width 0.127)
		(layer "F.Cu")
		(net "PHY_DRV_B_TO_SCC_B_29_DP")
	)
	(segment
		(start 189.236604 -18.992596)
		(end 189.333124 -18.896076)
		(width 0.127)
		(layer "F.Cu")
		(net "PHY_DRV_B_TO_SCC_B_29_DP")
	)
	(segment
		(start 190.258954 -19.023076)
		(end 190.258954 -19.385026)
		(width 0.127)
		(layer "F.Cu")
		(net "PHY_DRV_B_TO_SCC_B_29_DP")
	)
	(arc
		(start 190.131954 -18.896076)
		(mid 190.221757 -18.933273)
		(end 190.258954 -19.023076)
		(width 0.127)
		(layer "F.Cu")
		(net "PHY_DRV_B_TO_SCC_B_29_DP")
	)
	(segment
		(start 189.771274 -54.53634)
		(end 187.889388 -45.68063)
		(width 0.12065)
		(layer "In5.Cu")
		(net "PHY_DRV_B_TO_SCC_B_29_DP")
	)
	(segment
		(start 206.528162 -120.874028)
		(end 203.867004 -116.776246)
		(width 0.12065)
		(layer "In5.Cu")
		(net "PHY_DRV_B_TO_SCC_B_29_DP")
	)
	(segment
		(start 191.388238 -18.918174)
		(end 190.379604 -18.918174)
		(width 0.12065)
		(layer "In5.Cu")
		(net "PHY_DRV_B_TO_SCC_B_29_DP")
	)
	(segment
		(start 190.16599 -56.393588)
		(end 189.924944 -56.237124)
		(width 0.12065)
		(layer "In5.Cu")
		(net "PHY_DRV_B_TO_SCC_B_29_DP")
	)
	(segment
		(start 272.51533 -182.298086)
		(end 257.019806 -158.438088)
		(width 0.12065)
		(layer "In5.Cu")
		(net "PHY_DRV_B_TO_SCC_B_29_DP")
	)
	(segment
		(start 202.575414 -114.787172)
		(end 190.40094 -57.49925)
		(width 0.12065)
		(layer "In5.Cu")
		(net "PHY_DRV_B_TO_SCC_B_29_DP")
	)
	(segment
		(start 192.63487 -20.750784)
		(end 192.337944 -19.535902)
		(width 0.12065)
		(layer "In5.Cu")
		(net "PHY_DRV_B_TO_SCC_B_29_DP")
	)
	(segment
		(start 190.258954 -19.038824)
		(end 190.258954 -19.385026)
		(width 0.12065)
		(layer "In5.Cu")
		(net "PHY_DRV_B_TO_SCC_B_29_DP")
	)
	(segment
		(start 190.241174 -56.747664)
		(end 190.16599 -56.393588)
		(width 0.12065)
		(layer "In5.Cu")
		(net "PHY_DRV_B_TO_SCC_B_29_DP")
	)
	(segment
		(start 189.93104 -55.287926)
		(end 189.689994 -55.131208)
		(width 0.12065)
		(layer "In5.Cu")
		(net "PHY_DRV_B_TO_SCC_B_29_DP")
	)
	(segment
		(start 203.867004 -116.776246)
		(end 202.575414 -114.787172)
		(width 0.12065)
		(layer "In5.Cu")
		(net "PHY_DRV_B_TO_SCC_B_29_DP")
	)
	(segment
		(start 285.62808 -185.762646)
		(end 277.850854 -185.762646)
		(width 0.12065)
		(layer "In5.Cu")
		(net "PHY_DRV_B_TO_SCC_B_29_DP")
	)
	(segment
		(start 209.189066 -124.971302)
		(end 206.528162 -120.874028)
		(width 0.12065)
		(layer "In5.Cu")
		(net "PHY_DRV_B_TO_SCC_B_29_DP")
	)
	(segment
		(start 190.159894 -57.342786)
		(end 190.08471 -56.98871)
		(width 0.12065)
		(layer "In5.Cu")
		(net "PHY_DRV_B_TO_SCC_B_29_DP")
	)
	(segment
		(start 192.338198 -19.535902)
		(end 191.388238 -18.918174)
		(width 0.12065)
		(layer "In5.Cu")
		(net "PHY_DRV_B_TO_SCC_B_29_DP")
	)
	(segment
		(start 192.931542 -21.965158)
		(end 192.63487 -20.750784)
		(width 0.12065)
		(layer "In5.Cu")
		(net "PHY_DRV_B_TO_SCC_B_29_DP")
	)
	(segment
		(start 190.08471 -56.98871)
		(end 190.241174 -56.747664)
		(width 0.12065)
		(layer "In5.Cu")
		(net "PHY_DRV_B_TO_SCC_B_29_DP")
	)
	(segment
		(start 190.006224 -55.642002)
		(end 189.93104 -55.287926)
		(width 0.12065)
		(layer "In5.Cu")
		(net "PHY_DRV_B_TO_SCC_B_29_DP")
	)
	(segment
		(start 277.850854 -185.762646)
		(end 272.51533 -182.298086)
		(width 0.12065)
		(layer "In5.Cu")
		(net "PHY_DRV_B_TO_SCC_B_29_DP")
	)
	(segment
		(start 211.888832 -129.128774)
		(end 209.189066 -124.971302)
		(width 0.12065)
		(layer "In5.Cu")
		(net "PHY_DRV_B_TO_SCC_B_29_DP")
	)
	(segment
		(start 189.61481 -54.777132)
		(end 189.771274 -54.53634)
		(width 0.12065)
		(layer "In5.Cu")
		(net "PHY_DRV_B_TO_SCC_B_29_DP")
	)
	(segment
		(start 187.889388 -45.68063)
		(end 190.174372 -34.933382)
		(width 0.12065)
		(layer "In5.Cu")
		(net "PHY_DRV_B_TO_SCC_B_29_DP")
	)
	(segment
		(start 192.337944 -19.535902)
		(end 192.338198 -19.535902)
		(width 0.12065)
		(layer "In5.Cu")
		(net "PHY_DRV_B_TO_SCC_B_29_DP")
	)
	(segment
		(start 189.84976 -55.883048)
		(end 190.006224 -55.642002)
		(width 0.12065)
		(layer "In5.Cu")
		(net "PHY_DRV_B_TO_SCC_B_29_DP")
	)
	(segment
		(start 285.968186 -186.331352)
		(end 285.968186 -186.102752)
		(width 0.12065)
		(layer "In5.Cu")
		(net "PHY_DRV_B_TO_SCC_B_29_DP")
	)
	(segment
		(start 189.689994 -55.131208)
		(end 189.61481 -54.777132)
		(width 0.12065)
		(layer "In5.Cu")
		(net "PHY_DRV_B_TO_SCC_B_29_DP")
	)
	(segment
		(start 285.436564 -186.49442)
		(end 285.805118 -186.49442)
		(width 0.12065)
		(layer "In5.Cu")
		(net "PHY_DRV_B_TO_SCC_B_29_DP")
	)
	(segment
		(start 190.40094 -57.49925)
		(end 190.159894 -57.342786)
		(width 0.12065)
		(layer "In5.Cu")
		(net "PHY_DRV_B_TO_SCC_B_29_DP")
	)
	(segment
		(start 257.019806 -158.438088)
		(end 211.888832 -129.128774)
		(width 0.12065)
		(layer "In5.Cu")
		(net "PHY_DRV_B_TO_SCC_B_29_DP")
	)
	(segment
		(start 189.924944 -56.237124)
		(end 189.84976 -55.883048)
		(width 0.12065)
		(layer "In5.Cu")
		(net "PHY_DRV_B_TO_SCC_B_29_DP")
	)
	(segment
		(start 190.174372 -34.933382)
		(end 192.931542 -21.965158)
		(width 0.12065)
		(layer "In5.Cu")
		(net "PHY_DRV_B_TO_SCC_B_29_DP")
	)
	(arc
		(start 285.805118 -186.49442)
		(mid 285.920424 -186.446658)
		(end 285.968186 -186.331352)
		(width 0.12065)
		(layer "In5.Cu")
		(net "PHY_DRV_B_TO_SCC_B_29_DP")
	)
	(arc
		(start 190.379604 -18.918174)
		(mid 190.294292 -18.953512)
		(end 190.258954 -19.038824)
		(width 0.12065)
		(layer "In5.Cu")
		(net "PHY_DRV_B_TO_SCC_B_29_DP")
	)
	(arc
		(start 285.968186 -186.102752)
		(mid 285.868571 -185.862261)
		(end 285.62808 -185.762646)
		(width 0.12065)
		(layer "In5.Cu")
		(net "PHY_DRV_B_TO_SCC_B_29_DP")
	)
	(segment
		(start 189.236604 -18.242026)
		(end 189.236604 -18.476976)
		(width 0.127)
		(layer "F.Cu")
		(net "PHY_DRV_B_TO_SCC_B_29_DN")
	)
	(segment
		(start 189.236604 -18.476976)
		(end 189.363604 -18.603976)
		(width 0.127)
		(layer "F.Cu")
		(net "PHY_DRV_B_TO_SCC_B_29_DN")
	)
	(segment
		(start 189.109604 -18.115026)
		(end 189.236604 -18.242026)
		(width 0.127)
		(layer "F.Cu")
		(net "PHY_DRV_B_TO_SCC_B_29_DN")
	)
	(segment
		(start 189.363604 -18.603976)
		(end 190.131954 -18.603976)
		(width 0.127)
		(layer "F.Cu")
		(net "PHY_DRV_B_TO_SCC_B_29_DN")
	)
	(segment
		(start 187.775088 -18.115026)
		(end 189.109604 -18.115026)
		(width 0.127)
		(layer "F.Cu")
		(net "PHY_DRV_B_TO_SCC_B_29_DN")
	)
	(segment
		(start 190.258954 -18.476976)
		(end 190.258954 -18.115026)
		(width 0.127)
		(layer "F.Cu")
		(net "PHY_DRV_B_TO_SCC_B_29_DN")
	)
	(arc
		(start 190.131954 -18.603976)
		(mid 190.221757 -18.566779)
		(end 190.258954 -18.476976)
		(width 0.127)
		(layer "F.Cu")
		(net "PHY_DRV_B_TO_SCC_B_29_DN")
	)
	(segment
		(start 212.132164 -128.885442)
		(end 206.81061 -120.69064)
		(width 0.12065)
		(layer "In5.Cu")
		(net "PHY_DRV_B_TO_SCC_B_29_DN")
	)
	(segment
		(start 202.891644 -114.656108)
		(end 188.233558 -45.68063)
		(width 0.12065)
		(layer "In5.Cu")
		(net "PHY_DRV_B_TO_SCC_B_29_DN")
	)
	(segment
		(start 192.6336 -19.326352)
		(end 192.52184 -19.253708)
		(width 0.12065)
		(layer "In5.Cu")
		(net "PHY_DRV_B_TO_SCC_B_29_DN")
	)
	(segment
		(start 192.52184 -19.253708)
		(end 191.48806 -18.581624)
		(width 0.12065)
		(layer "In5.Cu")
		(net "PHY_DRV_B_TO_SCC_B_29_DN")
	)
	(segment
		(start 193.276982 -21.960078)
		(end 192.6336 -19.326352)
		(width 0.12065)
		(layer "In5.Cu")
		(net "PHY_DRV_B_TO_SCC_B_29_DN")
	)
	(segment
		(start 204.149452 -116.592858)
		(end 202.891644 -114.656108)
		(width 0.12065)
		(layer "In5.Cu")
		(net "PHY_DRV_B_TO_SCC_B_29_DN")
	)
	(segment
		(start 190.503556 -35.003486)
		(end 193.276982 -21.960078)
		(width 0.12065)
		(layer "In5.Cu")
		(net "PHY_DRV_B_TO_SCC_B_29_DN")
	)
	(segment
		(start 188.233558 -45.68063)
		(end 190.503556 -35.003486)
		(width 0.12065)
		(layer "In5.Cu")
		(net "PHY_DRV_B_TO_SCC_B_29_DN")
	)
	(segment
		(start 286.304736 -186.331352)
		(end 286.304736 -186.102752)
		(width 0.12065)
		(layer "In5.Cu")
		(net "PHY_DRV_B_TO_SCC_B_29_DN")
	)
	(segment
		(start 272.758662 -182.054754)
		(end 257.263138 -158.194756)
		(width 0.12065)
		(layer "In5.Cu")
		(net "PHY_DRV_B_TO_SCC_B_29_DN")
	)
	(segment
		(start 206.81061 -120.69064)
		(end 204.149452 -116.592858)
		(width 0.12065)
		(layer "In5.Cu")
		(net "PHY_DRV_B_TO_SCC_B_29_DN")
	)
	(segment
		(start 191.48806 -18.581624)
		(end 190.379604 -18.581624)
		(width 0.12065)
		(layer "In5.Cu")
		(net "PHY_DRV_B_TO_SCC_B_29_DN")
	)
	(segment
		(start 286.836612 -186.49442)
		(end 286.467804 -186.49442)
		(width 0.12065)
		(layer "In5.Cu")
		(net "PHY_DRV_B_TO_SCC_B_29_DN")
	)
	(segment
		(start 277.950676 -185.426096)
		(end 272.758662 -182.054754)
		(width 0.12065)
		(layer "In5.Cu")
		(net "PHY_DRV_B_TO_SCC_B_29_DN")
	)
	(segment
		(start 190.258954 -18.460974)
		(end 190.258954 -18.115026)
		(width 0.12065)
		(layer "In5.Cu")
		(net "PHY_DRV_B_TO_SCC_B_29_DN")
	)
	(segment
		(start 285.62808 -185.426096)
		(end 277.950676 -185.426096)
		(width 0.12065)
		(layer "In5.Cu")
		(net "PHY_DRV_B_TO_SCC_B_29_DN")
	)
	(segment
		(start 257.263138 -158.194756)
		(end 212.132164 -128.885442)
		(width 0.12065)
		(layer "In5.Cu")
		(net "PHY_DRV_B_TO_SCC_B_29_DN")
	)
	(arc
		(start 190.379604 -18.581624)
		(mid 190.294292 -18.546286)
		(end 190.258954 -18.460974)
		(width 0.12065)
		(layer "In5.Cu")
		(net "PHY_DRV_B_TO_SCC_B_29_DN")
	)
	(arc
		(start 286.304736 -186.102752)
		(mid 286.106548 -185.624284)
		(end 285.62808 -185.426096)
		(width 0.12065)
		(layer "In5.Cu")
		(net "PHY_DRV_B_TO_SCC_B_29_DN")
	)
	(arc
		(start 286.467804 -186.49442)
		(mid 286.352498 -186.446658)
		(end 286.304736 -186.331352)
		(width 0.12065)
		(layer "In5.Cu")
		(net "PHY_DRV_B_TO_SCC_B_29_DN")
	)
	(segment
		(start 157.686502 -19.023076)
		(end 157.813502 -18.896076)
		(width 0.127)
		(layer "F.Cu")
		(net "PHY_DRV_B_TO_SCC_B_28_DP")
	)
	(segment
		(start 157.686502 -19.258026)
		(end 157.686502 -19.023076)
		(width 0.127)
		(layer "F.Cu")
		(net "PHY_DRV_B_TO_SCC_B_28_DP")
	)
	(segment
		(start 156.224986 -19.385026)
		(end 157.559502 -19.385026)
		(width 0.127)
		(layer "F.Cu")
		(net "PHY_DRV_B_TO_SCC_B_28_DP")
	)
	(segment
		(start 157.813502 -18.896076)
		(end 158.581852 -18.896076)
		(width 0.127)
		(layer "F.Cu")
		(net "PHY_DRV_B_TO_SCC_B_28_DP")
	)
	(segment
		(start 158.708852 -19.023076)
		(end 158.708852 -19.385026)
		(width 0.127)
		(layer "F.Cu")
		(net "PHY_DRV_B_TO_SCC_B_28_DP")
	)
	(segment
		(start 157.559502 -19.385026)
		(end 157.686502 -19.258026)
		(width 0.127)
		(layer "F.Cu")
		(net "PHY_DRV_B_TO_SCC_B_28_DP")
	)
	(arc
		(start 158.581852 -18.896076)
		(mid 158.671655 -18.933273)
		(end 158.708852 -19.023076)
		(width 0.127)
		(layer "F.Cu")
		(net "PHY_DRV_B_TO_SCC_B_28_DP")
	)
	(segment
		(start 177.390806 -83.05673)
		(end 177.315368 -82.702908)
		(width 0.12065)
		(layer "In5.Cu")
		(net "PHY_DRV_B_TO_SCC_B_28_DP")
	)
	(segment
		(start 182.09514 -104.163114)
		(end 178.122326 -85.47227)
		(width 0.12065)
		(layer "In5.Cu")
		(net "PHY_DRV_B_TO_SCC_B_28_DP")
	)
	(segment
		(start 177.315368 -82.702908)
		(end 177.479706 -82.44967)
		(width 0.12065)
		(layer "In5.Cu")
		(net "PHY_DRV_B_TO_SCC_B_28_DP")
	)
	(segment
		(start 191.010032 -117.890798)
		(end 182.09514 -104.163114)
		(width 0.12065)
		(layer "In5.Cu")
		(net "PHY_DRV_B_TO_SCC_B_28_DP")
	)
	(segment
		(start 177.718974 -83.575144)
		(end 177.64379 -83.221068)
		(width 0.12065)
		(layer "In5.Cu")
		(net "PHY_DRV_B_TO_SCC_B_28_DP")
	)
	(segment
		(start 177.869088 -85.307932)
		(end 177.793904 -84.953856)
		(width 0.12065)
		(layer "In5.Cu")
		(net "PHY_DRV_B_TO_SCC_B_28_DP")
	)
	(segment
		(start 177.793904 -84.953856)
		(end 177.958242 -84.700618)
		(width 0.12065)
		(layer "In5.Cu")
		(net "PHY_DRV_B_TO_SCC_B_28_DP")
	)
	(segment
		(start 286.628078 -187.562744)
		(end 276.845268 -187.562744)
		(width 0.12065)
		(layer "In5.Cu")
		(net "PHY_DRV_B_TO_SCC_B_28_DP")
	)
	(segment
		(start 286.436562 -188.294518)
		(end 286.805116 -188.294518)
		(width 0.12065)
		(layer "In5.Cu")
		(net "PHY_DRV_B_TO_SCC_B_28_DP")
	)
	(segment
		(start 177.64379 -83.221068)
		(end 177.390806 -83.05673)
		(width 0.12065)
		(layer "In5.Cu")
		(net "PHY_DRV_B_TO_SCC_B_28_DP")
	)
	(segment
		(start 167.941498 -37.574982)
		(end 162.854894 -21.414232)
		(width 0.12065)
		(layer "In5.Cu")
		(net "PHY_DRV_B_TO_SCC_B_28_DP")
	)
	(segment
		(start 177.554636 -83.828382)
		(end 177.718974 -83.575144)
		(width 0.12065)
		(layer "In5.Cu")
		(net "PHY_DRV_B_TO_SCC_B_28_DP")
	)
	(segment
		(start 162.854894 -21.414232)
		(end 160.055052 -18.918174)
		(width 0.12065)
		(layer "In5.Cu")
		(net "PHY_DRV_B_TO_SCC_B_28_DP")
	)
	(segment
		(start 271.09166 -183.826658)
		(end 255.448308 -159.737806)
		(width 0.12065)
		(layer "In5.Cu")
		(net "PHY_DRV_B_TO_SCC_B_28_DP")
	)
	(segment
		(start 177.630074 -84.182204)
		(end 177.554636 -83.828382)
		(width 0.12065)
		(layer "In5.Cu")
		(net "PHY_DRV_B_TO_SCC_B_28_DP")
	)
	(segment
		(start 178.122326 -85.47227)
		(end 177.869088 -85.307932)
		(width 0.12065)
		(layer "In5.Cu")
		(net "PHY_DRV_B_TO_SCC_B_28_DP")
	)
	(segment
		(start 177.958242 -84.700618)
		(end 177.883058 -84.346542)
		(width 0.12065)
		(layer "In5.Cu")
		(net "PHY_DRV_B_TO_SCC_B_28_DP")
	)
	(segment
		(start 177.479706 -82.44967)
		(end 167.941498 -37.574982)
		(width 0.12065)
		(layer "In5.Cu")
		(net "PHY_DRV_B_TO_SCC_B_28_DP")
	)
	(segment
		(start 276.845268 -187.562744)
		(end 271.09166 -183.826658)
		(width 0.12065)
		(layer "In5.Cu")
		(net "PHY_DRV_B_TO_SCC_B_28_DP")
	)
	(segment
		(start 158.708852 -19.038824)
		(end 158.708852 -19.385026)
		(width 0.12065)
		(layer "In5.Cu")
		(net "PHY_DRV_B_TO_SCC_B_28_DP")
	)
	(segment
		(start 160.055052 -18.918174)
		(end 158.829502 -18.918174)
		(width 0.12065)
		(layer "In5.Cu")
		(net "PHY_DRV_B_TO_SCC_B_28_DP")
	)
	(segment
		(start 177.883058 -84.346542)
		(end 177.630074 -84.182204)
		(width 0.12065)
		(layer "In5.Cu")
		(net "PHY_DRV_B_TO_SCC_B_28_DP")
	)
	(segment
		(start 255.448308 -159.737806)
		(end 191.010032 -117.890798)
		(width 0.12065)
		(layer "In5.Cu")
		(net "PHY_DRV_B_TO_SCC_B_28_DP")
	)
	(segment
		(start 286.968184 -188.13145)
		(end 286.968184 -187.90285)
		(width 0.12065)
		(layer "In5.Cu")
		(net "PHY_DRV_B_TO_SCC_B_28_DP")
	)
	(arc
		(start 286.805116 -188.294518)
		(mid 286.920422 -188.246756)
		(end 286.968184 -188.13145)
		(width 0.12065)
		(layer "In5.Cu")
		(net "PHY_DRV_B_TO_SCC_B_28_DP")
	)
	(arc
		(start 286.968184 -187.90285)
		(mid 286.868569 -187.662359)
		(end 286.628078 -187.562744)
		(width 0.12065)
		(layer "In5.Cu")
		(net "PHY_DRV_B_TO_SCC_B_28_DP")
	)
	(arc
		(start 158.829502 -18.918174)
		(mid 158.74419 -18.953512)
		(end 158.708852 -19.038824)
		(width 0.12065)
		(layer "In5.Cu")
		(net "PHY_DRV_B_TO_SCC_B_28_DP")
	)
	(segment
		(start 156.224986 -18.115026)
		(end 157.559502 -18.115026)
		(width 0.127)
		(layer "F.Cu")
		(net "PHY_DRV_B_TO_SCC_B_28_DN")
	)
	(segment
		(start 157.686502 -18.476976)
		(end 157.813502 -18.603976)
		(width 0.127)
		(layer "F.Cu")
		(net "PHY_DRV_B_TO_SCC_B_28_DN")
	)
	(segment
		(start 157.686502 -18.242026)
		(end 157.686502 -18.476976)
		(width 0.127)
		(layer "F.Cu")
		(net "PHY_DRV_B_TO_SCC_B_28_DN")
	)
	(segment
		(start 158.708852 -18.476976)
		(end 158.708852 -18.115026)
		(width 0.127)
		(layer "F.Cu")
		(net "PHY_DRV_B_TO_SCC_B_28_DN")
	)
	(segment
		(start 157.559502 -18.115026)
		(end 157.686502 -18.242026)
		(width 0.127)
		(layer "F.Cu")
		(net "PHY_DRV_B_TO_SCC_B_28_DN")
	)
	(segment
		(start 157.813502 -18.603976)
		(end 158.581852 -18.603976)
		(width 0.127)
		(layer "F.Cu")
		(net "PHY_DRV_B_TO_SCC_B_28_DN")
	)
	(arc
		(start 158.581852 -18.603976)
		(mid 158.671655 -18.566779)
		(end 158.708852 -18.476976)
		(width 0.127)
		(layer "F.Cu")
		(net "PHY_DRV_B_TO_SCC_B_28_DN")
	)
	(segment
		(start 175.453294 -71.296022)
		(end 168.267634 -37.48913)
		(width 0.12065)
		(layer "In5.Cu")
		(net "PHY_DRV_B_TO_SCC_B_28_DN")
	)
	(segment
		(start 182.41137 -104.03205)
		(end 177.809144 -82.380074)
		(width 0.12065)
		(layer "In5.Cu")
		(net "PHY_DRV_B_TO_SCC_B_28_DN")
	)
	(segment
		(start 158.708852 -18.460974)
		(end 158.708852 -18.115026)
		(width 0.12065)
		(layer "In5.Cu")
		(net "PHY_DRV_B_TO_SCC_B_28_DN")
	)
	(segment
		(start 168.267634 -37.48913)
		(end 163.148264 -21.224494)
		(width 0.12065)
		(layer "In5.Cu")
		(net "PHY_DRV_B_TO_SCC_B_28_DN")
	)
	(segment
		(start 160.183322 -18.581624)
		(end 158.829502 -18.581624)
		(width 0.12065)
		(layer "In5.Cu")
		(net "PHY_DRV_B_TO_SCC_B_28_DN")
	)
	(segment
		(start 191.253364 -117.647466)
		(end 182.41137 -104.03205)
		(width 0.12065)
		(layer "In5.Cu")
		(net "PHY_DRV_B_TO_SCC_B_28_DN")
	)
	(segment
		(start 177.809144 -82.380074)
		(end 175.453294 -71.296022)
		(width 0.12065)
		(layer "In5.Cu")
		(net "PHY_DRV_B_TO_SCC_B_28_DN")
	)
	(segment
		(start 287.83661 -188.294518)
		(end 287.467802 -188.294518)
		(width 0.12065)
		(layer "In5.Cu")
		(net "PHY_DRV_B_TO_SCC_B_28_DN")
	)
	(segment
		(start 287.304734 -188.13145)
		(end 287.304734 -187.90285)
		(width 0.12065)
		(layer "In5.Cu")
		(net "PHY_DRV_B_TO_SCC_B_28_DN")
	)
	(segment
		(start 286.628078 -187.226194)
		(end 276.94509 -187.226194)
		(width 0.12065)
		(layer "In5.Cu")
		(net "PHY_DRV_B_TO_SCC_B_28_DN")
	)
	(segment
		(start 276.94509 -187.226194)
		(end 271.334992 -183.583326)
		(width 0.12065)
		(layer "In5.Cu")
		(net "PHY_DRV_B_TO_SCC_B_28_DN")
	)
	(segment
		(start 255.69164 -159.494474)
		(end 191.253364 -117.647466)
		(width 0.12065)
		(layer "In5.Cu")
		(net "PHY_DRV_B_TO_SCC_B_28_DN")
	)
	(segment
		(start 163.148264 -21.224494)
		(end 160.183322 -18.581624)
		(width 0.12065)
		(layer "In5.Cu")
		(net "PHY_DRV_B_TO_SCC_B_28_DN")
	)
	(segment
		(start 271.334992 -183.583326)
		(end 255.69164 -159.494474)
		(width 0.12065)
		(layer "In5.Cu")
		(net "PHY_DRV_B_TO_SCC_B_28_DN")
	)
	(arc
		(start 158.829502 -18.581624)
		(mid 158.74419 -18.546286)
		(end 158.708852 -18.460974)
		(width 0.12065)
		(layer "In5.Cu")
		(net "PHY_DRV_B_TO_SCC_B_28_DN")
	)
	(arc
		(start 287.467802 -188.294518)
		(mid 287.352496 -188.246756)
		(end 287.304734 -188.13145)
		(width 0.12065)
		(layer "In5.Cu")
		(net "PHY_DRV_B_TO_SCC_B_28_DN")
	)
	(arc
		(start 287.304734 -187.90285)
		(mid 287.106546 -187.424382)
		(end 286.628078 -187.226194)
		(width 0.12065)
		(layer "In5.Cu")
		(net "PHY_DRV_B_TO_SCC_B_28_DN")
	)
	(segment
		(start 127.15875 -19.023076)
		(end 127.15875 -19.385026)
		(width 0.127)
		(layer "F.Cu")
		(net "PHY_DRV_B_TO_SCC_B_27_DP")
	)
	(segment
		(start 126.0094 -19.385026)
		(end 126.1364 -19.258026)
		(width 0.127)
		(layer "F.Cu")
		(net "PHY_DRV_B_TO_SCC_B_27_DP")
	)
	(segment
		(start 126.1364 -19.258026)
		(end 126.1364 -19.023076)
		(width 0.127)
		(layer "F.Cu")
		(net "PHY_DRV_B_TO_SCC_B_27_DP")
	)
	(segment
		(start 124.674884 -19.385026)
		(end 126.0094 -19.385026)
		(width 0.127)
		(layer "F.Cu")
		(net "PHY_DRV_B_TO_SCC_B_27_DP")
	)
	(segment
		(start 126.1364 -19.023076)
		(end 126.2634 -18.896076)
		(width 0.127)
		(layer "F.Cu")
		(net "PHY_DRV_B_TO_SCC_B_27_DP")
	)
	(segment
		(start 126.2634 -18.896076)
		(end 127.03175 -18.896076)
		(width 0.127)
		(layer "F.Cu")
		(net "PHY_DRV_B_TO_SCC_B_27_DP")
	)
	(arc
		(start 127.03175 -18.896076)
		(mid 127.121553 -18.933273)
		(end 127.15875 -19.023076)
		(width 0.127)
		(layer "F.Cu")
		(net "PHY_DRV_B_TO_SCC_B_27_DP")
	)
	(segment
		(start 276.15769 -189.362588)
		(end 270.648938 -185.784998)
		(width 0.12065)
		(layer "In5.Cu")
		(net "PHY_DRV_B_TO_SCC_B_27_DP")
	)
	(segment
		(start 132.423154 -24.741124)
		(end 132.34797 -24.387302)
		(width 0.12065)
		(layer "In5.Cu")
		(net "PHY_DRV_B_TO_SCC_B_27_DP")
	)
	(segment
		(start 132.059934 -22.005798)
		(end 130.212084 -19.159474)
		(width 0.12065)
		(layer "In5.Cu")
		(net "PHY_DRV_B_TO_SCC_B_27_DP")
	)
	(segment
		(start 141.365224 -65.785746)
		(end 133.154674 -27.156664)
		(width 0.12065)
		(layer "In5.Cu")
		(net "PHY_DRV_B_TO_SCC_B_27_DP")
	)
	(segment
		(start 165.811454 -103.429562)
		(end 141.365224 -65.785746)
		(width 0.12065)
		(layer "In5.Cu")
		(net "PHY_DRV_B_TO_SCC_B_27_DP")
	)
	(segment
		(start 254.619252 -161.10204)
		(end 165.811454 -103.429562)
		(width 0.12065)
		(layer "In5.Cu")
		(net "PHY_DRV_B_TO_SCC_B_27_DP")
	)
	(segment
		(start 132.826252 -26.63825)
		(end 132.99059 -26.385012)
		(width 0.12065)
		(layer "In5.Cu")
		(net "PHY_DRV_B_TO_SCC_B_27_DP")
	)
	(segment
		(start 270.648938 -185.784998)
		(end 254.619252 -161.10204)
		(width 0.12065)
		(layer "In5.Cu")
		(net "PHY_DRV_B_TO_SCC_B_27_DP")
	)
	(segment
		(start 127.15875 -19.038824)
		(end 127.15875 -19.385026)
		(width 0.12065)
		(layer "In5.Cu")
		(net "PHY_DRV_B_TO_SCC_B_27_DP")
	)
	(segment
		(start 285.968186 -189.931294)
		(end 285.968186 -189.702694)
		(width 0.12065)
		(layer "In5.Cu")
		(net "PHY_DRV_B_TO_SCC_B_27_DP")
	)
	(segment
		(start 132.676138 -24.905462)
		(end 132.423154 -24.741124)
		(width 0.12065)
		(layer "In5.Cu")
		(net "PHY_DRV_B_TO_SCC_B_27_DP")
	)
	(segment
		(start 132.751576 -25.259538)
		(end 132.676138 -24.905462)
		(width 0.12065)
		(layer "In5.Cu")
		(net "PHY_DRV_B_TO_SCC_B_27_DP")
	)
	(segment
		(start 132.587238 -25.512776)
		(end 132.751576 -25.259538)
		(width 0.12065)
		(layer "In5.Cu")
		(net "PHY_DRV_B_TO_SCC_B_27_DP")
	)
	(segment
		(start 132.286248 -23.070312)
		(end 132.059934 -22.005798)
		(width 0.12065)
		(layer "In5.Cu")
		(net "PHY_DRV_B_TO_SCC_B_27_DP")
	)
	(segment
		(start 129.4003 -18.918174)
		(end 127.2794 -18.918174)
		(width 0.12065)
		(layer "In5.Cu")
		(net "PHY_DRV_B_TO_SCC_B_27_DP")
	)
	(segment
		(start 132.34797 -24.387302)
		(end 132.512308 -24.134064)
		(width 0.12065)
		(layer "In5.Cu")
		(net "PHY_DRV_B_TO_SCC_B_27_DP")
	)
	(segment
		(start 130.212084 -19.159474)
		(end 129.4003 -18.918174)
		(width 0.12065)
		(layer "In5.Cu")
		(net "PHY_DRV_B_TO_SCC_B_27_DP")
	)
	(segment
		(start 132.915406 -26.03119)
		(end 132.662422 -25.866598)
		(width 0.12065)
		(layer "In5.Cu")
		(net "PHY_DRV_B_TO_SCC_B_27_DP")
	)
	(segment
		(start 132.90169 -26.992326)
		(end 132.826252 -26.63825)
		(width 0.12065)
		(layer "In5.Cu")
		(net "PHY_DRV_B_TO_SCC_B_27_DP")
	)
	(segment
		(start 285.62808 -189.362588)
		(end 276.15769 -189.362588)
		(width 0.12065)
		(layer "In5.Cu")
		(net "PHY_DRV_B_TO_SCC_B_27_DP")
	)
	(segment
		(start 132.662422 -25.866598)
		(end 132.587238 -25.512776)
		(width 0.12065)
		(layer "In5.Cu")
		(net "PHY_DRV_B_TO_SCC_B_27_DP")
	)
	(segment
		(start 132.512308 -24.134064)
		(end 132.286248 -23.070312)
		(width 0.12065)
		(layer "In5.Cu")
		(net "PHY_DRV_B_TO_SCC_B_27_DP")
	)
	(segment
		(start 132.99059 -26.385012)
		(end 132.915406 -26.03119)
		(width 0.12065)
		(layer "In5.Cu")
		(net "PHY_DRV_B_TO_SCC_B_27_DP")
	)
	(segment
		(start 285.436564 -190.094362)
		(end 285.805118 -190.094362)
		(width 0.12065)
		(layer "In5.Cu")
		(net "PHY_DRV_B_TO_SCC_B_27_DP")
	)
	(segment
		(start 133.154674 -27.156664)
		(end 132.90169 -26.992326)
		(width 0.12065)
		(layer "In5.Cu")
		(net "PHY_DRV_B_TO_SCC_B_27_DP")
	)
	(arc
		(start 127.2794 -18.918174)
		(mid 127.194088 -18.953512)
		(end 127.15875 -19.038824)
		(width 0.12065)
		(layer "In5.Cu")
		(net "PHY_DRV_B_TO_SCC_B_27_DP")
	)
	(arc
		(start 285.805118 -190.094362)
		(mid 285.920424 -190.0466)
		(end 285.968186 -189.931294)
		(width 0.12065)
		(layer "In5.Cu")
		(net "PHY_DRV_B_TO_SCC_B_27_DP")
	)
	(arc
		(start 285.968186 -189.702694)
		(mid 285.868571 -189.462203)
		(end 285.62808 -189.362588)
		(width 0.12065)
		(layer "In5.Cu")
		(net "PHY_DRV_B_TO_SCC_B_27_DP")
	)
	(segment
		(start 126.0094 -18.115026)
		(end 126.1364 -18.242026)
		(width 0.127)
		(layer "F.Cu")
		(net "PHY_DRV_B_TO_SCC_B_27_DN")
	)
	(segment
		(start 126.1364 -18.242026)
		(end 126.1364 -18.476976)
		(width 0.127)
		(layer "F.Cu")
		(net "PHY_DRV_B_TO_SCC_B_27_DN")
	)
	(segment
		(start 126.2634 -18.603976)
		(end 127.03175 -18.603976)
		(width 0.127)
		(layer "F.Cu")
		(net "PHY_DRV_B_TO_SCC_B_27_DN")
	)
	(segment
		(start 124.674884 -18.115026)
		(end 126.0094 -18.115026)
		(width 0.127)
		(layer "F.Cu")
		(net "PHY_DRV_B_TO_SCC_B_27_DN")
	)
	(segment
		(start 127.15875 -18.476976)
		(end 127.15875 -18.115026)
		(width 0.127)
		(layer "F.Cu")
		(net "PHY_DRV_B_TO_SCC_B_27_DN")
	)
	(segment
		(start 126.1364 -18.476976)
		(end 126.2634 -18.603976)
		(width 0.127)
		(layer "F.Cu")
		(net "PHY_DRV_B_TO_SCC_B_27_DN")
	)
	(arc
		(start 127.03175 -18.603976)
		(mid 127.121553 -18.566779)
		(end 127.15875 -18.476976)
		(width 0.127)
		(layer "F.Cu")
		(net "PHY_DRV_B_TO_SCC_B_27_DN")
	)
	(segment
		(start 132.728716 -23.532338)
		(end 132.615432 -23.000208)
		(width 0.12065)
		(layer "In5.Cu")
		(net "PHY_DRV_B_TO_SCC_B_27_DN")
	)
	(segment
		(start 132.615432 -23.000208)
		(end 132.502402 -22.468078)
		(width 0.12065)
		(layer "In5.Cu")
		(net "PHY_DRV_B_TO_SCC_B_27_DN")
	)
	(segment
		(start 276.257512 -189.026038)
		(end 270.89227 -185.541666)
		(width 0.12065)
		(layer "In5.Cu")
		(net "PHY_DRV_B_TO_SCC_B_27_DN")
	)
	(segment
		(start 141.681454 -65.654682)
		(end 132.728716 -23.532338)
		(width 0.12065)
		(layer "In5.Cu")
		(net "PHY_DRV_B_TO_SCC_B_27_DN")
	)
	(segment
		(start 254.862584 -160.858708)
		(end 166.054786 -103.18623)
		(width 0.12065)
		(layer "In5.Cu")
		(net "PHY_DRV_B_TO_SCC_B_27_DN")
	)
	(segment
		(start 270.89227 -185.541666)
		(end 254.862584 -160.858708)
		(width 0.12065)
		(layer "In5.Cu")
		(net "PHY_DRV_B_TO_SCC_B_27_DN")
	)
	(segment
		(start 129.449322 -18.581624)
		(end 127.2794 -18.581624)
		(width 0.12065)
		(layer "In5.Cu")
		(net "PHY_DRV_B_TO_SCC_B_27_DN")
	)
	(segment
		(start 132.376164 -21.874734)
		(end 130.426968 -18.8722)
		(width 0.12065)
		(layer "In5.Cu")
		(net "PHY_DRV_B_TO_SCC_B_27_DN")
	)
	(segment
		(start 286.836612 -190.094362)
		(end 286.467804 -190.094362)
		(width 0.12065)
		(layer "In5.Cu")
		(net "PHY_DRV_B_TO_SCC_B_27_DN")
	)
	(segment
		(start 285.62808 -189.026038)
		(end 276.257512 -189.026038)
		(width 0.12065)
		(layer "In5.Cu")
		(net "PHY_DRV_B_TO_SCC_B_27_DN")
	)
	(segment
		(start 286.304736 -189.931294)
		(end 286.304736 -189.702694)
		(width 0.12065)
		(layer "In5.Cu")
		(net "PHY_DRV_B_TO_SCC_B_27_DN")
	)
	(segment
		(start 132.502402 -22.468078)
		(end 132.376164 -21.874734)
		(width 0.12065)
		(layer "In5.Cu")
		(net "PHY_DRV_B_TO_SCC_B_27_DN")
	)
	(segment
		(start 166.054786 -103.18623)
		(end 141.681454 -65.654682)
		(width 0.12065)
		(layer "In5.Cu")
		(net "PHY_DRV_B_TO_SCC_B_27_DN")
	)
	(segment
		(start 127.15875 -18.460974)
		(end 127.15875 -18.115026)
		(width 0.12065)
		(layer "In5.Cu")
		(net "PHY_DRV_B_TO_SCC_B_27_DN")
	)
	(segment
		(start 130.426968 -18.8722)
		(end 129.449322 -18.581624)
		(width 0.12065)
		(layer "In5.Cu")
		(net "PHY_DRV_B_TO_SCC_B_27_DN")
	)
	(arc
		(start 286.467804 -190.094362)
		(mid 286.352498 -190.0466)
		(end 286.304736 -189.931294)
		(width 0.12065)
		(layer "In5.Cu")
		(net "PHY_DRV_B_TO_SCC_B_27_DN")
	)
	(arc
		(start 286.304736 -189.702694)
		(mid 286.106548 -189.224226)
		(end 285.62808 -189.026038)
		(width 0.12065)
		(layer "In5.Cu")
		(net "PHY_DRV_B_TO_SCC_B_27_DN")
	)
	(arc
		(start 127.2794 -18.581624)
		(mid 127.194088 -18.546286)
		(end 127.15875 -18.460974)
		(width 0.12065)
		(layer "In5.Cu")
		(net "PHY_DRV_B_TO_SCC_B_27_DN")
	)
	(segment
		(start 94.586552 -19.281648)
		(end 94.586552 -19.023076)
		(width 0.127)
		(layer "F.Cu")
		(net "PHY_DRV_B_TO_SCC_B_26_DP")
	)
	(segment
		(start 94.713552 -18.896076)
		(end 95.481902 -18.896076)
		(width 0.127)
		(layer "F.Cu")
		(net "PHY_DRV_B_TO_SCC_B_26_DP")
	)
	(segment
		(start 94.483174 -19.385026)
		(end 94.586552 -19.281648)
		(width 0.127)
		(layer "F.Cu")
		(net "PHY_DRV_B_TO_SCC_B_26_DP")
	)
	(segment
		(start 95.608902 -19.023076)
		(end 95.608902 -19.385026)
		(width 0.127)
		(layer "F.Cu")
		(net "PHY_DRV_B_TO_SCC_B_26_DP")
	)
	(segment
		(start 94.586552 -19.023076)
		(end 94.713552 -18.896076)
		(width 0.127)
		(layer "F.Cu")
		(net "PHY_DRV_B_TO_SCC_B_26_DP")
	)
	(segment
		(start 93.125036 -19.385026)
		(end 94.483174 -19.385026)
		(width 0.127)
		(layer "F.Cu")
		(net "PHY_DRV_B_TO_SCC_B_26_DP")
	)
	(arc
		(start 95.481902 -18.896076)
		(mid 95.571705 -18.933273)
		(end 95.608902 -19.023076)
		(width 0.127)
		(layer "F.Cu")
		(net "PHY_DRV_B_TO_SCC_B_26_DP")
	)
	(segment
		(start 97.619058 -19.127216)
		(end 97.068132 -18.918174)
		(width 0.12065)
		(layer "In5.Cu")
		(net "PHY_DRV_B_TO_SCC_B_26_DP")
	)
	(segment
		(start 100.45065 -28.67279)
		(end 100.510594 -28.391866)
		(width 0.12065)
		(layer "In5.Cu")
		(net "PHY_DRV_B_TO_SCC_B_26_DP")
	)
	(segment
		(start 286.436562 -191.89446)
		(end 286.805116 -191.89446)
		(width 0.12065)
		(layer "In5.Cu")
		(net "PHY_DRV_B_TO_SCC_B_26_DP")
	)
	(segment
		(start 275.560282 -191.162686)
		(end 269.98041 -187.53836)
		(width 0.12065)
		(layer "In5.Cu")
		(net "PHY_DRV_B_TO_SCC_B_26_DP")
	)
	(segment
		(start 100.928932 -29.036264)
		(end 100.647754 -28.976574)
		(width 0.12065)
		(layer "In5.Cu")
		(net "PHY_DRV_B_TO_SCC_B_26_DP")
	)
	(segment
		(start 101.878892 -30.87243)
		(end 101.681788 -30.5689)
		(width 0.12065)
		(layer "In5.Cu")
		(net "PHY_DRV_B_TO_SCC_B_26_DP")
	)
	(segment
		(start 102.159816 -30.93212)
		(end 101.878892 -30.87243)
		(width 0.12065)
		(layer "In5.Cu")
		(net "PHY_DRV_B_TO_SCC_B_26_DP")
	)
	(segment
		(start 286.968184 -191.731392)
		(end 286.968184 -191.502792)
		(width 0.12065)
		(layer "In5.Cu")
		(net "PHY_DRV_B_TO_SCC_B_26_DP")
	)
	(segment
		(start 253.859792 -162.714686)
		(end 139.51458 -88.46439)
		(width 0.12065)
		(layer "In5.Cu")
		(net "PHY_DRV_B_TO_SCC_B_26_DP")
	)
	(segment
		(start 261.880858 -175.066198)
		(end 253.859792 -162.714686)
		(width 0.12065)
		(layer "In5.Cu")
		(net "PHY_DRV_B_TO_SCC_B_26_DP")
	)
	(segment
		(start 101.544374 -29.984192)
		(end 101.263196 -29.924502)
		(width 0.12065)
		(layer "In5.Cu")
		(net "PHY_DRV_B_TO_SCC_B_26_DP")
	)
	(segment
		(start 139.51458 -88.46439)
		(end 102.159816 -30.93212)
		(width 0.12065)
		(layer "In5.Cu")
		(net "PHY_DRV_B_TO_SCC_B_26_DP")
	)
	(segment
		(start 100.51034 -28.391866)
		(end 100.220018 -27.944826)
		(width 0.12065)
		(layer "In5.Cu")
		(net "PHY_DRV_B_TO_SCC_B_26_DP")
	)
	(segment
		(start 101.741478 -30.287722)
		(end 101.544374 -29.984192)
		(width 0.12065)
		(layer "In5.Cu")
		(net "PHY_DRV_B_TO_SCC_B_26_DP")
	)
	(segment
		(start 100.220018 -27.944826)
		(end 100.162106 -27.855926)
		(width 0.12065)
		(layer "In5.Cu")
		(net "PHY_DRV_B_TO_SCC_B_26_DP")
	)
	(segment
		(start 101.681788 -30.5689)
		(end 101.741478 -30.287722)
		(width 0.12065)
		(layer "In5.Cu")
		(net "PHY_DRV_B_TO_SCC_B_26_DP")
	)
	(segment
		(start 100.510594 -28.391866)
		(end 100.51034 -28.391866)
		(width 0.12065)
		(layer "In5.Cu")
		(net "PHY_DRV_B_TO_SCC_B_26_DP")
	)
	(segment
		(start 98.027744 -19.75739)
		(end 97.619058 -19.127216)
		(width 0.12065)
		(layer "In5.Cu")
		(net "PHY_DRV_B_TO_SCC_B_26_DP")
	)
	(segment
		(start 101.263196 -29.924502)
		(end 101.066092 -29.620718)
		(width 0.12065)
		(layer "In5.Cu")
		(net "PHY_DRV_B_TO_SCC_B_26_DP")
	)
	(segment
		(start 99.548696 -26.910538)
		(end 98.027744 -19.75739)
		(width 0.12065)
		(layer "In5.Cu")
		(net "PHY_DRV_B_TO_SCC_B_26_DP")
	)
	(segment
		(start 100.162106 -27.855926)
		(end 99.548696 -26.910538)
		(width 0.12065)
		(layer "In5.Cu")
		(net "PHY_DRV_B_TO_SCC_B_26_DP")
	)
	(segment
		(start 100.647754 -28.976574)
		(end 100.45065 -28.67279)
		(width 0.12065)
		(layer "In5.Cu")
		(net "PHY_DRV_B_TO_SCC_B_26_DP")
	)
	(segment
		(start 97.068132 -18.918174)
		(end 95.729552 -18.918174)
		(width 0.12065)
		(layer "In5.Cu")
		(net "PHY_DRV_B_TO_SCC_B_26_DP")
	)
	(segment
		(start 95.608902 -19.038824)
		(end 95.608902 -19.385026)
		(width 0.12065)
		(layer "In5.Cu")
		(net "PHY_DRV_B_TO_SCC_B_26_DP")
	)
	(segment
		(start 101.126036 -29.339794)
		(end 100.928932 -29.036264)
		(width 0.12065)
		(layer "In5.Cu")
		(net "PHY_DRV_B_TO_SCC_B_26_DP")
	)
	(segment
		(start 101.066092 -29.620718)
		(end 101.126036 -29.339794)
		(width 0.12065)
		(layer "In5.Cu")
		(net "PHY_DRV_B_TO_SCC_B_26_DP")
	)
	(segment
		(start 269.98041 -187.53836)
		(end 261.880858 -175.066198)
		(width 0.12065)
		(layer "In5.Cu")
		(net "PHY_DRV_B_TO_SCC_B_26_DP")
	)
	(segment
		(start 286.628078 -191.162686)
		(end 275.560282 -191.162686)
		(width 0.12065)
		(layer "In5.Cu")
		(net "PHY_DRV_B_TO_SCC_B_26_DP")
	)
	(arc
		(start 95.729552 -18.918174)
		(mid 95.64424 -18.953512)
		(end 95.608902 -19.038824)
		(width 0.12065)
		(layer "In5.Cu")
		(net "PHY_DRV_B_TO_SCC_B_26_DP")
	)
	(arc
		(start 286.968184 -191.502792)
		(mid 286.868569 -191.262301)
		(end 286.628078 -191.162686)
		(width 0.12065)
		(layer "In5.Cu")
		(net "PHY_DRV_B_TO_SCC_B_26_DP")
	)
	(arc
		(start 286.805116 -191.89446)
		(mid 286.920422 -191.846698)
		(end 286.968184 -191.731392)
		(width 0.12065)
		(layer "In5.Cu")
		(net "PHY_DRV_B_TO_SCC_B_26_DP")
	)
	(segment
		(start 94.586552 -18.476976)
		(end 94.713552 -18.603976)
		(width 0.127)
		(layer "F.Cu")
		(net "PHY_DRV_B_TO_SCC_B_26_DN")
	)
	(segment
		(start 94.442026 -18.115026)
		(end 94.586552 -18.259552)
		(width 0.127)
		(layer "F.Cu")
		(net "PHY_DRV_B_TO_SCC_B_26_DN")
	)
	(segment
		(start 94.713552 -18.603976)
		(end 95.481902 -18.603976)
		(width 0.127)
		(layer "F.Cu")
		(net "PHY_DRV_B_TO_SCC_B_26_DN")
	)
	(segment
		(start 95.608902 -18.476976)
		(end 95.608902 -18.115026)
		(width 0.127)
		(layer "F.Cu")
		(net "PHY_DRV_B_TO_SCC_B_26_DN")
	)
	(segment
		(start 93.125036 -18.115026)
		(end 94.442026 -18.115026)
		(width 0.127)
		(layer "F.Cu")
		(net "PHY_DRV_B_TO_SCC_B_26_DN")
	)
	(segment
		(start 94.586552 -18.259552)
		(end 94.586552 -18.476976)
		(width 0.127)
		(layer "F.Cu")
		(net "PHY_DRV_B_TO_SCC_B_26_DN")
	)
	(arc
		(start 95.481902 -18.603976)
		(mid 95.571705 -18.566779)
		(end 95.608902 -18.476976)
		(width 0.127)
		(layer "F.Cu")
		(net "PHY_DRV_B_TO_SCC_B_26_DN")
	)
	(segment
		(start 270.223742 -187.295028)
		(end 254.103124 -162.471354)
		(width 0.12065)
		(layer "In5.Cu")
		(net "PHY_DRV_B_TO_SCC_B_26_DN")
	)
	(segment
		(start 99.864926 -26.779474)
		(end 98.344228 -19.626326)
		(width 0.12065)
		(layer "In5.Cu")
		(net "PHY_DRV_B_TO_SCC_B_26_DN")
	)
	(segment
		(start 95.608902 -18.460974)
		(end 95.608902 -18.115026)
		(width 0.12065)
		(layer "In5.Cu")
		(net "PHY_DRV_B_TO_SCC_B_26_DN")
	)
	(segment
		(start 139.757912 -88.221058)
		(end 100.560886 -27.8511)
		(width 0.12065)
		(layer "In5.Cu")
		(net "PHY_DRV_B_TO_SCC_B_26_DN")
	)
	(segment
		(start 100.444554 -27.672284)
		(end 99.864926 -26.779474)
		(width 0.12065)
		(layer "In5.Cu")
		(net "PHY_DRV_B_TO_SCC_B_26_DN")
	)
	(segment
		(start 275.660104 -190.826136)
		(end 270.223742 -187.295028)
		(width 0.12065)
		(layer "In5.Cu")
		(net "PHY_DRV_B_TO_SCC_B_26_DN")
	)
	(segment
		(start 97.129854 -18.581624)
		(end 95.729552 -18.581624)
		(width 0.12065)
		(layer "In5.Cu")
		(net "PHY_DRV_B_TO_SCC_B_26_DN")
	)
	(segment
		(start 254.103124 -162.471354)
		(end 139.757912 -88.221058)
		(width 0.12065)
		(layer "In5.Cu")
		(net "PHY_DRV_B_TO_SCC_B_26_DN")
	)
	(segment
		(start 287.83661 -191.89446)
		(end 287.467802 -191.89446)
		(width 0.12065)
		(layer "In5.Cu")
		(net "PHY_DRV_B_TO_SCC_B_26_DN")
	)
	(segment
		(start 287.304734 -191.731392)
		(end 287.304734 -191.502792)
		(width 0.12065)
		(layer "In5.Cu")
		(net "PHY_DRV_B_TO_SCC_B_26_DN")
	)
	(segment
		(start 100.560886 -27.8511)
		(end 100.444554 -27.672284)
		(width 0.12065)
		(layer "In5.Cu")
		(net "PHY_DRV_B_TO_SCC_B_26_DN")
	)
	(segment
		(start 286.628078 -190.826136)
		(end 275.660104 -190.826136)
		(width 0.12065)
		(layer "In5.Cu")
		(net "PHY_DRV_B_TO_SCC_B_26_DN")
	)
	(segment
		(start 97.841562 -18.851372)
		(end 97.129854 -18.581624)
		(width 0.12065)
		(layer "In5.Cu")
		(net "PHY_DRV_B_TO_SCC_B_26_DN")
	)
	(segment
		(start 98.344228 -19.626326)
		(end 97.841562 -18.851372)
		(width 0.12065)
		(layer "In5.Cu")
		(net "PHY_DRV_B_TO_SCC_B_26_DN")
	)
	(arc
		(start 287.467802 -191.89446)
		(mid 287.352496 -191.846698)
		(end 287.304734 -191.731392)
		(width 0.12065)
		(layer "In5.Cu")
		(net "PHY_DRV_B_TO_SCC_B_26_DN")
	)
	(arc
		(start 287.304734 -191.502792)
		(mid 287.106546 -191.024324)
		(end 286.628078 -190.826136)
		(width 0.12065)
		(layer "In5.Cu")
		(net "PHY_DRV_B_TO_SCC_B_26_DN")
	)
	(arc
		(start 95.729552 -18.581624)
		(mid 95.64424 -18.546286)
		(end 95.608902 -18.460974)
		(width 0.12065)
		(layer "In5.Cu")
		(net "PHY_DRV_B_TO_SCC_B_26_DN")
	)
	(segment
		(start 62.90945 -19.385026)
		(end 63.03645 -19.258026)
		(width 0.127)
		(layer "F.Cu")
		(net "PHY_DRV_B_TO_SCC_B_25_DP")
	)
	(segment
		(start 64.0588 -19.023076)
		(end 64.0588 -19.385026)
		(width 0.127)
		(layer "F.Cu")
		(net "PHY_DRV_B_TO_SCC_B_25_DP")
	)
	(segment
		(start 63.03645 -19.258026)
		(end 63.03645 -19.023076)
		(width 0.127)
		(layer "F.Cu")
		(net "PHY_DRV_B_TO_SCC_B_25_DP")
	)
	(segment
		(start 61.574934 -19.385026)
		(end 62.90945 -19.385026)
		(width 0.127)
		(layer "F.Cu")
		(net "PHY_DRV_B_TO_SCC_B_25_DP")
	)
	(segment
		(start 63.03645 -19.023076)
		(end 63.16345 -18.896076)
		(width 0.127)
		(layer "F.Cu")
		(net "PHY_DRV_B_TO_SCC_B_25_DP")
	)
	(segment
		(start 63.16345 -18.896076)
		(end 63.9318 -18.896076)
		(width 0.127)
		(layer "F.Cu")
		(net "PHY_DRV_B_TO_SCC_B_25_DP")
	)
	(arc
		(start 63.9318 -18.896076)
		(mid 64.021603 -18.933273)
		(end 64.0588 -19.023076)
		(width 0.127)
		(layer "F.Cu")
		(net "PHY_DRV_B_TO_SCC_B_25_DP")
	)
	(segment
		(start 64.0588 -19.038824)
		(end 64.0588 -19.385026)
		(width 0.12065)
		(layer "In5.Cu")
		(net "PHY_DRV_B_TO_SCC_B_25_DP")
	)
	(segment
		(start 275.444458 -192.77584)
		(end 269.081758 -188.644276)
		(width 0.12065)
		(layer "In5.Cu")
		(net "PHY_DRV_B_TO_SCC_B_25_DP")
	)
	(segment
		(start 68.999354 -19.768058)
		(end 68.70319 -19.825462)
		(width 0.12065)
		(layer "In5.Cu")
		(net "PHY_DRV_B_TO_SCC_B_25_DP")
	)
	(segment
		(start 68.345558 -19.32686)
		(end 67.739514 -18.918174)
		(width 0.12065)
		(layer "In5.Cu")
		(net "PHY_DRV_B_TO_SCC_B_25_DP")
	)
	(segment
		(start 70.310756 -20.910042)
		(end 70.253352 -20.613878)
		(width 0.12065)
		(layer "In5.Cu")
		(net "PHY_DRV_B_TO_SCC_B_25_DP")
	)
	(segment
		(start 120.208802 -77.684122)
		(end 91.28252 -34.799016)
		(width 0.12065)
		(layer "In5.Cu")
		(net "PHY_DRV_B_TO_SCC_B_25_DP")
	)
	(segment
		(start 276.323806 -192.962784)
		(end 275.444458 -192.77584)
		(width 0.12065)
		(layer "In5.Cu")
		(net "PHY_DRV_B_TO_SCC_B_25_DP")
	)
	(segment
		(start 69.953124 -20.41144)
		(end 69.65696 -20.469098)
		(width 0.12065)
		(layer "In5.Cu")
		(net "PHY_DRV_B_TO_SCC_B_25_DP")
	)
	(segment
		(start 69.356986 -20.26666)
		(end 69.299328 -19.970496)
		(width 0.12065)
		(layer "In5.Cu")
		(net "PHY_DRV_B_TO_SCC_B_25_DP")
	)
	(segment
		(start 67.739514 -18.918174)
		(end 64.17945 -18.918174)
		(width 0.12065)
		(layer "In5.Cu")
		(net "PHY_DRV_B_TO_SCC_B_25_DP")
	)
	(segment
		(start 285.968186 -193.53149)
		(end 285.968186 -193.30289)
		(width 0.12065)
		(layer "In5.Cu")
		(net "PHY_DRV_B_TO_SCC_B_25_DP")
	)
	(segment
		(start 70.610984 -21.11248)
		(end 70.310756 -20.910042)
		(width 0.12065)
		(layer "In5.Cu")
		(net "PHY_DRV_B_TO_SCC_B_25_DP")
	)
	(segment
		(start 285.62808 -192.962784)
		(end 276.323806 -192.962784)
		(width 0.12065)
		(layer "In5.Cu")
		(net "PHY_DRV_B_TO_SCC_B_25_DP")
	)
	(segment
		(start 285.436564 -193.694558)
		(end 285.805118 -193.694558)
		(width 0.12065)
		(layer "In5.Cu")
		(net "PHY_DRV_B_TO_SCC_B_25_DP")
	)
	(segment
		(start 91.28252 -34.799016)
		(end 70.907148 -21.054822)
		(width 0.12065)
		(layer "In5.Cu")
		(net "PHY_DRV_B_TO_SCC_B_25_DP")
	)
	(segment
		(start 68.402962 -19.623278)
		(end 68.345558 -19.32686)
		(width 0.12065)
		(layer "In5.Cu")
		(net "PHY_DRV_B_TO_SCC_B_25_DP")
	)
	(segment
		(start 69.299328 -19.970496)
		(end 68.999354 -19.768058)
		(width 0.12065)
		(layer "In5.Cu")
		(net "PHY_DRV_B_TO_SCC_B_25_DP")
	)
	(segment
		(start 68.70319 -19.825462)
		(end 68.402962 -19.623278)
		(width 0.12065)
		(layer "In5.Cu")
		(net "PHY_DRV_B_TO_SCC_B_25_DP")
	)
	(segment
		(start 69.65696 -20.469098)
		(end 69.356986 -20.26666)
		(width 0.12065)
		(layer "In5.Cu")
		(net "PHY_DRV_B_TO_SCC_B_25_DP")
	)
	(segment
		(start 70.253352 -20.613878)
		(end 69.953124 -20.41144)
		(width 0.12065)
		(layer "In5.Cu")
		(net "PHY_DRV_B_TO_SCC_B_25_DP")
	)
	(segment
		(start 269.081758 -188.644276)
		(end 253.041404 -163.943792)
		(width 0.12065)
		(layer "In5.Cu")
		(net "PHY_DRV_B_TO_SCC_B_25_DP")
	)
	(segment
		(start 70.907148 -21.054822)
		(end 70.610984 -21.11248)
		(width 0.12065)
		(layer "In5.Cu")
		(net "PHY_DRV_B_TO_SCC_B_25_DP")
	)
	(segment
		(start 253.041404 -163.943792)
		(end 120.208802 -77.684122)
		(width 0.12065)
		(layer "In5.Cu")
		(net "PHY_DRV_B_TO_SCC_B_25_DP")
	)
	(arc
		(start 64.17945 -18.918174)
		(mid 64.094138 -18.953512)
		(end 64.0588 -19.038824)
		(width 0.12065)
		(layer "In5.Cu")
		(net "PHY_DRV_B_TO_SCC_B_25_DP")
	)
	(arc
		(start 285.805118 -193.694558)
		(mid 285.920424 -193.646796)
		(end 285.968186 -193.53149)
		(width 0.12065)
		(layer "In5.Cu")
		(net "PHY_DRV_B_TO_SCC_B_25_DP")
	)
	(arc
		(start 285.968186 -193.30289)
		(mid 285.868571 -193.062399)
		(end 285.62808 -192.962784)
		(width 0.12065)
		(layer "In5.Cu")
		(net "PHY_DRV_B_TO_SCC_B_25_DP")
	)
	(segment
		(start 61.574934 -18.115026)
		(end 62.90945 -18.115026)
		(width 0.127)
		(layer "F.Cu")
		(net "PHY_DRV_B_TO_SCC_B_25_DN")
	)
	(segment
		(start 63.16345 -18.603976)
		(end 63.9318 -18.603976)
		(width 0.127)
		(layer "F.Cu")
		(net "PHY_DRV_B_TO_SCC_B_25_DN")
	)
	(segment
		(start 64.0588 -18.476976)
		(end 64.0588 -18.115026)
		(width 0.127)
		(layer "F.Cu")
		(net "PHY_DRV_B_TO_SCC_B_25_DN")
	)
	(segment
		(start 62.90945 -18.115026)
		(end 63.03645 -18.242026)
		(width 0.127)
		(layer "F.Cu")
		(net "PHY_DRV_B_TO_SCC_B_25_DN")
	)
	(segment
		(start 63.03645 -18.476976)
		(end 63.16345 -18.603976)
		(width 0.127)
		(layer "F.Cu")
		(net "PHY_DRV_B_TO_SCC_B_25_DN")
	)
	(segment
		(start 63.03645 -18.242026)
		(end 63.03645 -18.476976)
		(width 0.127)
		(layer "F.Cu")
		(net "PHY_DRV_B_TO_SCC_B_25_DN")
	)
	(arc
		(start 63.9318 -18.603976)
		(mid 64.021603 -18.566779)
		(end 64.0588 -18.476976)
		(width 0.127)
		(layer "F.Cu")
		(net "PHY_DRV_B_TO_SCC_B_25_DN")
	)
	(segment
		(start 67.842638 -18.581624)
		(end 64.17945 -18.581624)
		(width 0.12065)
		(layer "In5.Cu")
		(net "PHY_DRV_B_TO_SCC_B_25_DN")
	)
	(segment
		(start 275.575522 -192.45961)
		(end 269.32509 -188.400944)
		(width 0.12065)
		(layer "In5.Cu")
		(net "PHY_DRV_B_TO_SCC_B_25_DN")
	)
	(segment
		(start 68.649596 -19.125692)
		(end 67.842638 -18.581624)
		(width 0.12065)
		(layer "In5.Cu")
		(net "PHY_DRV_B_TO_SCC_B_25_DN")
	)
	(segment
		(start 285.62808 -192.626234)
		(end 276.359366 -192.626234)
		(width 0.12065)
		(layer "In5.Cu")
		(net "PHY_DRV_B_TO_SCC_B_25_DN")
	)
	(segment
		(start 276.359366 -192.626234)
		(end 275.575522 -192.45961)
		(width 0.12065)
		(layer "In5.Cu")
		(net "PHY_DRV_B_TO_SCC_B_25_DN")
	)
	(segment
		(start 120.449594 -77.439012)
		(end 91.52509 -34.556446)
		(width 0.12065)
		(layer "In5.Cu")
		(net "PHY_DRV_B_TO_SCC_B_25_DN")
	)
	(segment
		(start 269.32509 -188.400944)
		(end 253.284736 -163.70046)
		(width 0.12065)
		(layer "In5.Cu")
		(net "PHY_DRV_B_TO_SCC_B_25_DN")
	)
	(segment
		(start 64.0588 -18.460974)
		(end 64.0588 -18.115026)
		(width 0.12065)
		(layer "In5.Cu")
		(net "PHY_DRV_B_TO_SCC_B_25_DN")
	)
	(segment
		(start 253.284736 -163.70046)
		(end 120.449594 -77.439012)
		(width 0.12065)
		(layer "In5.Cu")
		(net "PHY_DRV_B_TO_SCC_B_25_DN")
	)
	(segment
		(start 91.52509 -34.556446)
		(end 68.64985 -19.1262)
		(width 0.12065)
		(layer "In5.Cu")
		(net "PHY_DRV_B_TO_SCC_B_25_DN")
	)
	(segment
		(start 286.836612 -193.694558)
		(end 286.467804 -193.694558)
		(width 0.12065)
		(layer "In5.Cu")
		(net "PHY_DRV_B_TO_SCC_B_25_DN")
	)
	(segment
		(start 68.64985 -19.1262)
		(end 68.649596 -19.125692)
		(width 0.12065)
		(layer "In5.Cu")
		(net "PHY_DRV_B_TO_SCC_B_25_DN")
	)
	(segment
		(start 286.304736 -193.53149)
		(end 286.304736 -193.30289)
		(width 0.12065)
		(layer "In5.Cu")
		(net "PHY_DRV_B_TO_SCC_B_25_DN")
	)
	(arc
		(start 286.467804 -193.694558)
		(mid 286.352498 -193.646796)
		(end 286.304736 -193.53149)
		(width 0.12065)
		(layer "In5.Cu")
		(net "PHY_DRV_B_TO_SCC_B_25_DN")
	)
	(arc
		(start 64.17945 -18.581624)
		(mid 64.094138 -18.546286)
		(end 64.0588 -18.460974)
		(width 0.12065)
		(layer "In5.Cu")
		(net "PHY_DRV_B_TO_SCC_B_25_DN")
	)
	(arc
		(start 286.304736 -193.30289)
		(mid 286.106548 -192.824422)
		(end 285.62808 -192.626234)
		(width 0.12065)
		(layer "In5.Cu")
		(net "PHY_DRV_B_TO_SCC_B_25_DN")
	)
	(segment
		(start 31.613602 -18.896076)
		(end 32.381952 -18.896076)
		(width 0.127)
		(layer "F.Cu")
		(net "PHY_DRV_B_TO_SCC_B_24_DP")
	)
	(segment
		(start 31.359602 -19.385026)
		(end 31.486602 -19.258026)
		(width 0.127)
		(layer "F.Cu")
		(net "PHY_DRV_B_TO_SCC_B_24_DP")
	)
	(segment
		(start 32.508952 -19.023076)
		(end 32.508952 -19.385026)
		(width 0.127)
		(layer "F.Cu")
		(net "PHY_DRV_B_TO_SCC_B_24_DP")
	)
	(segment
		(start 30.025086 -19.385026)
		(end 31.359602 -19.385026)
		(width 0.127)
		(layer "F.Cu")
		(net "PHY_DRV_B_TO_SCC_B_24_DP")
	)
	(segment
		(start 31.486602 -19.023076)
		(end 31.613602 -18.896076)
		(width 0.127)
		(layer "F.Cu")
		(net "PHY_DRV_B_TO_SCC_B_24_DP")
	)
	(segment
		(start 31.486602 -19.258026)
		(end 31.486602 -19.023076)
		(width 0.127)
		(layer "F.Cu")
		(net "PHY_DRV_B_TO_SCC_B_24_DP")
	)
	(arc
		(start 32.381952 -18.896076)
		(mid 32.471755 -18.933273)
		(end 32.508952 -19.023076)
		(width 0.127)
		(layer "F.Cu")
		(net "PHY_DRV_B_TO_SCC_B_24_DP")
	)
	(segment
		(start 40.729154 -22.874478)
		(end 34.66719 -18.918174)
		(width 0.12065)
		(layer "In5.Cu")
		(net "PHY_DRV_B_TO_SCC_B_24_DP")
	)
	(segment
		(start 32.508952 -19.038824)
		(end 32.508952 -19.385026)
		(width 0.12065)
		(layer "In5.Cu")
		(net "PHY_DRV_B_TO_SCC_B_24_DP")
	)
	(segment
		(start 134.439152 -88.7349)
		(end 99.181666 -81.24063)
		(width 0.12065)
		(layer "In5.Cu")
		(net "PHY_DRV_B_TO_SCC_B_24_DP")
	)
	(segment
		(start 286.436562 -195.494402)
		(end 286.805116 -195.494402)
		(width 0.12065)
		(layer "In5.Cu")
		(net "PHY_DRV_B_TO_SCC_B_24_DP")
	)
	(segment
		(start 34.66719 -18.918174)
		(end 32.629602 -18.918174)
		(width 0.12065)
		(layer "In5.Cu")
		(net "PHY_DRV_B_TO_SCC_B_24_DP")
	)
	(segment
		(start 42.656252 -24.132286)
		(end 42.35323 -23.93442)
		(width 0.12065)
		(layer "In5.Cu")
		(net "PHY_DRV_B_TO_SCC_B_24_DP")
	)
	(segment
		(start 252.821694 -165.611556)
		(end 134.439152 -88.7349)
		(width 0.12065)
		(layer "In5.Cu")
		(net "PHY_DRV_B_TO_SCC_B_24_DP")
	)
	(segment
		(start 276.37486 -194.762628)
		(end 274.664932 -194.399154)
		(width 0.12065)
		(layer "In5.Cu")
		(net "PHY_DRV_B_TO_SCC_B_24_DP")
	)
	(segment
		(start 99.181666 -81.24063)
		(end 83.720178 -71.199248)
		(width 0.12065)
		(layer "In5.Cu")
		(net "PHY_DRV_B_TO_SCC_B_24_DP")
	)
	(segment
		(start 41.094406 -23.367492)
		(end 40.79113 -23.169626)
		(width 0.12065)
		(layer "In5.Cu")
		(net "PHY_DRV_B_TO_SCC_B_24_DP")
	)
	(segment
		(start 286.968184 -195.331334)
		(end 286.968184 -195.102734)
		(width 0.12065)
		(layer "In5.Cu")
		(net "PHY_DRV_B_TO_SCC_B_24_DP")
	)
	(segment
		(start 40.79113 -23.169626)
		(end 40.729154 -22.874478)
		(width 0.12065)
		(layer "In5.Cu")
		(net "PHY_DRV_B_TO_SCC_B_24_DP")
	)
	(segment
		(start 43.316652 -24.563324)
		(end 43.021504 -24.6253)
		(width 0.12065)
		(layer "In5.Cu")
		(net "PHY_DRV_B_TO_SCC_B_24_DP")
	)
	(segment
		(start 42.057828 -23.996396)
		(end 41.754806 -23.79853)
		(width 0.12065)
		(layer "In5.Cu")
		(net "PHY_DRV_B_TO_SCC_B_24_DP")
	)
	(segment
		(start 41.389554 -23.305516)
		(end 41.094406 -23.367492)
		(width 0.12065)
		(layer "In5.Cu")
		(net "PHY_DRV_B_TO_SCC_B_24_DP")
	)
	(segment
		(start 274.664932 -194.399154)
		(end 269.21206 -190.856616)
		(width 0.12065)
		(layer "In5.Cu")
		(net "PHY_DRV_B_TO_SCC_B_24_DP")
	)
	(segment
		(start 43.021504 -24.6253)
		(end 42.718482 -24.427434)
		(width 0.12065)
		(layer "In5.Cu")
		(net "PHY_DRV_B_TO_SCC_B_24_DP")
	)
	(segment
		(start 41.69283 -23.503382)
		(end 41.389554 -23.305516)
		(width 0.12065)
		(layer "In5.Cu")
		(net "PHY_DRV_B_TO_SCC_B_24_DP")
	)
	(segment
		(start 286.628078 -194.762628)
		(end 276.37486 -194.762628)
		(width 0.12065)
		(layer "In5.Cu")
		(net "PHY_DRV_B_TO_SCC_B_24_DP")
	)
	(segment
		(start 42.718482 -24.427434)
		(end 42.656252 -24.132286)
		(width 0.12065)
		(layer "In5.Cu")
		(net "PHY_DRV_B_TO_SCC_B_24_DP")
	)
	(segment
		(start 83.720178 -71.199248)
		(end 60.883292 -36.028122)
		(width 0.12065)
		(layer "In5.Cu")
		(net "PHY_DRV_B_TO_SCC_B_24_DP")
	)
	(segment
		(start 269.21206 -190.856616)
		(end 252.821694 -165.611556)
		(width 0.12065)
		(layer "In5.Cu")
		(net "PHY_DRV_B_TO_SCC_B_24_DP")
	)
	(segment
		(start 41.754806 -23.79853)
		(end 41.69283 -23.503382)
		(width 0.12065)
		(layer "In5.Cu")
		(net "PHY_DRV_B_TO_SCC_B_24_DP")
	)
	(segment
		(start 60.883292 -36.028122)
		(end 43.316652 -24.563324)
		(width 0.12065)
		(layer "In5.Cu")
		(net "PHY_DRV_B_TO_SCC_B_24_DP")
	)
	(segment
		(start 42.35323 -23.93442)
		(end 42.057828 -23.996396)
		(width 0.12065)
		(layer "In5.Cu")
		(net "PHY_DRV_B_TO_SCC_B_24_DP")
	)
	(arc
		(start 32.629602 -18.918174)
		(mid 32.54429 -18.953512)
		(end 32.508952 -19.038824)
		(width 0.12065)
		(layer "In5.Cu")
		(net "PHY_DRV_B_TO_SCC_B_24_DP")
	)
	(arc
		(start 286.805116 -195.494402)
		(mid 286.920422 -195.44664)
		(end 286.968184 -195.331334)
		(width 0.12065)
		(layer "In5.Cu")
		(net "PHY_DRV_B_TO_SCC_B_24_DP")
	)
	(arc
		(start 286.968184 -195.102734)
		(mid 286.868569 -194.862243)
		(end 286.628078 -194.762628)
		(width 0.12065)
		(layer "In5.Cu")
		(net "PHY_DRV_B_TO_SCC_B_24_DP")
	)
	(segment
		(start 31.486602 -18.242026)
		(end 31.486602 -18.476976)
		(width 0.127)
		(layer "F.Cu")
		(net "PHY_DRV_B_TO_SCC_B_24_DN")
	)
	(segment
		(start 31.486602 -18.476976)
		(end 31.613602 -18.603976)
		(width 0.127)
		(layer "F.Cu")
		(net "PHY_DRV_B_TO_SCC_B_24_DN")
	)
	(segment
		(start 31.613602 -18.603976)
		(end 32.381952 -18.603976)
		(width 0.127)
		(layer "F.Cu")
		(net "PHY_DRV_B_TO_SCC_B_24_DN")
	)
	(segment
		(start 30.025086 -18.115026)
		(end 31.359602 -18.115026)
		(width 0.127)
		(layer "F.Cu")
		(net "PHY_DRV_B_TO_SCC_B_24_DN")
	)
	(segment
		(start 32.508952 -18.476976)
		(end 32.508952 -18.115026)
		(width 0.127)
		(layer "F.Cu")
		(net "PHY_DRV_B_TO_SCC_B_24_DN")
	)
	(segment
		(start 31.359602 -18.115026)
		(end 31.486602 -18.242026)
		(width 0.127)
		(layer "F.Cu")
		(net "PHY_DRV_B_TO_SCC_B_24_DN")
	)
	(arc
		(start 32.381952 -18.603976)
		(mid 32.471755 -18.566779)
		(end 32.508952 -18.476976)
		(width 0.127)
		(layer "F.Cu")
		(net "PHY_DRV_B_TO_SCC_B_24_DN")
	)
	(segment
		(start 34.76752 -18.581624)
		(end 32.629602 -18.581624)
		(width 0.12065)
		(layer "In5.Cu")
		(net "PHY_DRV_B_TO_SCC_B_24_DN")
	)
	(segment
		(start 253.065026 -165.368224)
		(end 134.570216 -88.41867)
		(width 0.12065)
		(layer "In5.Cu")
		(net "PHY_DRV_B_TO_SCC_B_24_DN")
	)
	(segment
		(start 99.31273 -80.9244)
		(end 83.96351 -70.955916)
		(width 0.12065)
		(layer "In5.Cu")
		(net "PHY_DRV_B_TO_SCC_B_24_DN")
	)
	(segment
		(start 61.126878 -35.785044)
		(end 52.284122 -30.01391)
		(width 0.12065)
		(layer "In5.Cu")
		(net "PHY_DRV_B_TO_SCC_B_24_DN")
	)
	(segment
		(start 52.284122 -30.01391)
		(end 34.76752 -18.581624)
		(width 0.12065)
		(layer "In5.Cu")
		(net "PHY_DRV_B_TO_SCC_B_24_DN")
	)
	(segment
		(start 276.41042 -194.426078)
		(end 274.795996 -194.082924)
		(width 0.12065)
		(layer "In5.Cu")
		(net "PHY_DRV_B_TO_SCC_B_24_DN")
	)
	(segment
		(start 287.304734 -195.331334)
		(end 287.304734 -195.102734)
		(width 0.12065)
		(layer "In5.Cu")
		(net "PHY_DRV_B_TO_SCC_B_24_DN")
	)
	(segment
		(start 32.508952 -18.460974)
		(end 32.508952 -18.115026)
		(width 0.12065)
		(layer "In5.Cu")
		(net "PHY_DRV_B_TO_SCC_B_24_DN")
	)
	(segment
		(start 269.455392 -190.613284)
		(end 253.065026 -165.368224)
		(width 0.12065)
		(layer "In5.Cu")
		(net "PHY_DRV_B_TO_SCC_B_24_DN")
	)
	(segment
		(start 134.570216 -88.41867)
		(end 99.31273 -80.9244)
		(width 0.12065)
		(layer "In5.Cu")
		(net "PHY_DRV_B_TO_SCC_B_24_DN")
	)
	(segment
		(start 286.628078 -194.426078)
		(end 276.41042 -194.426078)
		(width 0.12065)
		(layer "In5.Cu")
		(net "PHY_DRV_B_TO_SCC_B_24_DN")
	)
	(segment
		(start 274.795996 -194.082924)
		(end 269.455392 -190.613284)
		(width 0.12065)
		(layer "In5.Cu")
		(net "PHY_DRV_B_TO_SCC_B_24_DN")
	)
	(segment
		(start 287.83661 -195.494402)
		(end 287.467802 -195.494402)
		(width 0.12065)
		(layer "In5.Cu")
		(net "PHY_DRV_B_TO_SCC_B_24_DN")
	)
	(segment
		(start 83.96351 -70.955916)
		(end 61.126878 -35.785044)
		(width 0.12065)
		(layer "In5.Cu")
		(net "PHY_DRV_B_TO_SCC_B_24_DN")
	)
	(arc
		(start 287.304734 -195.102734)
		(mid 287.106546 -194.624266)
		(end 286.628078 -194.426078)
		(width 0.12065)
		(layer "In5.Cu")
		(net "PHY_DRV_B_TO_SCC_B_24_DN")
	)
	(arc
		(start 32.629602 -18.581624)
		(mid 32.54429 -18.546286)
		(end 32.508952 -18.460974)
		(width 0.12065)
		(layer "In5.Cu")
		(net "PHY_DRV_B_TO_SCC_B_24_DN")
	)
	(arc
		(start 287.467802 -195.494402)
		(mid 287.352496 -195.44664)
		(end 287.304734 -195.331334)
		(width 0.12065)
		(layer "In5.Cu")
		(net "PHY_DRV_B_TO_SCC_B_24_DN")
	)
	(segment
		(start 480.920552 -133.440932)
		(end 480.920552 -132.599176)
		(width 0.127)
		(layer "F.Cu")
		(net "PHY_DRV_B_TO_SCC_B_23_DP")
	)
	(segment
		(start 483.663498 -134.007098)
		(end 483.52202 -133.86562)
		(width 0.127)
		(layer "F.Cu")
		(net "PHY_DRV_B_TO_SCC_B_23_DP")
	)
	(segment
		(start 483.663498 -134.25805)
		(end 483.663498 -134.007098)
		(width 0.127)
		(layer "F.Cu")
		(net "PHY_DRV_B_TO_SCC_B_23_DP")
	)
	(segment
		(start 483.790498 -134.38505)
		(end 483.663498 -134.25805)
		(width 0.127)
		(layer "F.Cu")
		(net "PHY_DRV_B_TO_SCC_B_23_DP")
	)
	(segment
		(start 481.34524 -133.86562)
		(end 480.920552 -133.440932)
		(width 0.127)
		(layer "F.Cu")
		(net "PHY_DRV_B_TO_SCC_B_23_DP")
	)
	(segment
		(start 483.52202 -133.86562)
		(end 481.34524 -133.86562)
		(width 0.127)
		(layer "F.Cu")
		(net "PHY_DRV_B_TO_SCC_B_23_DP")
	)
	(segment
		(start 485.125014 -134.38505)
		(end 483.790498 -134.38505)
		(width 0.127)
		(layer "F.Cu")
		(net "PHY_DRV_B_TO_SCC_B_23_DP")
	)
	(segment
		(start 480.7585 -132.437124)
		(end 480.431602 -132.437124)
		(width 0.127)
		(layer "F.Cu")
		(net "PHY_DRV_B_TO_SCC_B_23_DP")
	)
	(arc
		(start 480.920552 -132.599176)
		(mid 480.873088 -132.484588)
		(end 480.7585 -132.437124)
		(width 0.127)
		(layer "F.Cu")
		(net "PHY_DRV_B_TO_SCC_B_23_DP")
	)
	(segment
		(start 286.436562 -206.294482)
		(end 286.743902 -206.294482)
		(width 0.12065)
		(layer "In5.Cu")
		(net "PHY_DRV_B_TO_SCC_B_23_DP")
	)
	(segment
		(start 478.441258 -138.873484)
		(end 480.8982 -135.090154)
		(width 0.12065)
		(layer "In5.Cu")
		(net "PHY_DRV_B_TO_SCC_B_23_DP")
	)
	(segment
		(start 286.968184 -206.0702)
		(end 286.968184 -205.8162)
		(width 0.12065)
		(layer "In5.Cu")
		(net "PHY_DRV_B_TO_SCC_B_23_DP")
	)
	(segment
		(start 287.558226 -205.226158)
		(end 299.315886 -205.226158)
		(width 0.12065)
		(layer "In5.Cu")
		(net "PHY_DRV_B_TO_SCC_B_23_DP")
	)
	(segment
		(start 379.246384 -177.910744)
		(end 404.46325 -161.535618)
		(width 0.12065)
		(layer "In5.Cu")
		(net "PHY_DRV_B_TO_SCC_B_23_DP")
	)
	(segment
		(start 351.432876 -195.645278)
		(end 379.246384 -177.910744)
		(width 0.12065)
		(layer "In5.Cu")
		(net "PHY_DRV_B_TO_SCC_B_23_DP")
	)
	(segment
		(start 480.8982 -135.090154)
		(end 480.8982 -132.5626)
		(width 0.12065)
		(layer "In5.Cu")
		(net "PHY_DRV_B_TO_SCC_B_23_DP")
	)
	(segment
		(start 299.315886 -205.226158)
		(end 318.37249 -202.67295)
		(width 0.12065)
		(layer "In5.Cu")
		(net "PHY_DRV_B_TO_SCC_B_23_DP")
	)
	(segment
		(start 404.46325 -161.535618)
		(end 462.559908 -149.186646)
		(width 0.12065)
		(layer "In5.Cu")
		(net "PHY_DRV_B_TO_SCC_B_23_DP")
	)
	(segment
		(start 480.772724 -132.437124)
		(end 480.431602 -132.437124)
		(width 0.12065)
		(layer "In5.Cu")
		(net "PHY_DRV_B_TO_SCC_B_23_DP")
	)
	(segment
		(start 462.559908 -149.186646)
		(end 478.441258 -138.873484)
		(width 0.12065)
		(layer "In5.Cu")
		(net "PHY_DRV_B_TO_SCC_B_23_DP")
	)
	(segment
		(start 318.37249 -202.67295)
		(end 351.432876 -195.645278)
		(width 0.12065)
		(layer "In5.Cu")
		(net "PHY_DRV_B_TO_SCC_B_23_DP")
	)
	(arc
		(start 286.968184 -205.8162)
		(mid 287.141003 -205.398977)
		(end 287.558226 -205.226158)
		(width 0.12065)
		(layer "In5.Cu")
		(net "PHY_DRV_B_TO_SCC_B_23_DP")
	)
	(arc
		(start 480.8982 -132.5626)
		(mid 480.861449 -132.473875)
		(end 480.772724 -132.437124)
		(width 0.12065)
		(layer "In5.Cu")
		(net "PHY_DRV_B_TO_SCC_B_23_DP")
	)
	(arc
		(start 286.743902 -206.294482)
		(mid 286.902493 -206.228791)
		(end 286.968184 -206.0702)
		(width 0.12065)
		(layer "In5.Cu")
		(net "PHY_DRV_B_TO_SCC_B_23_DP")
	)
	(segment
		(start 481.466398 -133.57352)
		(end 481.212652 -133.319774)
		(width 0.127)
		(layer "F.Cu")
		(net "PHY_DRV_B_TO_SCC_B_23_DN")
	)
	(segment
		(start 483.663498 -133.24205)
		(end 483.663498 -133.477)
		(width 0.127)
		(layer "F.Cu")
		(net "PHY_DRV_B_TO_SCC_B_23_DN")
	)
	(segment
		(start 483.790498 -133.11505)
		(end 483.663498 -133.24205)
		(width 0.127)
		(layer "F.Cu")
		(net "PHY_DRV_B_TO_SCC_B_23_DN")
	)
	(segment
		(start 481.374704 -132.437124)
		(end 481.701602 -132.437124)
		(width 0.127)
		(layer "F.Cu")
		(net "PHY_DRV_B_TO_SCC_B_23_DN")
	)
	(segment
		(start 483.663498 -133.477)
		(end 483.566978 -133.57352)
		(width 0.127)
		(layer "F.Cu")
		(net "PHY_DRV_B_TO_SCC_B_23_DN")
	)
	(segment
		(start 481.212652 -133.319774)
		(end 481.212652 -132.599176)
		(width 0.127)
		(layer "F.Cu")
		(net "PHY_DRV_B_TO_SCC_B_23_DN")
	)
	(segment
		(start 485.125014 -133.11505)
		(end 483.790498 -133.11505)
		(width 0.127)
		(layer "F.Cu")
		(net "PHY_DRV_B_TO_SCC_B_23_DN")
	)
	(segment
		(start 483.566978 -133.57352)
		(end 481.466398 -133.57352)
		(width 0.127)
		(layer "F.Cu")
		(net "PHY_DRV_B_TO_SCC_B_23_DN")
	)
	(arc
		(start 481.212652 -132.599176)
		(mid 481.260116 -132.484588)
		(end 481.374704 -132.437124)
		(width 0.127)
		(layer "F.Cu")
		(net "PHY_DRV_B_TO_SCC_B_23_DN")
	)
	(segment
		(start 478.68459 -139.116816)
		(end 481.23475 -135.189976)
		(width 0.12065)
		(layer "In5.Cu")
		(net "PHY_DRV_B_TO_SCC_B_23_DN")
	)
	(segment
		(start 404.594314 -161.851848)
		(end 406.64257 -161.416492)
		(width 0.12065)
		(layer "In5.Cu")
		(net "PHY_DRV_B_TO_SCC_B_23_DN")
	)
	(segment
		(start 406.883616 -161.572956)
		(end 407.237438 -161.497772)
		(width 0.12065)
		(layer "In5.Cu")
		(net "PHY_DRV_B_TO_SCC_B_23_DN")
	)
	(segment
		(start 308.888638 -204.28331)
		(end 318.429894 -203.004928)
		(width 0.12065)
		(layer "In5.Cu")
		(net "PHY_DRV_B_TO_SCC_B_23_DN")
	)
	(segment
		(start 351.562416 -195.962016)
		(end 379.428756 -178.193954)
		(width 0.12065)
		(layer "In5.Cu")
		(net "PHY_DRV_B_TO_SCC_B_23_DN")
	)
	(segment
		(start 379.428756 -178.193954)
		(end 404.594314 -161.851848)
		(width 0.12065)
		(layer "In5.Cu")
		(net "PHY_DRV_B_TO_SCC_B_23_DN")
	)
	(segment
		(start 407.237438 -161.497772)
		(end 407.394156 -161.256726)
		(width 0.12065)
		(layer "In5.Cu")
		(net "PHY_DRV_B_TO_SCC_B_23_DN")
	)
	(segment
		(start 481.36048 -132.437124)
		(end 481.701602 -132.437124)
		(width 0.12065)
		(layer "In5.Cu")
		(net "PHY_DRV_B_TO_SCC_B_23_DN")
	)
	(segment
		(start 287.304734 -206.0702)
		(end 287.304734 -205.8162)
		(width 0.12065)
		(layer "In5.Cu")
		(net "PHY_DRV_B_TO_SCC_B_23_DN")
	)
	(segment
		(start 408.499564 -161.021776)
		(end 408.85364 -160.946592)
		(width 0.12065)
		(layer "In5.Cu")
		(net "PHY_DRV_B_TO_SCC_B_23_DN")
	)
	(segment
		(start 287.83661 -206.294482)
		(end 287.529016 -206.294482)
		(width 0.12065)
		(layer "In5.Cu")
		(net "PHY_DRV_B_TO_SCC_B_23_DN")
	)
	(segment
		(start 407.394156 -161.256726)
		(end 407.748232 -161.181542)
		(width 0.12065)
		(layer "In5.Cu")
		(net "PHY_DRV_B_TO_SCC_B_23_DN")
	)
	(segment
		(start 299.338492 -205.562708)
		(end 308.888638 -204.28331)
		(width 0.12065)
		(layer "In5.Cu")
		(net "PHY_DRV_B_TO_SCC_B_23_DN")
	)
	(segment
		(start 318.429894 -203.004928)
		(end 351.562416 -195.962016)
		(width 0.12065)
		(layer "In5.Cu")
		(net "PHY_DRV_B_TO_SCC_B_23_DN")
	)
	(segment
		(start 287.558226 -205.562708)
		(end 299.338492 -205.562708)
		(width 0.12065)
		(layer "In5.Cu")
		(net "PHY_DRV_B_TO_SCC_B_23_DN")
	)
	(segment
		(start 409.094686 -161.103056)
		(end 409.448762 -161.027618)
		(width 0.12065)
		(layer "In5.Cu")
		(net "PHY_DRV_B_TO_SCC_B_23_DN")
	)
	(segment
		(start 462.690972 -149.502876)
		(end 478.68459 -139.116816)
		(width 0.12065)
		(layer "In5.Cu")
		(net "PHY_DRV_B_TO_SCC_B_23_DN")
	)
	(segment
		(start 407.748232 -161.181542)
		(end 407.989024 -161.338006)
		(width 0.12065)
		(layer "In5.Cu")
		(net "PHY_DRV_B_TO_SCC_B_23_DN")
	)
	(segment
		(start 408.85364 -160.946592)
		(end 409.094686 -161.103056)
		(width 0.12065)
		(layer "In5.Cu")
		(net "PHY_DRV_B_TO_SCC_B_23_DN")
	)
	(segment
		(start 409.448762 -161.027618)
		(end 409.605226 -160.786826)
		(width 0.12065)
		(layer "In5.Cu")
		(net "PHY_DRV_B_TO_SCC_B_23_DN")
	)
	(segment
		(start 407.989024 -161.338006)
		(end 408.3431 -161.262822)
		(width 0.12065)
		(layer "In5.Cu")
		(net "PHY_DRV_B_TO_SCC_B_23_DN")
	)
	(segment
		(start 409.605226 -160.786826)
		(end 462.690972 -149.502876)
		(width 0.12065)
		(layer "In5.Cu")
		(net "PHY_DRV_B_TO_SCC_B_23_DN")
	)
	(segment
		(start 406.64257 -161.416492)
		(end 406.883616 -161.572956)
		(width 0.12065)
		(layer "In5.Cu")
		(net "PHY_DRV_B_TO_SCC_B_23_DN")
	)
	(segment
		(start 408.3431 -161.262822)
		(end 408.499564 -161.021776)
		(width 0.12065)
		(layer "In5.Cu")
		(net "PHY_DRV_B_TO_SCC_B_23_DN")
	)
	(segment
		(start 481.23475 -135.189976)
		(end 481.23475 -132.562854)
		(width 0.12065)
		(layer "In5.Cu")
		(net "PHY_DRV_B_TO_SCC_B_23_DN")
	)
	(arc
		(start 287.529016 -206.294482)
		(mid 287.370425 -206.228791)
		(end 287.304734 -206.0702)
		(width 0.12065)
		(layer "In5.Cu")
		(net "PHY_DRV_B_TO_SCC_B_23_DN")
	)
	(arc
		(start 287.304734 -205.8162)
		(mid 287.37898 -205.636954)
		(end 287.558226 -205.562708)
		(width 0.12065)
		(layer "In5.Cu")
		(net "PHY_DRV_B_TO_SCC_B_23_DN")
	)
	(arc
		(start 481.23475 -132.562854)
		(mid 481.271575 -132.473949)
		(end 481.36048 -132.437124)
		(width 0.12065)
		(layer "In5.Cu")
		(net "PHY_DRV_B_TO_SCC_B_23_DN")
	)
	(segment
		(start 452.113396 -134.25805)
		(end 452.113396 -134.0231)
		(width 0.127)
		(layer "F.Cu")
		(net "PHY_DRV_B_TO_SCC_B_22_DP")
	)
	(segment
		(start 453.574912 -134.38505)
		(end 452.240396 -134.38505)
		(width 0.127)
		(layer "F.Cu")
		(net "PHY_DRV_B_TO_SCC_B_22_DP")
	)
	(segment
		(start 449.37045 -133.440932)
		(end 449.37045 -132.60705)
		(width 0.127)
		(layer "F.Cu")
		(net "PHY_DRV_B_TO_SCC_B_22_DP")
	)
	(segment
		(start 452.113396 -134.0231)
		(end 451.963536 -133.87324)
		(width 0.127)
		(layer "F.Cu")
		(net "PHY_DRV_B_TO_SCC_B_22_DP")
	)
	(segment
		(start 449.802758 -133.87324)
		(end 449.37045 -133.440932)
		(width 0.127)
		(layer "F.Cu")
		(net "PHY_DRV_B_TO_SCC_B_22_DP")
	)
	(segment
		(start 451.963536 -133.87324)
		(end 449.802758 -133.87324)
		(width 0.127)
		(layer "F.Cu")
		(net "PHY_DRV_B_TO_SCC_B_22_DP")
	)
	(segment
		(start 449.200524 -132.437124)
		(end 448.8815 -132.437124)
		(width 0.127)
		(layer "F.Cu")
		(net "PHY_DRV_B_TO_SCC_B_22_DP")
	)
	(segment
		(start 452.240396 -134.38505)
		(end 452.113396 -134.25805)
		(width 0.127)
		(layer "F.Cu")
		(net "PHY_DRV_B_TO_SCC_B_22_DP")
	)
	(arc
		(start 449.37045 -132.60705)
		(mid 449.32068 -132.486894)
		(end 449.200524 -132.437124)
		(width 0.127)
		(layer "F.Cu")
		(net "PHY_DRV_B_TO_SCC_B_22_DP")
	)
	(segment
		(start 318.502792 -201.091038)
		(end 348.93123 -194.623436)
		(width 0.12065)
		(layer "In5.Cu")
		(net "PHY_DRV_B_TO_SCC_B_22_DP")
	)
	(segment
		(start 446.81267 -137.08253)
		(end 449.348098 -133.180328)
		(width 0.12065)
		(layer "In5.Cu")
		(net "PHY_DRV_B_TO_SCC_B_22_DP")
	)
	(segment
		(start 348.93123 -194.623436)
		(end 414.332166 -152.151588)
		(width 0.12065)
		(layer "In5.Cu")
		(net "PHY_DRV_B_TO_SCC_B_22_DP")
	)
	(segment
		(start 285.436564 -204.494384)
		(end 285.743904 -204.494384)
		(width 0.12065)
		(layer "In5.Cu")
		(net "PHY_DRV_B_TO_SCC_B_22_DP")
	)
	(segment
		(start 414.332166 -152.151588)
		(end 428.119286 -149.220936)
		(width 0.12065)
		(layer "In5.Cu")
		(net "PHY_DRV_B_TO_SCC_B_22_DP")
	)
	(segment
		(start 449.200524 -132.437124)
		(end 448.8815 -132.437124)
		(width 0.12065)
		(layer "In5.Cu")
		(net "PHY_DRV_B_TO_SCC_B_22_DP")
	)
	(segment
		(start 286.558228 -203.42606)
		(end 299.006006 -203.42606)
		(width 0.12065)
		(layer "In5.Cu")
		(net "PHY_DRV_B_TO_SCC_B_22_DP")
	)
	(segment
		(start 285.968186 -204.270102)
		(end 285.968186 -204.016102)
		(width 0.12065)
		(layer "In5.Cu")
		(net "PHY_DRV_B_TO_SCC_B_22_DP")
	)
	(segment
		(start 428.119286 -149.220936)
		(end 446.81267 -137.08253)
		(width 0.12065)
		(layer "In5.Cu")
		(net "PHY_DRV_B_TO_SCC_B_22_DP")
	)
	(segment
		(start 299.006006 -203.42606)
		(end 318.502792 -201.091038)
		(width 0.12065)
		(layer "In5.Cu")
		(net "PHY_DRV_B_TO_SCC_B_22_DP")
	)
	(segment
		(start 449.348098 -133.180328)
		(end 449.348098 -132.584698)
		(width 0.12065)
		(layer "In5.Cu")
		(net "PHY_DRV_B_TO_SCC_B_22_DP")
	)
	(arc
		(start 285.968186 -204.016102)
		(mid 286.141005 -203.598879)
		(end 286.558228 -203.42606)
		(width 0.12065)
		(layer "In5.Cu")
		(net "PHY_DRV_B_TO_SCC_B_22_DP")
	)
	(arc
		(start 449.348098 -132.584698)
		(mid 449.304875 -132.480347)
		(end 449.200524 -132.437124)
		(width 0.12065)
		(layer "In5.Cu")
		(net "PHY_DRV_B_TO_SCC_B_22_DP")
	)
	(arc
		(start 285.743904 -204.494384)
		(mid 285.902495 -204.428693)
		(end 285.968186 -204.270102)
		(width 0.12065)
		(layer "In5.Cu")
		(net "PHY_DRV_B_TO_SCC_B_22_DP")
	)
	(segment
		(start 449.832476 -132.437124)
		(end 450.1515 -132.437124)
		(width 0.127)
		(layer "F.Cu")
		(net "PHY_DRV_B_TO_SCC_B_22_DN")
	)
	(segment
		(start 452.113396 -133.477)
		(end 452.009256 -133.58114)
		(width 0.127)
		(layer "F.Cu")
		(net "PHY_DRV_B_TO_SCC_B_22_DN")
	)
	(segment
		(start 449.66255 -133.319774)
		(end 449.66255 -132.60705)
		(width 0.127)
		(layer "F.Cu")
		(net "PHY_DRV_B_TO_SCC_B_22_DN")
	)
	(segment
		(start 452.240396 -133.11505)
		(end 452.113396 -133.24205)
		(width 0.127)
		(layer "F.Cu")
		(net "PHY_DRV_B_TO_SCC_B_22_DN")
	)
	(segment
		(start 452.113396 -133.24205)
		(end 452.113396 -133.477)
		(width 0.127)
		(layer "F.Cu")
		(net "PHY_DRV_B_TO_SCC_B_22_DN")
	)
	(segment
		(start 452.009256 -133.58114)
		(end 449.923916 -133.58114)
		(width 0.127)
		(layer "F.Cu")
		(net "PHY_DRV_B_TO_SCC_B_22_DN")
	)
	(segment
		(start 453.574912 -133.11505)
		(end 452.240396 -133.11505)
		(width 0.127)
		(layer "F.Cu")
		(net "PHY_DRV_B_TO_SCC_B_22_DN")
	)
	(segment
		(start 449.923916 -133.58114)
		(end 449.66255 -133.319774)
		(width 0.127)
		(layer "F.Cu")
		(net "PHY_DRV_B_TO_SCC_B_22_DN")
	)
	(arc
		(start 449.66255 -132.60705)
		(mid 449.71232 -132.486894)
		(end 449.832476 -132.437124)
		(width 0.127)
		(layer "F.Cu")
		(net "PHY_DRV_B_TO_SCC_B_22_DN")
	)
	(segment
		(start 349.062294 -194.939666)
		(end 368.40287 -182.379874)
		(width 0.12065)
		(layer "In5.Cu")
		(net "PHY_DRV_B_TO_SCC_B_22_DN")
	)
	(segment
		(start 368.987324 -182.24246)
		(end 369.047268 -181.961282)
		(width 0.12065)
		(layer "In5.Cu")
		(net "PHY_DRV_B_TO_SCC_B_22_DN")
	)
	(segment
		(start 369.350798 -181.764178)
		(end 369.631722 -181.823868)
		(width 0.12065)
		(layer "In5.Cu")
		(net "PHY_DRV_B_TO_SCC_B_22_DN")
	)
	(segment
		(start 369.995196 -181.34584)
		(end 370.298726 -181.148482)
		(width 0.12065)
		(layer "In5.Cu")
		(net "PHY_DRV_B_TO_SCC_B_22_DN")
	)
	(segment
		(start 449.832476 -132.437124)
		(end 450.1515 -132.437124)
		(width 0.12065)
		(layer "In5.Cu")
		(net "PHY_DRV_B_TO_SCC_B_22_DN")
	)
	(segment
		(start 286.558228 -203.76261)
		(end 299.026326 -203.76261)
		(width 0.12065)
		(layer "In5.Cu")
		(net "PHY_DRV_B_TO_SCC_B_22_DN")
	)
	(segment
		(start 286.836612 -204.494384)
		(end 286.529018 -204.494384)
		(width 0.12065)
		(layer "In5.Cu")
		(net "PHY_DRV_B_TO_SCC_B_22_DN")
	)
	(segment
		(start 449.684648 -133.28015)
		(end 449.684648 -132.584952)
		(width 0.12065)
		(layer "In5.Cu")
		(net "PHY_DRV_B_TO_SCC_B_22_DN")
	)
	(segment
		(start 368.40287 -182.379874)
		(end 368.683794 -182.439564)
		(width 0.12065)
		(layer "In5.Cu")
		(net "PHY_DRV_B_TO_SCC_B_22_DN")
	)
	(segment
		(start 370.298726 -181.148482)
		(end 370.57965 -181.208426)
		(width 0.12065)
		(layer "In5.Cu")
		(net "PHY_DRV_B_TO_SCC_B_22_DN")
	)
	(segment
		(start 369.047268 -181.961282)
		(end 369.350798 -181.764178)
		(width 0.12065)
		(layer "In5.Cu")
		(net "PHY_DRV_B_TO_SCC_B_22_DN")
	)
	(segment
		(start 447.056002 -137.325862)
		(end 449.684648 -133.28015)
		(width 0.12065)
		(layer "In5.Cu")
		(net "PHY_DRV_B_TO_SCC_B_22_DN")
	)
	(segment
		(start 286.304736 -204.270102)
		(end 286.304736 -204.016102)
		(width 0.12065)
		(layer "In5.Cu")
		(net "PHY_DRV_B_TO_SCC_B_22_DN")
	)
	(segment
		(start 370.883434 -181.011322)
		(end 370.943124 -180.730144)
		(width 0.12065)
		(layer "In5.Cu")
		(net "PHY_DRV_B_TO_SCC_B_22_DN")
	)
	(segment
		(start 369.631722 -181.823868)
		(end 369.935252 -181.626764)
		(width 0.12065)
		(layer "In5.Cu")
		(net "PHY_DRV_B_TO_SCC_B_22_DN")
	)
	(segment
		(start 318.55791 -201.423524)
		(end 349.062294 -194.939666)
		(width 0.12065)
		(layer "In5.Cu")
		(net "PHY_DRV_B_TO_SCC_B_22_DN")
	)
	(segment
		(start 369.935252 -181.626764)
		(end 369.995196 -181.34584)
		(width 0.12065)
		(layer "In5.Cu")
		(net "PHY_DRV_B_TO_SCC_B_22_DN")
	)
	(segment
		(start 428.25035 -149.537166)
		(end 447.056002 -137.325862)
		(width 0.12065)
		(layer "In5.Cu")
		(net "PHY_DRV_B_TO_SCC_B_22_DN")
	)
	(segment
		(start 299.026326 -203.76261)
		(end 318.55791 -201.423524)
		(width 0.12065)
		(layer "In5.Cu")
		(net "PHY_DRV_B_TO_SCC_B_22_DN")
	)
	(segment
		(start 368.683794 -182.439564)
		(end 368.987324 -182.24246)
		(width 0.12065)
		(layer "In5.Cu")
		(net "PHY_DRV_B_TO_SCC_B_22_DN")
	)
	(segment
		(start 370.57965 -181.208426)
		(end 370.883434 -181.011322)
		(width 0.12065)
		(layer "In5.Cu")
		(net "PHY_DRV_B_TO_SCC_B_22_DN")
	)
	(segment
		(start 414.46323 -152.467818)
		(end 428.25035 -149.537166)
		(width 0.12065)
		(layer "In5.Cu")
		(net "PHY_DRV_B_TO_SCC_B_22_DN")
	)
	(segment
		(start 370.943124 -180.730144)
		(end 414.46323 -152.467818)
		(width 0.12065)
		(layer "In5.Cu")
		(net "PHY_DRV_B_TO_SCC_B_22_DN")
	)
	(arc
		(start 449.684648 -132.584952)
		(mid 449.727946 -132.480422)
		(end 449.832476 -132.437124)
		(width 0.12065)
		(layer "In5.Cu")
		(net "PHY_DRV_B_TO_SCC_B_22_DN")
	)
	(arc
		(start 286.304736 -204.016102)
		(mid 286.378982 -203.836856)
		(end 286.558228 -203.76261)
		(width 0.12065)
		(layer "In5.Cu")
		(net "PHY_DRV_B_TO_SCC_B_22_DN")
	)
	(arc
		(start 286.529018 -204.494384)
		(mid 286.370427 -204.428693)
		(end 286.304736 -204.270102)
		(width 0.12065)
		(layer "In5.Cu")
		(net "PHY_DRV_B_TO_SCC_B_22_DN")
	)
	(segment
		(start 420.690548 -134.38505)
		(end 420.563548 -134.25805)
		(width 0.127)
		(layer "F.Cu")
		(net "PHY_DRV_B_TO_SCC_B_21_DP")
	)
	(segment
		(start 417.820602 -133.440932)
		(end 417.820602 -132.588)
		(width 0.127)
		(layer "F.Cu")
		(net "PHY_DRV_B_TO_SCC_B_21_DP")
	)
	(segment
		(start 420.563548 -134.000748)
		(end 420.43096 -133.86816)
		(width 0.127)
		(layer "F.Cu")
		(net "PHY_DRV_B_TO_SCC_B_21_DP")
	)
	(segment
		(start 420.43096 -133.86816)
		(end 418.24783 -133.86816)
		(width 0.127)
		(layer "F.Cu")
		(net "PHY_DRV_B_TO_SCC_B_21_DP")
	)
	(segment
		(start 422.025064 -134.38505)
		(end 420.690548 -134.38505)
		(width 0.127)
		(layer "F.Cu")
		(net "PHY_DRV_B_TO_SCC_B_21_DP")
	)
	(segment
		(start 417.669726 -132.437124)
		(end 417.331652 -132.437124)
		(width 0.127)
		(layer "F.Cu")
		(net "PHY_DRV_B_TO_SCC_B_21_DP")
	)
	(segment
		(start 418.24783 -133.86816)
		(end 417.820602 -133.440932)
		(width 0.127)
		(layer "F.Cu")
		(net "PHY_DRV_B_TO_SCC_B_21_DP")
	)
	(segment
		(start 420.563548 -134.25805)
		(end 420.563548 -134.000748)
		(width 0.127)
		(layer "F.Cu")
		(net "PHY_DRV_B_TO_SCC_B_21_DP")
	)
	(arc
		(start 417.820602 -132.588)
		(mid 417.776411 -132.481315)
		(end 417.669726 -132.437124)
		(width 0.127)
		(layer "F.Cu")
		(net "PHY_DRV_B_TO_SCC_B_21_DP")
	)
	(segment
		(start 336.426556 -193.840354)
		(end 410.117036 -145.984214)
		(width 0.12065)
		(layer "In5.Cu")
		(net "PHY_DRV_B_TO_SCC_B_21_DP")
	)
	(segment
		(start 417.79825 -134.149084)
		(end 417.79825 -132.6388)
		(width 0.12065)
		(layer "In5.Cu")
		(net "PHY_DRV_B_TO_SCC_B_21_DP")
	)
	(segment
		(start 286.968184 -202.470258)
		(end 286.968184 -202.216258)
		(width 0.12065)
		(layer "In5.Cu")
		(net "PHY_DRV_B_TO_SCC_B_21_DP")
	)
	(segment
		(start 287.558226 -201.626216)
		(end 288.387028 -201.626216)
		(width 0.12065)
		(layer "In5.Cu")
		(net "PHY_DRV_B_TO_SCC_B_21_DP")
	)
	(segment
		(start 286.436562 -202.69454)
		(end 286.743902 -202.69454)
		(width 0.12065)
		(layer "In5.Cu")
		(net "PHY_DRV_B_TO_SCC_B_21_DP")
	)
	(segment
		(start 288.387028 -201.626216)
		(end 336.426556 -193.840354)
		(width 0.12065)
		(layer "In5.Cu")
		(net "PHY_DRV_B_TO_SCC_B_21_DP")
	)
	(segment
		(start 417.596574 -132.437124)
		(end 417.331652 -132.437124)
		(width 0.12065)
		(layer "In5.Cu")
		(net "PHY_DRV_B_TO_SCC_B_21_DP")
	)
	(segment
		(start 410.117036 -145.984214)
		(end 417.79825 -134.149084)
		(width 0.12065)
		(layer "In5.Cu")
		(net "PHY_DRV_B_TO_SCC_B_21_DP")
	)
	(arc
		(start 417.79825 -132.6388)
		(mid 417.73918 -132.496194)
		(end 417.596574 -132.437124)
		(width 0.12065)
		(layer "In5.Cu")
		(net "PHY_DRV_B_TO_SCC_B_21_DP")
	)
	(arc
		(start 286.968184 -202.216258)
		(mid 287.141003 -201.799035)
		(end 287.558226 -201.626216)
		(width 0.12065)
		(layer "In5.Cu")
		(net "PHY_DRV_B_TO_SCC_B_21_DP")
	)
	(arc
		(start 286.743902 -202.69454)
		(mid 286.902493 -202.628849)
		(end 286.968184 -202.470258)
		(width 0.12065)
		(layer "In5.Cu")
		(net "PHY_DRV_B_TO_SCC_B_21_DP")
	)
	(segment
		(start 420.690548 -133.11505)
		(end 420.563548 -133.24205)
		(width 0.127)
		(layer "F.Cu")
		(net "PHY_DRV_B_TO_SCC_B_21_DN")
	)
	(segment
		(start 420.563548 -133.24205)
		(end 420.563548 -133.477)
		(width 0.127)
		(layer "F.Cu")
		(net "PHY_DRV_B_TO_SCC_B_21_DN")
	)
	(segment
		(start 422.025064 -133.11505)
		(end 420.690548 -133.11505)
		(width 0.127)
		(layer "F.Cu")
		(net "PHY_DRV_B_TO_SCC_B_21_DN")
	)
	(segment
		(start 420.464488 -133.57606)
		(end 418.368988 -133.57606)
		(width 0.127)
		(layer "F.Cu")
		(net "PHY_DRV_B_TO_SCC_B_21_DN")
	)
	(segment
		(start 418.368988 -133.57606)
		(end 418.112702 -133.319774)
		(width 0.127)
		(layer "F.Cu")
		(net "PHY_DRV_B_TO_SCC_B_21_DN")
	)
	(segment
		(start 420.563548 -133.477)
		(end 420.464488 -133.57606)
		(width 0.127)
		(layer "F.Cu")
		(net "PHY_DRV_B_TO_SCC_B_21_DN")
	)
	(segment
		(start 418.112702 -133.319774)
		(end 418.112702 -132.588)
		(width 0.127)
		(layer "F.Cu")
		(net "PHY_DRV_B_TO_SCC_B_21_DN")
	)
	(segment
		(start 418.263578 -132.437124)
		(end 418.601652 -132.437124)
		(width 0.127)
		(layer "F.Cu")
		(net "PHY_DRV_B_TO_SCC_B_21_DN")
	)
	(arc
		(start 418.112702 -132.588)
		(mid 418.156893 -132.481315)
		(end 418.263578 -132.437124)
		(width 0.127)
		(layer "F.Cu")
		(net "PHY_DRV_B_TO_SCC_B_21_DN")
	)
	(segment
		(start 404.773638 -149.855936)
		(end 405.054562 -149.915626)
		(width 0.12065)
		(layer "In5.Cu")
		(net "PHY_DRV_B_TO_SCC_B_21_DN")
	)
	(segment
		(start 405.054562 -149.915626)
		(end 405.358092 -149.718522)
		(width 0.12065)
		(layer "In5.Cu")
		(net "PHY_DRV_B_TO_SCC_B_21_DN")
	)
	(segment
		(start 287.558226 -201.962766)
		(end 288.414206 -201.962766)
		(width 0.12065)
		(layer "In5.Cu")
		(net "PHY_DRV_B_TO_SCC_B_21_DN")
	)
	(segment
		(start 287.304734 -202.470258)
		(end 287.304734 -202.216258)
		(width 0.12065)
		(layer "In5.Cu")
		(net "PHY_DRV_B_TO_SCC_B_21_DN")
	)
	(segment
		(start 406.950418 -148.684234)
		(end 407.253948 -148.48713)
		(width 0.12065)
		(layer "In5.Cu")
		(net "PHY_DRV_B_TO_SCC_B_21_DN")
	)
	(segment
		(start 405.721566 -149.24024)
		(end 406.00249 -149.29993)
		(width 0.12065)
		(layer "In5.Cu")
		(net "PHY_DRV_B_TO_SCC_B_21_DN")
	)
	(segment
		(start 405.418036 -149.437344)
		(end 405.721566 -149.24024)
		(width 0.12065)
		(layer "In5.Cu")
		(net "PHY_DRV_B_TO_SCC_B_21_DN")
	)
	(segment
		(start 418.1348 -134.248906)
		(end 418.1348 -132.6388)
		(width 0.12065)
		(layer "In5.Cu")
		(net "PHY_DRV_B_TO_SCC_B_21_DN")
	)
	(segment
		(start 410.360368 -146.227546)
		(end 418.1348 -134.248906)
		(width 0.12065)
		(layer "In5.Cu")
		(net "PHY_DRV_B_TO_SCC_B_21_DN")
	)
	(segment
		(start 407.253948 -148.48713)
		(end 407.313892 -148.206206)
		(width 0.12065)
		(layer "In5.Cu")
		(net "PHY_DRV_B_TO_SCC_B_21_DN")
	)
	(segment
		(start 406.365964 -148.821648)
		(end 406.669494 -148.624544)
		(width 0.12065)
		(layer "In5.Cu")
		(net "PHY_DRV_B_TO_SCC_B_21_DN")
	)
	(segment
		(start 405.358092 -149.718522)
		(end 405.418036 -149.437344)
		(width 0.12065)
		(layer "In5.Cu")
		(net "PHY_DRV_B_TO_SCC_B_21_DN")
	)
	(segment
		(start 418.336476 -132.437124)
		(end 418.601652 -132.437124)
		(width 0.12065)
		(layer "In5.Cu")
		(net "PHY_DRV_B_TO_SCC_B_21_DN")
	)
	(segment
		(start 406.669494 -148.624544)
		(end 406.950418 -148.684234)
		(width 0.12065)
		(layer "In5.Cu")
		(net "PHY_DRV_B_TO_SCC_B_21_DN")
	)
	(segment
		(start 406.00249 -149.29993)
		(end 406.30602 -149.102826)
		(width 0.12065)
		(layer "In5.Cu")
		(net "PHY_DRV_B_TO_SCC_B_21_DN")
	)
	(segment
		(start 406.30602 -149.102826)
		(end 406.365964 -148.821648)
		(width 0.12065)
		(layer "In5.Cu")
		(net "PHY_DRV_B_TO_SCC_B_21_DN")
	)
	(segment
		(start 407.313892 -148.206206)
		(end 410.360368 -146.227546)
		(width 0.12065)
		(layer "In5.Cu")
		(net "PHY_DRV_B_TO_SCC_B_21_DN")
	)
	(segment
		(start 288.414206 -201.962766)
		(end 336.550508 -194.16141)
		(width 0.12065)
		(layer "In5.Cu")
		(net "PHY_DRV_B_TO_SCC_B_21_DN")
	)
	(segment
		(start 287.83661 -202.69454)
		(end 287.529016 -202.69454)
		(width 0.12065)
		(layer "In5.Cu")
		(net "PHY_DRV_B_TO_SCC_B_21_DN")
	)
	(segment
		(start 336.550508 -194.16141)
		(end 404.773638 -149.855936)
		(width 0.12065)
		(layer "In5.Cu")
		(net "PHY_DRV_B_TO_SCC_B_21_DN")
	)
	(arc
		(start 287.304734 -202.216258)
		(mid 287.37898 -202.037012)
		(end 287.558226 -201.962766)
		(width 0.12065)
		(layer "In5.Cu")
		(net "PHY_DRV_B_TO_SCC_B_21_DN")
	)
	(arc
		(start 418.1348 -132.6388)
		(mid 418.19387 -132.496194)
		(end 418.336476 -132.437124)
		(width 0.12065)
		(layer "In5.Cu")
		(net "PHY_DRV_B_TO_SCC_B_21_DN")
	)
	(arc
		(start 287.529016 -202.69454)
		(mid 287.370425 -202.628849)
		(end 287.304734 -202.470258)
		(width 0.12065)
		(layer "In5.Cu")
		(net "PHY_DRV_B_TO_SCC_B_21_DN")
	)
	(segment
		(start 389.013446 -134.25805)
		(end 389.013446 -134.0231)
		(width 0.127)
		(layer "F.Cu")
		(net "PHY_DRV_B_TO_SCC_B_20_DP")
	)
	(segment
		(start 386.2705 -133.440932)
		(end 386.2705 -132.6007)
		(width 0.127)
		(layer "F.Cu")
		(net "PHY_DRV_B_TO_SCC_B_20_DP")
	)
	(segment
		(start 389.140446 -134.38505)
		(end 389.013446 -134.25805)
		(width 0.127)
		(layer "F.Cu")
		(net "PHY_DRV_B_TO_SCC_B_20_DP")
	)
	(segment
		(start 390.474962 -134.38505)
		(end 389.140446 -134.38505)
		(width 0.127)
		(layer "F.Cu")
		(net "PHY_DRV_B_TO_SCC_B_20_DP")
	)
	(segment
		(start 386.106924 -132.437124)
		(end 385.78155 -132.437124)
		(width 0.127)
		(layer "F.Cu")
		(net "PHY_DRV_B_TO_SCC_B_20_DP")
	)
	(segment
		(start 386.702808 -133.87324)
		(end 386.2705 -133.440932)
		(width 0.127)
		(layer "F.Cu")
		(net "PHY_DRV_B_TO_SCC_B_20_DP")
	)
	(segment
		(start 388.863586 -133.87324)
		(end 386.702808 -133.87324)
		(width 0.127)
		(layer "F.Cu")
		(net "PHY_DRV_B_TO_SCC_B_20_DP")
	)
	(segment
		(start 389.013446 -134.0231)
		(end 388.863586 -133.87324)
		(width 0.127)
		(layer "F.Cu")
		(net "PHY_DRV_B_TO_SCC_B_20_DP")
	)
	(arc
		(start 386.2705 -132.6007)
		(mid 386.22259 -132.485034)
		(end 386.106924 -132.437124)
		(width 0.127)
		(layer "F.Cu")
		(net "PHY_DRV_B_TO_SCC_B_20_DP")
	)
	(segment
		(start 291.212016 -199.826118)
		(end 334.0735 -192.705736)
		(width 0.12065)
		(layer "In5.Cu")
		(net "PHY_DRV_B_TO_SCC_B_20_DP")
	)
	(segment
		(start 386.106924 -132.437124)
		(end 385.78155 -132.437124)
		(width 0.12065)
		(layer "In5.Cu")
		(net "PHY_DRV_B_TO_SCC_B_20_DP")
	)
	(segment
		(start 286.558228 -199.826118)
		(end 291.212016 -199.826118)
		(width 0.12065)
		(layer "In5.Cu")
		(net "PHY_DRV_B_TO_SCC_B_20_DP")
	)
	(segment
		(start 334.0735 -192.705736)
		(end 358.911398 -176.576228)
		(width 0.12065)
		(layer "In5.Cu")
		(net "PHY_DRV_B_TO_SCC_B_20_DP")
	)
	(segment
		(start 358.911398 -176.576228)
		(end 386.190744 -134.554722)
		(width 0.12065)
		(layer "In5.Cu")
		(net "PHY_DRV_B_TO_SCC_B_20_DP")
	)
	(segment
		(start 386.190744 -134.554722)
		(end 386.248148 -134.285482)
		(width 0.12065)
		(layer "In5.Cu")
		(net "PHY_DRV_B_TO_SCC_B_20_DP")
	)
	(segment
		(start 386.248148 -134.285482)
		(end 386.248148 -132.578348)
		(width 0.12065)
		(layer "In5.Cu")
		(net "PHY_DRV_B_TO_SCC_B_20_DP")
	)
	(segment
		(start 285.968186 -200.67016)
		(end 285.968186 -200.41616)
		(width 0.12065)
		(layer "In5.Cu")
		(net "PHY_DRV_B_TO_SCC_B_20_DP")
	)
	(segment
		(start 285.436564 -200.894442)
		(end 285.743904 -200.894442)
		(width 0.12065)
		(layer "In5.Cu")
		(net "PHY_DRV_B_TO_SCC_B_20_DP")
	)
	(arc
		(start 386.248148 -132.578348)
		(mid 386.206784 -132.478488)
		(end 386.106924 -132.437124)
		(width 0.12065)
		(layer "In5.Cu")
		(net "PHY_DRV_B_TO_SCC_B_20_DP")
	)
	(arc
		(start 285.968186 -200.41616)
		(mid 286.141005 -199.998937)
		(end 286.558228 -199.826118)
		(width 0.12065)
		(layer "In5.Cu")
		(net "PHY_DRV_B_TO_SCC_B_20_DP")
	)
	(arc
		(start 285.743904 -200.894442)
		(mid 285.902495 -200.828751)
		(end 285.968186 -200.67016)
		(width 0.12065)
		(layer "In5.Cu")
		(net "PHY_DRV_B_TO_SCC_B_20_DP")
	)
	(segment
		(start 388.909306 -133.58114)
		(end 386.823966 -133.58114)
		(width 0.127)
		(layer "F.Cu")
		(net "PHY_DRV_B_TO_SCC_B_20_DN")
	)
	(segment
		(start 389.013446 -133.477)
		(end 388.909306 -133.58114)
		(width 0.127)
		(layer "F.Cu")
		(net "PHY_DRV_B_TO_SCC_B_20_DN")
	)
	(segment
		(start 386.5626 -133.319774)
		(end 386.5626 -132.6007)
		(width 0.127)
		(layer "F.Cu")
		(net "PHY_DRV_B_TO_SCC_B_20_DN")
	)
	(segment
		(start 386.823966 -133.58114)
		(end 386.5626 -133.319774)
		(width 0.127)
		(layer "F.Cu")
		(net "PHY_DRV_B_TO_SCC_B_20_DN")
	)
	(segment
		(start 389.013446 -133.24205)
		(end 389.013446 -133.477)
		(width 0.127)
		(layer "F.Cu")
		(net "PHY_DRV_B_TO_SCC_B_20_DN")
	)
	(segment
		(start 390.474962 -133.11505)
		(end 389.140446 -133.11505)
		(width 0.127)
		(layer "F.Cu")
		(net "PHY_DRV_B_TO_SCC_B_20_DN")
	)
	(segment
		(start 386.726176 -132.437124)
		(end 387.05155 -132.437124)
		(width 0.127)
		(layer "F.Cu")
		(net "PHY_DRV_B_TO_SCC_B_20_DN")
	)
	(segment
		(start 389.140446 -133.11505)
		(end 389.013446 -133.24205)
		(width 0.127)
		(layer "F.Cu")
		(net "PHY_DRV_B_TO_SCC_B_20_DN")
	)
	(arc
		(start 386.5626 -132.6007)
		(mid 386.61051 -132.485034)
		(end 386.726176 -132.437124)
		(width 0.127)
		(layer "F.Cu")
		(net "PHY_DRV_B_TO_SCC_B_20_DN")
	)
	(segment
		(start 368.10061 -163.412678)
		(end 368.04092 -163.1315)
		(width 0.12065)
		(layer "In5.Cu")
		(net "PHY_DRV_B_TO_SCC_B_20_DN")
	)
	(segment
		(start 334.19796 -193.026284)
		(end 359.15473 -176.81956)
		(width 0.12065)
		(layer "In5.Cu")
		(net "PHY_DRV_B_TO_SCC_B_20_DN")
	)
	(segment
		(start 367.622582 -163.775898)
		(end 367.903506 -163.716208)
		(width 0.12065)
		(layer "In5.Cu")
		(net "PHY_DRV_B_TO_SCC_B_20_DN")
	)
	(segment
		(start 367.288064 -164.664136)
		(end 367.485168 -164.360606)
		(width 0.12065)
		(layer "In5.Cu")
		(net "PHY_DRV_B_TO_SCC_B_20_DN")
	)
	(segment
		(start 286.836612 -200.894442)
		(end 286.529018 -200.894442)
		(width 0.12065)
		(layer "In5.Cu")
		(net "PHY_DRV_B_TO_SCC_B_20_DN")
	)
	(segment
		(start 367.903506 -163.716208)
		(end 368.10061 -163.412678)
		(width 0.12065)
		(layer "In5.Cu")
		(net "PHY_DRV_B_TO_SCC_B_20_DN")
	)
	(segment
		(start 367.006886 -164.72408)
		(end 367.00714 -164.72408)
		(width 0.12065)
		(layer "In5.Cu")
		(net "PHY_DRV_B_TO_SCC_B_20_DN")
	)
	(segment
		(start 367.485168 -164.360606)
		(end 367.425478 -164.079682)
		(width 0.12065)
		(layer "In5.Cu")
		(net "PHY_DRV_B_TO_SCC_B_20_DN")
	)
	(segment
		(start 368.238024 -162.82797)
		(end 368.518948 -162.768026)
		(width 0.12065)
		(layer "In5.Cu")
		(net "PHY_DRV_B_TO_SCC_B_20_DN")
	)
	(segment
		(start 286.304736 -200.67016)
		(end 286.304736 -200.41616)
		(width 0.12065)
		(layer "In5.Cu")
		(net "PHY_DRV_B_TO_SCC_B_20_DN")
	)
	(segment
		(start 286.558228 -200.162668)
		(end 291.239956 -200.162668)
		(width 0.12065)
		(layer "In5.Cu")
		(net "PHY_DRV_B_TO_SCC_B_20_DN")
	)
	(segment
		(start 386.584698 -134.321042)
		(end 386.584698 -132.578602)
		(width 0.12065)
		(layer "In5.Cu")
		(net "PHY_DRV_B_TO_SCC_B_20_DN")
	)
	(segment
		(start 368.656362 -162.183318)
		(end 386.506974 -134.685786)
		(width 0.12065)
		(layer "In5.Cu")
		(net "PHY_DRV_B_TO_SCC_B_20_DN")
	)
	(segment
		(start 368.518948 -162.768026)
		(end 368.716052 -162.464496)
		(width 0.12065)
		(layer "In5.Cu")
		(net "PHY_DRV_B_TO_SCC_B_20_DN")
	)
	(segment
		(start 368.716052 -162.464496)
		(end 368.656362 -162.183572)
		(width 0.12065)
		(layer "In5.Cu")
		(net "PHY_DRV_B_TO_SCC_B_20_DN")
	)
	(segment
		(start 368.656362 -162.183572)
		(end 368.656362 -162.183318)
		(width 0.12065)
		(layer "In5.Cu")
		(net "PHY_DRV_B_TO_SCC_B_20_DN")
	)
	(segment
		(start 386.506974 -134.685786)
		(end 386.584698 -134.321042)
		(width 0.12065)
		(layer "In5.Cu")
		(net "PHY_DRV_B_TO_SCC_B_20_DN")
	)
	(segment
		(start 367.00714 -164.72408)
		(end 367.288064 -164.664136)
		(width 0.12065)
		(layer "In5.Cu")
		(net "PHY_DRV_B_TO_SCC_B_20_DN")
	)
	(segment
		(start 359.15473 -176.81956)
		(end 367.006886 -164.72408)
		(width 0.12065)
		(layer "In5.Cu")
		(net "PHY_DRV_B_TO_SCC_B_20_DN")
	)
	(segment
		(start 367.425478 -164.079682)
		(end 367.622582 -163.775898)
		(width 0.12065)
		(layer "In5.Cu")
		(net "PHY_DRV_B_TO_SCC_B_20_DN")
	)
	(segment
		(start 291.239956 -200.162668)
		(end 334.19796 -193.026284)
		(width 0.12065)
		(layer "In5.Cu")
		(net "PHY_DRV_B_TO_SCC_B_20_DN")
	)
	(segment
		(start 386.726176 -132.437124)
		(end 387.05155 -132.437124)
		(width 0.12065)
		(layer "In5.Cu")
		(net "PHY_DRV_B_TO_SCC_B_20_DN")
	)
	(segment
		(start 368.04092 -163.1315)
		(end 368.238024 -162.82797)
		(width 0.12065)
		(layer "In5.Cu")
		(net "PHY_DRV_B_TO_SCC_B_20_DN")
	)
	(arc
		(start 286.529018 -200.894442)
		(mid 286.370427 -200.828751)
		(end 286.304736 -200.67016)
		(width 0.12065)
		(layer "In5.Cu")
		(net "PHY_DRV_B_TO_SCC_B_20_DN")
	)
	(arc
		(start 286.304736 -200.41616)
		(mid 286.378982 -200.236914)
		(end 286.558228 -200.162668)
		(width 0.12065)
		(layer "In5.Cu")
		(net "PHY_DRV_B_TO_SCC_B_20_DN")
	)
	(arc
		(start 386.584698 -132.578602)
		(mid 386.626136 -132.478562)
		(end 386.726176 -132.437124)
		(width 0.12065)
		(layer "In5.Cu")
		(net "PHY_DRV_B_TO_SCC_B_20_DN")
	)
	(segment
		(start 94.459552 -249.385074)
		(end 94.586552 -249.258074)
		(width 0.127)
		(layer "F.Cu")
		(net "PHY_DRV_B_TO_SCC_B_2_DP")
	)
	(segment
		(start 94.586552 -249.023124)
		(end 94.713552 -248.896124)
		(width 0.127)
		(layer "F.Cu")
		(net "PHY_DRV_B_TO_SCC_B_2_DP")
	)
	(segment
		(start 94.586552 -249.258074)
		(end 94.586552 -249.023124)
		(width 0.127)
		(layer "F.Cu")
		(net "PHY_DRV_B_TO_SCC_B_2_DP")
	)
	(segment
		(start 94.713552 -248.896124)
		(end 95.481902 -248.896124)
		(width 0.127)
		(layer "F.Cu")
		(net "PHY_DRV_B_TO_SCC_B_2_DP")
	)
	(segment
		(start 93.125036 -249.385074)
		(end 94.459552 -249.385074)
		(width 0.127)
		(layer "F.Cu")
		(net "PHY_DRV_B_TO_SCC_B_2_DP")
	)
	(segment
		(start 95.608902 -249.023124)
		(end 95.608902 -249.385074)
		(width 0.127)
		(layer "F.Cu")
		(net "PHY_DRV_B_TO_SCC_B_2_DP")
	)
	(arc
		(start 95.481902 -248.896124)
		(mid 95.571705 -248.933321)
		(end 95.608902 -249.023124)
		(width 0.127)
		(layer "F.Cu")
		(net "PHY_DRV_B_TO_SCC_B_2_DP")
	)
	(segment
		(start 143.881348 -239.064546)
		(end 143.527272 -239.139984)
		(width 0.12065)
		(layer "In5.Cu")
		(net "PHY_DRV_B_TO_SCC_B_2_DP")
	)
	(segment
		(start 258.546092 -232.562654)
		(end 251.773182 -234.002072)
		(width 0.12065)
		(layer "In5.Cu")
		(net "PHY_DRV_B_TO_SCC_B_2_DP")
	)
	(segment
		(start 190.414402 -228.931724)
		(end 144.045432 -238.811308)
		(width 0.12065)
		(layer "In5.Cu")
		(net "PHY_DRV_B_TO_SCC_B_2_DP")
	)
	(segment
		(start 142.401798 -239.37976)
		(end 142.148814 -239.215422)
		(width 0.12065)
		(layer "In5.Cu")
		(net "PHY_DRV_B_TO_SCC_B_2_DP")
	)
	(segment
		(start 141.276578 -239.619536)
		(end 141.02334 -239.455198)
		(width 0.12065)
		(layer "In5.Cu")
		(net "PHY_DRV_B_TO_SCC_B_2_DP")
	)
	(segment
		(start 222.08871 -235.728256)
		(end 190.414402 -228.931724)
		(width 0.12065)
		(layer "In5.Cu")
		(net "PHY_DRV_B_TO_SCC_B_2_DP")
	)
	(segment
		(start 285.436564 -233.294428)
		(end 285.805118 -233.294428)
		(width 0.12065)
		(layer "In5.Cu")
		(net "PHY_DRV_B_TO_SCC_B_2_DP")
	)
	(segment
		(start 142.148814 -239.215422)
		(end 141.794738 -239.29086)
		(width 0.12065)
		(layer "In5.Cu")
		(net "PHY_DRV_B_TO_SCC_B_2_DP")
	)
	(segment
		(start 95.608902 -249.038872)
		(end 95.608902 -249.385074)
		(width 0.12065)
		(layer "In5.Cu")
		(net "PHY_DRV_B_TO_SCC_B_2_DP")
	)
	(segment
		(start 141.02334 -239.455198)
		(end 96.6089 -248.918222)
		(width 0.12065)
		(layer "In5.Cu")
		(net "PHY_DRV_B_TO_SCC_B_2_DP")
	)
	(segment
		(start 285.968186 -233.13136)
		(end 285.968186 -232.90276)
		(width 0.12065)
		(layer "In5.Cu")
		(net "PHY_DRV_B_TO_SCC_B_2_DP")
	)
	(segment
		(start 143.274034 -238.975646)
		(end 142.920212 -239.051084)
		(width 0.12065)
		(layer "In5.Cu")
		(net "PHY_DRV_B_TO_SCC_B_2_DP")
	)
	(segment
		(start 141.630654 -239.544098)
		(end 141.276578 -239.619536)
		(width 0.12065)
		(layer "In5.Cu")
		(net "PHY_DRV_B_TO_SCC_B_2_DP")
	)
	(segment
		(start 141.794738 -239.29086)
		(end 141.630654 -239.544098)
		(width 0.12065)
		(layer "In5.Cu")
		(net "PHY_DRV_B_TO_SCC_B_2_DP")
	)
	(segment
		(start 143.527272 -239.139984)
		(end 143.274034 -238.975646)
		(width 0.12065)
		(layer "In5.Cu")
		(net "PHY_DRV_B_TO_SCC_B_2_DP")
	)
	(segment
		(start 240.991136 -231.709976)
		(end 222.08871 -235.728256)
		(width 0.12065)
		(layer "In5.Cu")
		(net "PHY_DRV_B_TO_SCC_B_2_DP")
	)
	(segment
		(start 142.920212 -239.051084)
		(end 142.755874 -239.304322)
		(width 0.12065)
		(layer "In5.Cu")
		(net "PHY_DRV_B_TO_SCC_B_2_DP")
	)
	(segment
		(start 251.773182 -234.002072)
		(end 240.991136 -231.709976)
		(width 0.12065)
		(layer "In5.Cu")
		(net "PHY_DRV_B_TO_SCC_B_2_DP")
	)
	(segment
		(start 285.62808 -232.562654)
		(end 258.546092 -232.562654)
		(width 0.12065)
		(layer "In5.Cu")
		(net "PHY_DRV_B_TO_SCC_B_2_DP")
	)
	(segment
		(start 96.6089 -248.918222)
		(end 95.729552 -248.918222)
		(width 0.12065)
		(layer "In5.Cu")
		(net "PHY_DRV_B_TO_SCC_B_2_DP")
	)
	(segment
		(start 142.755874 -239.304322)
		(end 142.401798 -239.37976)
		(width 0.12065)
		(layer "In5.Cu")
		(net "PHY_DRV_B_TO_SCC_B_2_DP")
	)
	(segment
		(start 144.045432 -238.811308)
		(end 143.881348 -239.064546)
		(width 0.12065)
		(layer "In5.Cu")
		(net "PHY_DRV_B_TO_SCC_B_2_DP")
	)
	(arc
		(start 285.805118 -233.294428)
		(mid 285.920424 -233.246666)
		(end 285.968186 -233.13136)
		(width 0.12065)
		(layer "In5.Cu")
		(net "PHY_DRV_B_TO_SCC_B_2_DP")
	)
	(arc
		(start 285.968186 -232.90276)
		(mid 285.868571 -232.662269)
		(end 285.62808 -232.562654)
		(width 0.12065)
		(layer "In5.Cu")
		(net "PHY_DRV_B_TO_SCC_B_2_DP")
	)
	(arc
		(start 95.729552 -248.918222)
		(mid 95.64424 -248.95356)
		(end 95.608902 -249.038872)
		(width 0.12065)
		(layer "In5.Cu")
		(net "PHY_DRV_B_TO_SCC_B_2_DP")
	)
	(segment
		(start 95.608902 -248.477024)
		(end 95.608902 -248.115074)
		(width 0.127)
		(layer "F.Cu")
		(net "PHY_DRV_B_TO_SCC_B_2_DN")
	)
	(segment
		(start 94.713552 -248.604024)
		(end 95.481902 -248.604024)
		(width 0.127)
		(layer "F.Cu")
		(net "PHY_DRV_B_TO_SCC_B_2_DN")
	)
	(segment
		(start 93.125036 -248.115074)
		(end 94.459552 -248.115074)
		(width 0.127)
		(layer "F.Cu")
		(net "PHY_DRV_B_TO_SCC_B_2_DN")
	)
	(segment
		(start 94.459552 -248.115074)
		(end 94.586552 -248.242074)
		(width 0.127)
		(layer "F.Cu")
		(net "PHY_DRV_B_TO_SCC_B_2_DN")
	)
	(segment
		(start 94.586552 -248.242074)
		(end 94.586552 -248.477024)
		(width 0.127)
		(layer "F.Cu")
		(net "PHY_DRV_B_TO_SCC_B_2_DN")
	)
	(segment
		(start 94.586552 -248.477024)
		(end 94.713552 -248.604024)
		(width 0.127)
		(layer "F.Cu")
		(net "PHY_DRV_B_TO_SCC_B_2_DN")
	)
	(arc
		(start 95.481902 -248.604024)
		(mid 95.571705 -248.566827)
		(end 95.608902 -248.477024)
		(width 0.127)
		(layer "F.Cu")
		(net "PHY_DRV_B_TO_SCC_B_2_DN")
	)
	(segment
		(start 251.773182 -233.657902)
		(end 240.991136 -231.365806)
		(width 0.12065)
		(layer "In5.Cu")
		(net "PHY_DRV_B_TO_SCC_B_2_DN")
	)
	(segment
		(start 286.304736 -233.13136)
		(end 286.304736 -232.90276)
		(width 0.12065)
		(layer "In5.Cu")
		(net "PHY_DRV_B_TO_SCC_B_2_DN")
	)
	(segment
		(start 286.836612 -233.294428)
		(end 286.467804 -233.294428)
		(width 0.12065)
		(layer "In5.Cu")
		(net "PHY_DRV_B_TO_SCC_B_2_DN")
	)
	(segment
		(start 285.62808 -232.226104)
		(end 258.510532 -232.226104)
		(width 0.12065)
		(layer "In5.Cu")
		(net "PHY_DRV_B_TO_SCC_B_2_DN")
	)
	(segment
		(start 96.57334 -248.581672)
		(end 95.729552 -248.581672)
		(width 0.12065)
		(layer "In5.Cu")
		(net "PHY_DRV_B_TO_SCC_B_2_DN")
	)
	(segment
		(start 258.510532 -232.226104)
		(end 251.773182 -233.657902)
		(width 0.12065)
		(layer "In5.Cu")
		(net "PHY_DRV_B_TO_SCC_B_2_DN")
	)
	(segment
		(start 95.608902 -248.461022)
		(end 95.608902 -248.115074)
		(width 0.12065)
		(layer "In5.Cu")
		(net "PHY_DRV_B_TO_SCC_B_2_DN")
	)
	(segment
		(start 240.991136 -231.365806)
		(end 222.088964 -235.384086)
		(width 0.12065)
		(layer "In5.Cu")
		(net "PHY_DRV_B_TO_SCC_B_2_DN")
	)
	(segment
		(start 222.088964 -235.384086)
		(end 190.414656 -228.587554)
		(width 0.12065)
		(layer "In5.Cu")
		(net "PHY_DRV_B_TO_SCC_B_2_DN")
	)
	(segment
		(start 190.414656 -228.587554)
		(end 96.57334 -248.581672)
		(width 0.12065)
		(layer "In5.Cu")
		(net "PHY_DRV_B_TO_SCC_B_2_DN")
	)
	(arc
		(start 286.467804 -233.294428)
		(mid 286.352498 -233.246666)
		(end 286.304736 -233.13136)
		(width 0.12065)
		(layer "In5.Cu")
		(net "PHY_DRV_B_TO_SCC_B_2_DN")
	)
	(arc
		(start 95.729552 -248.581672)
		(mid 95.64424 -248.546334)
		(end 95.608902 -248.461022)
		(width 0.12065)
		(layer "In5.Cu")
		(net "PHY_DRV_B_TO_SCC_B_2_DN")
	)
	(arc
		(start 286.304736 -232.90276)
		(mid 286.106548 -232.424292)
		(end 285.62808 -232.226104)
		(width 0.12065)
		(layer "In5.Cu")
		(net "PHY_DRV_B_TO_SCC_B_2_DN")
	)
	(segment
		(start 357.362252 -133.893052)
		(end 355.172772 -133.893052)
		(width 0.127)
		(layer "F.Cu")
		(net "PHY_DRV_B_TO_SCC_B_19_DP")
	)
	(segment
		(start 357.463598 -133.994398)
		(end 357.362252 -133.893052)
		(width 0.127)
		(layer "F.Cu")
		(net "PHY_DRV_B_TO_SCC_B_19_DP")
	)
	(segment
		(start 357.590598 -134.38505)
		(end 357.463598 -134.25805)
		(width 0.127)
		(layer "F.Cu")
		(net "PHY_DRV_B_TO_SCC_B_19_DP")
	)
	(segment
		(start 358.925114 -134.38505)
		(end 357.590598 -134.38505)
		(width 0.127)
		(layer "F.Cu")
		(net "PHY_DRV_B_TO_SCC_B_19_DP")
	)
	(segment
		(start 357.463598 -134.25805)
		(end 357.463598 -133.994398)
		(width 0.127)
		(layer "F.Cu")
		(net "PHY_DRV_B_TO_SCC_B_19_DP")
	)
	(segment
		(start 354.720652 -133.440932)
		(end 354.720652 -132.623052)
		(width 0.127)
		(layer "F.Cu")
		(net "PHY_DRV_B_TO_SCC_B_19_DP")
	)
	(segment
		(start 354.534724 -132.437124)
		(end 354.231702 -132.437124)
		(width 0.127)
		(layer "F.Cu")
		(net "PHY_DRV_B_TO_SCC_B_19_DP")
	)
	(segment
		(start 355.172772 -133.893052)
		(end 354.720652 -133.440932)
		(width 0.127)
		(layer "F.Cu")
		(net "PHY_DRV_B_TO_SCC_B_19_DP")
	)
	(arc
		(start 354.720652 -132.623052)
		(mid 354.666195 -132.491581)
		(end 354.534724 -132.437124)
		(width 0.127)
		(layer "F.Cu")
		(net "PHY_DRV_B_TO_SCC_B_19_DP")
	)
	(segment
		(start 354.534724 -132.437124)
		(end 354.231702 -132.437124)
		(width 0.12065)
		(layer "In5.Cu")
		(net "PHY_DRV_B_TO_SCC_B_19_DP")
	)
	(segment
		(start 286.968184 -198.870062)
		(end 286.968184 -198.616062)
		(width 0.12065)
		(layer "In5.Cu")
		(net "PHY_DRV_B_TO_SCC_B_19_DP")
	)
	(segment
		(start 286.436562 -199.094344)
		(end 286.743902 -199.094344)
		(width 0.12065)
		(layer "In5.Cu")
		(net "PHY_DRV_B_TO_SCC_B_19_DP")
	)
	(segment
		(start 311.75706 -190.059564)
		(end 313.66968 -188.681868)
		(width 0.12065)
		(layer "In5.Cu")
		(net "PHY_DRV_B_TO_SCC_B_19_DP")
	)
	(segment
		(start 354.6983 -133.308344)
		(end 354.6983 -132.6007)
		(width 0.12065)
		(layer "In5.Cu")
		(net "PHY_DRV_B_TO_SCC_B_19_DP")
	)
	(segment
		(start 313.66968 -188.681868)
		(end 354.6983 -133.308344)
		(width 0.12065)
		(layer "In5.Cu")
		(net "PHY_DRV_B_TO_SCC_B_19_DP")
	)
	(segment
		(start 289.458146 -198.02602)
		(end 311.75706 -190.059564)
		(width 0.12065)
		(layer "In5.Cu")
		(net "PHY_DRV_B_TO_SCC_B_19_DP")
	)
	(segment
		(start 287.558226 -198.02602)
		(end 289.458146 -198.02602)
		(width 0.12065)
		(layer "In5.Cu")
		(net "PHY_DRV_B_TO_SCC_B_19_DP")
	)
	(arc
		(start 354.6983 -132.6007)
		(mid 354.65039 -132.485034)
		(end 354.534724 -132.437124)
		(width 0.12065)
		(layer "In5.Cu")
		(net "PHY_DRV_B_TO_SCC_B_19_DP")
	)
	(arc
		(start 286.743902 -199.094344)
		(mid 286.902493 -199.028653)
		(end 286.968184 -198.870062)
		(width 0.12065)
		(layer "In5.Cu")
		(net "PHY_DRV_B_TO_SCC_B_19_DP")
	)
	(arc
		(start 286.968184 -198.616062)
		(mid 287.141003 -198.198839)
		(end 287.558226 -198.02602)
		(width 0.12065)
		(layer "In5.Cu")
		(net "PHY_DRV_B_TO_SCC_B_19_DP")
	)
	(segment
		(start 357.590598 -133.11505)
		(end 357.463598 -133.24205)
		(width 0.127)
		(layer "F.Cu")
		(net "PHY_DRV_B_TO_SCC_B_19_DN")
	)
	(segment
		(start 357.463598 -133.477)
		(end 357.339646 -133.600952)
		(width 0.127)
		(layer "F.Cu")
		(net "PHY_DRV_B_TO_SCC_B_19_DN")
	)
	(segment
		(start 355.19868 -132.437124)
		(end 355.501702 -132.437124)
		(width 0.127)
		(layer "F.Cu")
		(net "PHY_DRV_B_TO_SCC_B_19_DN")
	)
	(segment
		(start 357.463598 -133.24205)
		(end 357.463598 -133.477)
		(width 0.127)
		(layer "F.Cu")
		(net "PHY_DRV_B_TO_SCC_B_19_DN")
	)
	(segment
		(start 358.925114 -133.11505)
		(end 357.590598 -133.11505)
		(width 0.127)
		(layer "F.Cu")
		(net "PHY_DRV_B_TO_SCC_B_19_DN")
	)
	(segment
		(start 355.012752 -133.319774)
		(end 355.012752 -132.623052)
		(width 0.127)
		(layer "F.Cu")
		(net "PHY_DRV_B_TO_SCC_B_19_DN")
	)
	(segment
		(start 357.339646 -133.600952)
		(end 355.29393 -133.600952)
		(width 0.127)
		(layer "F.Cu")
		(net "PHY_DRV_B_TO_SCC_B_19_DN")
	)
	(segment
		(start 355.29393 -133.600952)
		(end 355.012752 -133.319774)
		(width 0.127)
		(layer "F.Cu")
		(net "PHY_DRV_B_TO_SCC_B_19_DN")
	)
	(arc
		(start 355.012752 -132.623052)
		(mid 355.067209 -132.491581)
		(end 355.19868 -132.437124)
		(width 0.127)
		(layer "F.Cu")
		(net "PHY_DRV_B_TO_SCC_B_19_DN")
	)
	(segment
		(start 344.717878 -147.685252)
		(end 344.93327 -147.394422)
		(width 0.12065)
		(layer "In5.Cu")
		(net "PHY_DRV_B_TO_SCC_B_19_DN")
	)
	(segment
		(start 343.587578 -149.210776)
		(end 343.54516 -148.92655)
		(width 0.12065)
		(layer "In5.Cu")
		(net "PHY_DRV_B_TO_SCC_B_19_DN")
	)
	(segment
		(start 344.433652 -147.727416)
		(end 344.717878 -147.685252)
		(width 0.12065)
		(layer "In5.Cu")
		(net "PHY_DRV_B_TO_SCC_B_19_DN")
	)
	(segment
		(start 344.93327 -147.394422)
		(end 344.891106 -147.110196)
		(width 0.12065)
		(layer "In5.Cu")
		(net "PHY_DRV_B_TO_SCC_B_19_DN")
	)
	(segment
		(start 287.304734 -198.870062)
		(end 287.304734 -198.616062)
		(width 0.12065)
		(layer "In5.Cu")
		(net "PHY_DRV_B_TO_SCC_B_19_DN")
	)
	(segment
		(start 355.03485 -133.419596)
		(end 355.03485 -132.600954)
		(width 0.12065)
		(layer "In5.Cu")
		(net "PHY_DRV_B_TO_SCC_B_19_DN")
	)
	(segment
		(start 344.045032 -148.593302)
		(end 344.260424 -148.302472)
		(width 0.12065)
		(layer "In5.Cu")
		(net "PHY_DRV_B_TO_SCC_B_19_DN")
	)
	(segment
		(start 344.260424 -148.302472)
		(end 344.21826 -148.018246)
		(width 0.12065)
		(layer "In5.Cu")
		(net "PHY_DRV_B_TO_SCC_B_19_DN")
	)
	(segment
		(start 313.908948 -188.924438)
		(end 343.087706 -149.54377)
		(width 0.12065)
		(layer "In5.Cu")
		(net "PHY_DRV_B_TO_SCC_B_19_DN")
	)
	(segment
		(start 287.558226 -198.36257)
		(end 289.516566 -198.36257)
		(width 0.12065)
		(layer "In5.Cu")
		(net "PHY_DRV_B_TO_SCC_B_19_DN")
	)
	(segment
		(start 311.915048 -190.360554)
		(end 313.908948 -188.924438)
		(width 0.12065)
		(layer "In5.Cu")
		(net "PHY_DRV_B_TO_SCC_B_19_DN")
	)
	(segment
		(start 344.21826 -148.018246)
		(end 344.433652 -147.727416)
		(width 0.12065)
		(layer "In5.Cu")
		(net "PHY_DRV_B_TO_SCC_B_19_DN")
	)
	(segment
		(start 343.760806 -148.63572)
		(end 344.045032 -148.593302)
		(width 0.12065)
		(layer "In5.Cu")
		(net "PHY_DRV_B_TO_SCC_B_19_DN")
	)
	(segment
		(start 355.19868 -132.437124)
		(end 355.501702 -132.437124)
		(width 0.12065)
		(layer "In5.Cu")
		(net "PHY_DRV_B_TO_SCC_B_19_DN")
	)
	(segment
		(start 287.83661 -199.094344)
		(end 287.529016 -199.094344)
		(width 0.12065)
		(layer "In5.Cu")
		(net "PHY_DRV_B_TO_SCC_B_19_DN")
	)
	(segment
		(start 343.372186 -149.501606)
		(end 343.587578 -149.210776)
		(width 0.12065)
		(layer "In5.Cu")
		(net "PHY_DRV_B_TO_SCC_B_19_DN")
	)
	(segment
		(start 289.516566 -198.36257)
		(end 311.915048 -190.360554)
		(width 0.12065)
		(layer "In5.Cu")
		(net "PHY_DRV_B_TO_SCC_B_19_DN")
	)
	(segment
		(start 343.54516 -148.92655)
		(end 343.760806 -148.63572)
		(width 0.12065)
		(layer "In5.Cu")
		(net "PHY_DRV_B_TO_SCC_B_19_DN")
	)
	(segment
		(start 343.087706 -149.54377)
		(end 343.372186 -149.501606)
		(width 0.12065)
		(layer "In5.Cu")
		(net "PHY_DRV_B_TO_SCC_B_19_DN")
	)
	(segment
		(start 344.891106 -147.110196)
		(end 355.03485 -133.419596)
		(width 0.12065)
		(layer "In5.Cu")
		(net "PHY_DRV_B_TO_SCC_B_19_DN")
	)
	(arc
		(start 355.03485 -132.600954)
		(mid 355.082835 -132.485109)
		(end 355.19868 -132.437124)
		(width 0.12065)
		(layer "In5.Cu")
		(net "PHY_DRV_B_TO_SCC_B_19_DN")
	)
	(arc
		(start 287.304734 -198.616062)
		(mid 287.37898 -198.436816)
		(end 287.558226 -198.36257)
		(width 0.12065)
		(layer "In5.Cu")
		(net "PHY_DRV_B_TO_SCC_B_19_DN")
	)
	(arc
		(start 287.529016 -199.094344)
		(mid 287.370425 -199.028653)
		(end 287.304734 -198.870062)
		(width 0.12065)
		(layer "In5.Cu")
		(net "PHY_DRV_B_TO_SCC_B_19_DN")
	)
	(segment
		(start 323.17055 -133.440932)
		(end 323.17055 -132.61975)
		(width 0.127)
		(layer "F.Cu")
		(net "PHY_DRV_B_TO_SCC_B_18_DP")
	)
	(segment
		(start 327.375012 -134.38505)
		(end 326.02805 -134.38505)
		(width 0.127)
		(layer "F.Cu")
		(net "PHY_DRV_B_TO_SCC_B_18_DP")
	)
	(segment
		(start 322.987924 -132.437124)
		(end 322.6816 -132.437124)
		(width 0.127)
		(layer "F.Cu")
		(net "PHY_DRV_B_TO_SCC_B_18_DP")
	)
	(segment
		(start 325.786496 -133.8961)
		(end 323.625718 -133.8961)
		(width 0.127)
		(layer "F.Cu")
		(net "PHY_DRV_B_TO_SCC_B_18_DP")
	)
	(segment
		(start 323.625718 -133.8961)
		(end 323.17055 -133.440932)
		(width 0.127)
		(layer "F.Cu")
		(net "PHY_DRV_B_TO_SCC_B_18_DP")
	)
	(segment
		(start 325.913496 -134.270496)
		(end 325.913496 -134.0231)
		(width 0.127)
		(layer "F.Cu")
		(net "PHY_DRV_B_TO_SCC_B_18_DP")
	)
	(segment
		(start 326.02805 -134.38505)
		(end 325.913496 -134.270496)
		(width 0.127)
		(layer "F.Cu")
		(net "PHY_DRV_B_TO_SCC_B_18_DP")
	)
	(segment
		(start 325.913496 -134.0231)
		(end 325.786496 -133.8961)
		(width 0.127)
		(layer "F.Cu")
		(net "PHY_DRV_B_TO_SCC_B_18_DP")
	)
	(arc
		(start 323.17055 -132.61975)
		(mid 323.11706 -132.490614)
		(end 322.987924 -132.437124)
		(width 0.127)
		(layer "F.Cu")
		(net "PHY_DRV_B_TO_SCC_B_18_DP")
	)
	(segment
		(start 323.148198 -135.431784)
		(end 323.148198 -132.597398)
		(width 0.12065)
		(layer "In5.Cu")
		(net "PHY_DRV_B_TO_SCC_B_18_DP")
	)
	(segment
		(start 322.987924 -132.437124)
		(end 322.6816 -132.437124)
		(width 0.12065)
		(layer "In5.Cu")
		(net "PHY_DRV_B_TO_SCC_B_18_DP")
	)
	(segment
		(start 295.247314 -193.453004)
		(end 314.526676 -162.395408)
		(width 0.12065)
		(layer "In5.Cu")
		(net "PHY_DRV_B_TO_SCC_B_18_DP")
	)
	(segment
		(start 285.968186 -197.070218)
		(end 285.968186 -196.816218)
		(width 0.12065)
		(layer "In5.Cu")
		(net "PHY_DRV_B_TO_SCC_B_18_DP")
	)
	(segment
		(start 314.526676 -162.395408)
		(end 323.148198 -135.431784)
		(width 0.12065)
		(layer "In5.Cu")
		(net "PHY_DRV_B_TO_SCC_B_18_DP")
	)
	(segment
		(start 289.887406 -196.226176)
		(end 295.247314 -193.453004)
		(width 0.12065)
		(layer "In5.Cu")
		(net "PHY_DRV_B_TO_SCC_B_18_DP")
	)
	(segment
		(start 285.436564 -197.2945)
		(end 285.743904 -197.2945)
		(width 0.12065)
		(layer "In5.Cu")
		(net "PHY_DRV_B_TO_SCC_B_18_DP")
	)
	(segment
		(start 286.558228 -196.226176)
		(end 289.887406 -196.226176)
		(width 0.12065)
		(layer "In5.Cu")
		(net "PHY_DRV_B_TO_SCC_B_18_DP")
	)
	(arc
		(start 323.148198 -132.597398)
		(mid 323.101255 -132.484067)
		(end 322.987924 -132.437124)
		(width 0.12065)
		(layer "In5.Cu")
		(net "PHY_DRV_B_TO_SCC_B_18_DP")
	)
	(arc
		(start 285.743904 -197.2945)
		(mid 285.902495 -197.228809)
		(end 285.968186 -197.070218)
		(width 0.12065)
		(layer "In5.Cu")
		(net "PHY_DRV_B_TO_SCC_B_18_DP")
	)
	(arc
		(start 285.968186 -196.816218)
		(mid 286.141005 -196.398995)
		(end 286.558228 -196.226176)
		(width 0.12065)
		(layer "In5.Cu")
		(net "PHY_DRV_B_TO_SCC_B_18_DP")
	)
	(segment
		(start 327.375012 -133.11505)
		(end 326.040496 -133.11505)
		(width 0.127)
		(layer "F.Cu")
		(net "PHY_DRV_B_TO_SCC_B_18_DN")
	)
	(segment
		(start 326.040496 -133.11505)
		(end 325.913496 -133.24205)
		(width 0.127)
		(layer "F.Cu")
		(net "PHY_DRV_B_TO_SCC_B_18_DN")
	)
	(segment
		(start 323.46265 -133.319774)
		(end 323.46265 -132.61975)
		(width 0.127)
		(layer "F.Cu")
		(net "PHY_DRV_B_TO_SCC_B_18_DN")
	)
	(segment
		(start 325.913496 -133.24205)
		(end 325.913496 -133.445504)
		(width 0.127)
		(layer "F.Cu")
		(net "PHY_DRV_B_TO_SCC_B_18_DN")
	)
	(segment
		(start 323.645276 -132.437124)
		(end 323.9516 -132.437124)
		(width 0.127)
		(layer "F.Cu")
		(net "PHY_DRV_B_TO_SCC_B_18_DN")
	)
	(segment
		(start 325.913496 -133.445504)
		(end 325.755 -133.604)
		(width 0.127)
		(layer "F.Cu")
		(net "PHY_DRV_B_TO_SCC_B_18_DN")
	)
	(segment
		(start 323.746876 -133.604)
		(end 323.46265 -133.319774)
		(width 0.127)
		(layer "F.Cu")
		(net "PHY_DRV_B_TO_SCC_B_18_DN")
	)
	(segment
		(start 325.755 -133.604)
		(end 323.746876 -133.604)
		(width 0.127)
		(layer "F.Cu")
		(net "PHY_DRV_B_TO_SCC_B_18_DN")
	)
	(arc
		(start 323.46265 -132.61975)
		(mid 323.51614 -132.490614)
		(end 323.645276 -132.437124)
		(width 0.127)
		(layer "F.Cu")
		(net "PHY_DRV_B_TO_SCC_B_18_DN")
	)
	(segment
		(start 319.403476 -148.915882)
		(end 319.513712 -148.571204)
		(width 0.12065)
		(layer "In5.Cu")
		(net "PHY_DRV_B_TO_SCC_B_18_DN")
	)
	(segment
		(start 319.037716 -149.392386)
		(end 319.147952 -149.047708)
		(width 0.12065)
		(layer "In5.Cu")
		(net "PHY_DRV_B_TO_SCC_B_18_DN")
	)
	(segment
		(start 318.803782 -150.12416)
		(end 319.059306 -149.992588)
		(width 0.12065)
		(layer "In5.Cu")
		(net "PHY_DRV_B_TO_SCC_B_18_DN")
	)
	(segment
		(start 319.169542 -149.64791)
		(end 319.037716 -149.392386)
		(width 0.12065)
		(layer "In5.Cu")
		(net "PHY_DRV_B_TO_SCC_B_18_DN")
	)
	(segment
		(start 318.459612 -151.200866)
		(end 318.715136 -151.06904)
		(width 0.12065)
		(layer "In5.Cu")
		(net "PHY_DRV_B_TO_SCC_B_18_DN")
	)
	(segment
		(start 323.484748 -135.484362)
		(end 323.484748 -132.597652)
		(width 0.12065)
		(layer "In5.Cu")
		(net "PHY_DRV_B_TO_SCC_B_18_DN")
	)
	(segment
		(start 319.147952 -149.047708)
		(end 319.403476 -148.915882)
		(width 0.12065)
		(layer "In5.Cu")
		(net "PHY_DRV_B_TO_SCC_B_18_DN")
	)
	(segment
		(start 286.304736 -197.070218)
		(end 286.304736 -196.816218)
		(width 0.12065)
		(layer "In5.Cu")
		(net "PHY_DRV_B_TO_SCC_B_18_DN")
	)
	(segment
		(start 295.48455 -193.709544)
		(end 314.834778 -162.537648)
		(width 0.12065)
		(layer "In5.Cu")
		(net "PHY_DRV_B_TO_SCC_B_18_DN")
	)
	(segment
		(start 319.38214 -148.31568)
		(end 323.484748 -135.484362)
		(width 0.12065)
		(layer "In5.Cu")
		(net "PHY_DRV_B_TO_SCC_B_18_DN")
	)
	(segment
		(start 318.715136 -151.06904)
		(end 318.825118 -150.724362)
		(width 0.12065)
		(layer "In5.Cu")
		(net "PHY_DRV_B_TO_SCC_B_18_DN")
	)
	(segment
		(start 286.558228 -196.562726)
		(end 289.969448 -196.562726)
		(width 0.12065)
		(layer "In5.Cu")
		(net "PHY_DRV_B_TO_SCC_B_18_DN")
	)
	(segment
		(start 318.693546 -150.469092)
		(end 318.803782 -150.12416)
		(width 0.12065)
		(layer "In5.Cu")
		(net "PHY_DRV_B_TO_SCC_B_18_DN")
	)
	(segment
		(start 289.969448 -196.562726)
		(end 295.48455 -193.709544)
		(width 0.12065)
		(layer "In5.Cu")
		(net "PHY_DRV_B_TO_SCC_B_18_DN")
	)
	(segment
		(start 314.834778 -162.537648)
		(end 318.459612 -151.200866)
		(width 0.12065)
		(layer "In5.Cu")
		(net "PHY_DRV_B_TO_SCC_B_18_DN")
	)
	(segment
		(start 319.513712 -148.571204)
		(end 319.38214 -148.31568)
		(width 0.12065)
		(layer "In5.Cu")
		(net "PHY_DRV_B_TO_SCC_B_18_DN")
	)
	(segment
		(start 319.059306 -149.992588)
		(end 319.169542 -149.64791)
		(width 0.12065)
		(layer "In5.Cu")
		(net "PHY_DRV_B_TO_SCC_B_18_DN")
	)
	(segment
		(start 323.645276 -132.437124)
		(end 323.9516 -132.437124)
		(width 0.12065)
		(layer "In5.Cu")
		(net "PHY_DRV_B_TO_SCC_B_18_DN")
	)
	(segment
		(start 318.825118 -150.724362)
		(end 318.693546 -150.469092)
		(width 0.12065)
		(layer "In5.Cu")
		(net "PHY_DRV_B_TO_SCC_B_18_DN")
	)
	(segment
		(start 286.836612 -197.2945)
		(end 286.529018 -197.2945)
		(width 0.12065)
		(layer "In5.Cu")
		(net "PHY_DRV_B_TO_SCC_B_18_DN")
	)
	(arc
		(start 286.304736 -196.816218)
		(mid 286.378982 -196.636972)
		(end 286.558228 -196.562726)
		(width 0.12065)
		(layer "In5.Cu")
		(net "PHY_DRV_B_TO_SCC_B_18_DN")
	)
	(arc
		(start 323.484748 -132.597652)
		(mid 323.531766 -132.484142)
		(end 323.645276 -132.437124)
		(width 0.12065)
		(layer "In5.Cu")
		(net "PHY_DRV_B_TO_SCC_B_18_DN")
	)
	(arc
		(start 286.529018 -197.2945)
		(mid 286.370427 -197.228809)
		(end 286.304736 -197.070218)
		(width 0.12065)
		(layer "In5.Cu")
		(net "PHY_DRV_B_TO_SCC_B_18_DN")
	)
	(segment
		(start 189.109604 -134.38505)
		(end 189.236604 -134.25805)
		(width 0.127)
		(layer "F.Cu")
		(net "PHY_DRV_B_TO_SCC_B_17_DP")
	)
	(segment
		(start 189.363604 -133.8961)
		(end 190.131954 -133.8961)
		(width 0.127)
		(layer "F.Cu")
		(net "PHY_DRV_B_TO_SCC_B_17_DP")
	)
	(segment
		(start 187.775088 -134.38505)
		(end 189.109604 -134.38505)
		(width 0.127)
		(layer "F.Cu")
		(net "PHY_DRV_B_TO_SCC_B_17_DP")
	)
	(segment
		(start 189.236604 -134.25805)
		(end 189.236604 -134.0231)
		(width 0.127)
		(layer "F.Cu")
		(net "PHY_DRV_B_TO_SCC_B_17_DP")
	)
	(segment
		(start 190.258954 -134.0231)
		(end 190.258954 -134.38505)
		(width 0.127)
		(layer "F.Cu")
		(net "PHY_DRV_B_TO_SCC_B_17_DP")
	)
	(segment
		(start 189.236604 -134.0231)
		(end 189.363604 -133.8961)
		(width 0.127)
		(layer "F.Cu")
		(net "PHY_DRV_B_TO_SCC_B_17_DP")
	)
	(arc
		(start 190.131954 -133.8961)
		(mid 190.221757 -133.933297)
		(end 190.258954 -134.0231)
		(width 0.127)
		(layer "F.Cu")
		(net "PHY_DRV_B_TO_SCC_B_17_DP")
	)
	(segment
		(start 199.183752 -136.010142)
		(end 198.83374 -135.918194)
		(width 0.12065)
		(layer "In5.Cu")
		(net "PHY_DRV_B_TO_SCC_B_17_DP")
	)
	(segment
		(start 278.006556 -207.362806)
		(end 277.44928 -207.084676)
		(width 0.12065)
		(layer "In5.Cu")
		(net "PHY_DRV_B_TO_SCC_B_17_DP")
	)
	(segment
		(start 198.83374 -135.918194)
		(end 198.681594 -135.657844)
		(width 0.12065)
		(layer "In5.Cu")
		(net "PHY_DRV_B_TO_SCC_B_17_DP")
	)
	(segment
		(start 201.409554 -136.595104)
		(end 201.059542 -136.502902)
		(width 0.12065)
		(layer "In5.Cu")
		(net "PHY_DRV_B_TO_SCC_B_17_DP")
	)
	(segment
		(start 285.968186 -207.931512)
		(end 285.968186 -207.702912)
		(width 0.12065)
		(layer "In5.Cu")
		(net "PHY_DRV_B_TO_SCC_B_17_DP")
	)
	(segment
		(start 285.436564 -208.09458)
		(end 285.805118 -208.09458)
		(width 0.12065)
		(layer "In5.Cu")
		(net "PHY_DRV_B_TO_SCC_B_17_DP")
	)
	(segment
		(start 201.670158 -136.442958)
		(end 201.409554 -136.595104)
		(width 0.12065)
		(layer "In5.Cu")
		(net "PHY_DRV_B_TO_SCC_B_17_DP")
	)
	(segment
		(start 250.868942 -166.154862)
		(end 207.459834 -137.96391)
		(width 0.12065)
		(layer "In5.Cu")
		(net "PHY_DRV_B_TO_SCC_B_17_DP")
	)
	(segment
		(start 198.681594 -135.657844)
		(end 192.060322 -133.918198)
		(width 0.12065)
		(layer "In5.Cu")
		(net "PHY_DRV_B_TO_SCC_B_17_DP")
	)
	(segment
		(start 200.907396 -136.242552)
		(end 200.55713 -136.150604)
		(width 0.12065)
		(layer "In5.Cu")
		(net "PHY_DRV_B_TO_SCC_B_17_DP")
	)
	(segment
		(start 277.44928 -207.084676)
		(end 250.868942 -166.154862)
		(width 0.12065)
		(layer "In5.Cu")
		(net "PHY_DRV_B_TO_SCC_B_17_DP")
	)
	(segment
		(start 201.059542 -136.502902)
		(end 200.907396 -136.242552)
		(width 0.12065)
		(layer "In5.Cu")
		(net "PHY_DRV_B_TO_SCC_B_17_DP")
	)
	(segment
		(start 190.258954 -134.038848)
		(end 190.258954 -134.38505)
		(width 0.12065)
		(layer "In5.Cu")
		(net "PHY_DRV_B_TO_SCC_B_17_DP")
	)
	(segment
		(start 207.459834 -137.96391)
		(end 201.670158 -136.442958)
		(width 0.12065)
		(layer "In5.Cu")
		(net "PHY_DRV_B_TO_SCC_B_17_DP")
	)
	(segment
		(start 200.296526 -136.30275)
		(end 199.946514 -136.210548)
		(width 0.12065)
		(layer "In5.Cu")
		(net "PHY_DRV_B_TO_SCC_B_17_DP")
	)
	(segment
		(start 192.060322 -133.918198)
		(end 190.379604 -133.918198)
		(width 0.12065)
		(layer "In5.Cu")
		(net "PHY_DRV_B_TO_SCC_B_17_DP")
	)
	(segment
		(start 199.444356 -135.857996)
		(end 199.183752 -136.010142)
		(width 0.12065)
		(layer "In5.Cu")
		(net "PHY_DRV_B_TO_SCC_B_17_DP")
	)
	(segment
		(start 199.946514 -136.210548)
		(end 199.794368 -135.950198)
		(width 0.12065)
		(layer "In5.Cu")
		(net "PHY_DRV_B_TO_SCC_B_17_DP")
	)
	(segment
		(start 200.55713 -136.150604)
		(end 200.296526 -136.30275)
		(width 0.12065)
		(layer "In5.Cu")
		(net "PHY_DRV_B_TO_SCC_B_17_DP")
	)
	(segment
		(start 285.62808 -207.362806)
		(end 278.006556 -207.362806)
		(width 0.12065)
		(layer "In5.Cu")
		(net "PHY_DRV_B_TO_SCC_B_17_DP")
	)
	(segment
		(start 199.794368 -135.950198)
		(end 199.444356 -135.857996)
		(width 0.12065)
		(layer "In5.Cu")
		(net "PHY_DRV_B_TO_SCC_B_17_DP")
	)
	(arc
		(start 190.379604 -133.918198)
		(mid 190.294292 -133.953536)
		(end 190.258954 -134.038848)
		(width 0.12065)
		(layer "In5.Cu")
		(net "PHY_DRV_B_TO_SCC_B_17_DP")
	)
	(arc
		(start 285.968186 -207.702912)
		(mid 285.868571 -207.462421)
		(end 285.62808 -207.362806)
		(width 0.12065)
		(layer "In5.Cu")
		(net "PHY_DRV_B_TO_SCC_B_17_DP")
	)
	(arc
		(start 285.805118 -208.09458)
		(mid 285.920424 -208.046818)
		(end 285.968186 -207.931512)
		(width 0.12065)
		(layer "In5.Cu")
		(net "PHY_DRV_B_TO_SCC_B_17_DP")
	)
	(segment
		(start 189.109604 -133.11505)
		(end 189.236604 -133.24205)
		(width 0.127)
		(layer "F.Cu")
		(net "PHY_DRV_B_TO_SCC_B_17_DN")
	)
	(segment
		(start 189.363604 -133.604)
		(end 190.131954 -133.604)
		(width 0.127)
		(layer "F.Cu")
		(net "PHY_DRV_B_TO_SCC_B_17_DN")
	)
	(segment
		(start 189.236604 -133.477)
		(end 189.363604 -133.604)
		(width 0.127)
		(layer "F.Cu")
		(net "PHY_DRV_B_TO_SCC_B_17_DN")
	)
	(segment
		(start 187.775088 -133.11505)
		(end 189.109604 -133.11505)
		(width 0.127)
		(layer "F.Cu")
		(net "PHY_DRV_B_TO_SCC_B_17_DN")
	)
	(segment
		(start 190.258954 -133.477)
		(end 190.258954 -133.11505)
		(width 0.127)
		(layer "F.Cu")
		(net "PHY_DRV_B_TO_SCC_B_17_DN")
	)
	(segment
		(start 189.236604 -133.24205)
		(end 189.236604 -133.477)
		(width 0.127)
		(layer "F.Cu")
		(net "PHY_DRV_B_TO_SCC_B_17_DN")
	)
	(arc
		(start 190.131954 -133.604)
		(mid 190.221757 -133.566803)
		(end 190.258954 -133.477)
		(width 0.127)
		(layer "F.Cu")
		(net "PHY_DRV_B_TO_SCC_B_17_DN")
	)
	(segment
		(start 286.836612 -208.09458)
		(end 286.467804 -208.09458)
		(width 0.12065)
		(layer "In5.Cu")
		(net "PHY_DRV_B_TO_SCC_B_17_DN")
	)
	(segment
		(start 278.086058 -207.026256)
		(end 277.68169 -206.824326)
		(width 0.12065)
		(layer "In5.Cu")
		(net "PHY_DRV_B_TO_SCC_B_17_DN")
	)
	(segment
		(start 192.104264 -133.581648)
		(end 190.379604 -133.581648)
		(width 0.12065)
		(layer "In5.Cu")
		(net "PHY_DRV_B_TO_SCC_B_17_DN")
	)
	(segment
		(start 286.304736 -207.931512)
		(end 286.304736 -207.702912)
		(width 0.12065)
		(layer "In5.Cu")
		(net "PHY_DRV_B_TO_SCC_B_17_DN")
	)
	(segment
		(start 251.112274 -165.91153)
		(end 207.597756 -137.651998)
		(width 0.12065)
		(layer "In5.Cu")
		(net "PHY_DRV_B_TO_SCC_B_17_DN")
	)
	(segment
		(start 207.597756 -137.651998)
		(end 192.104264 -133.581648)
		(width 0.12065)
		(layer "In5.Cu")
		(net "PHY_DRV_B_TO_SCC_B_17_DN")
	)
	(segment
		(start 190.258954 -133.460998)
		(end 190.258954 -133.11505)
		(width 0.12065)
		(layer "In5.Cu")
		(net "PHY_DRV_B_TO_SCC_B_17_DN")
	)
	(segment
		(start 277.68169 -206.824326)
		(end 251.112274 -165.91153)
		(width 0.12065)
		(layer "In5.Cu")
		(net "PHY_DRV_B_TO_SCC_B_17_DN")
	)
	(segment
		(start 285.62808 -207.026256)
		(end 278.086058 -207.026256)
		(width 0.12065)
		(layer "In5.Cu")
		(net "PHY_DRV_B_TO_SCC_B_17_DN")
	)
	(arc
		(start 286.467804 -208.09458)
		(mid 286.352498 -208.046818)
		(end 286.304736 -207.931512)
		(width 0.12065)
		(layer "In5.Cu")
		(net "PHY_DRV_B_TO_SCC_B_17_DN")
	)
	(arc
		(start 286.304736 -207.702912)
		(mid 286.106548 -207.224444)
		(end 285.62808 -207.026256)
		(width 0.12065)
		(layer "In5.Cu")
		(net "PHY_DRV_B_TO_SCC_B_17_DN")
	)
	(arc
		(start 190.379604 -133.581648)
		(mid 190.294292 -133.54631)
		(end 190.258954 -133.460998)
		(width 0.12065)
		(layer "In5.Cu")
		(net "PHY_DRV_B_TO_SCC_B_17_DN")
	)
	(segment
		(start 157.56255 -134.38505)
		(end 157.6832 -134.2644)
		(width 0.127)
		(layer "F.Cu")
		(net "PHY_DRV_B_TO_SCC_B_16_DP")
	)
	(segment
		(start 157.6832 -134.0104)
		(end 157.7975 -133.8961)
		(width 0.127)
		(layer "F.Cu")
		(net "PHY_DRV_B_TO_SCC_B_16_DP")
	)
	(segment
		(start 157.6832 -134.2644)
		(end 157.6832 -134.0104)
		(width 0.127)
		(layer "F.Cu")
		(net "PHY_DRV_B_TO_SCC_B_16_DP")
	)
	(segment
		(start 156.224986 -134.38505)
		(end 157.56255 -134.38505)
		(width 0.127)
		(layer "F.Cu")
		(net "PHY_DRV_B_TO_SCC_B_16_DP")
	)
	(segment
		(start 157.7975 -133.8961)
		(end 158.581852 -133.8961)
		(width 0.127)
		(layer "F.Cu")
		(net "PHY_DRV_B_TO_SCC_B_16_DP")
	)
	(segment
		(start 158.708852 -134.0231)
		(end 158.708852 -134.38505)
		(width 0.127)
		(layer "F.Cu")
		(net "PHY_DRV_B_TO_SCC_B_16_DP")
	)
	(arc
		(start 158.581852 -133.8961)
		(mid 158.671655 -133.933297)
		(end 158.708852 -134.0231)
		(width 0.127)
		(layer "F.Cu")
		(net "PHY_DRV_B_TO_SCC_B_16_DP")
	)
	(segment
		(start 267.67536 -205.971648)
		(end 261.42442 -203.796138)
		(width 0.12065)
		(layer "In5.Cu")
		(net "PHY_DRV_B_TO_SCC_B_16_DP")
	)
	(segment
		(start 181.177438 -151.696166)
		(end 173.318932 -139.601956)
		(width 0.12065)
		(layer "In5.Cu")
		(net "PHY_DRV_B_TO_SCC_B_16_DP")
	)
	(segment
		(start 269.848584 -206.727806)
		(end 269.5067 -206.608934)
		(width 0.12065)
		(layer "In5.Cu")
		(net "PHY_DRV_B_TO_SCC_B_16_DP")
	)
	(segment
		(start 276.845014 -209.16265)
		(end 270.593566 -206.98714)
		(width 0.12065)
		(layer "In5.Cu")
		(net "PHY_DRV_B_TO_SCC_B_16_DP")
	)
	(segment
		(start 267.806678 -206.243174)
		(end 267.67536 -205.971648)
		(width 0.12065)
		(layer "In5.Cu")
		(net "PHY_DRV_B_TO_SCC_B_16_DP")
	)
	(segment
		(start 268.89329 -206.62138)
		(end 268.761972 -206.349854)
		(width 0.12065)
		(layer "In5.Cu")
		(net "PHY_DRV_B_TO_SCC_B_16_DP")
	)
	(segment
		(start 169.10177 -136.863328)
		(end 162.052 -133.918198)
		(width 0.12065)
		(layer "In5.Cu")
		(net "PHY_DRV_B_TO_SCC_B_16_DP")
	)
	(segment
		(start 286.436562 -209.894424)
		(end 286.805116 -209.894424)
		(width 0.12065)
		(layer "In5.Cu")
		(net "PHY_DRV_B_TO_SCC_B_16_DP")
	)
	(segment
		(start 269.980156 -206.999586)
		(end 269.848584 -206.727806)
		(width 0.12065)
		(layer "In5.Cu")
		(net "PHY_DRV_B_TO_SCC_B_16_DP")
	)
	(segment
		(start 158.708852 -134.038848)
		(end 158.708852 -134.38505)
		(width 0.12065)
		(layer "In5.Cu")
		(net "PHY_DRV_B_TO_SCC_B_16_DP")
	)
	(segment
		(start 269.235174 -206.740252)
		(end 268.89329 -206.62138)
		(width 0.12065)
		(layer "In5.Cu")
		(net "PHY_DRV_B_TO_SCC_B_16_DP")
	)
	(segment
		(start 286.628078 -209.16265)
		(end 276.845014 -209.16265)
		(width 0.12065)
		(layer "In5.Cu")
		(net "PHY_DRV_B_TO_SCC_B_16_DP")
	)
	(segment
		(start 270.593566 -206.98714)
		(end 270.321786 -207.118458)
		(width 0.12065)
		(layer "In5.Cu")
		(net "PHY_DRV_B_TO_SCC_B_16_DP")
	)
	(segment
		(start 268.148562 -206.362046)
		(end 267.806678 -206.243174)
		(width 0.12065)
		(layer "In5.Cu")
		(net "PHY_DRV_B_TO_SCC_B_16_DP")
	)
	(segment
		(start 268.761972 -206.349854)
		(end 268.420088 -206.230728)
		(width 0.12065)
		(layer "In5.Cu")
		(net "PHY_DRV_B_TO_SCC_B_16_DP")
	)
	(segment
		(start 286.968184 -209.731356)
		(end 286.968184 -209.502756)
		(width 0.12065)
		(layer "In5.Cu")
		(net "PHY_DRV_B_TO_SCC_B_16_DP")
	)
	(segment
		(start 269.5067 -206.608934)
		(end 269.235174 -206.740252)
		(width 0.12065)
		(layer "In5.Cu")
		(net "PHY_DRV_B_TO_SCC_B_16_DP")
	)
	(segment
		(start 173.318932 -139.601956)
		(end 169.10177 -136.863328)
		(width 0.12065)
		(layer "In5.Cu")
		(net "PHY_DRV_B_TO_SCC_B_16_DP")
	)
	(segment
		(start 268.420088 -206.230728)
		(end 268.148562 -206.362046)
		(width 0.12065)
		(layer "In5.Cu")
		(net "PHY_DRV_B_TO_SCC_B_16_DP")
	)
	(segment
		(start 162.052 -133.918198)
		(end 158.829502 -133.918198)
		(width 0.12065)
		(layer "In5.Cu")
		(net "PHY_DRV_B_TO_SCC_B_16_DP")
	)
	(segment
		(start 270.321786 -207.118458)
		(end 269.980156 -206.999586)
		(width 0.12065)
		(layer "In5.Cu")
		(net "PHY_DRV_B_TO_SCC_B_16_DP")
	)
	(segment
		(start 261.42442 -203.796138)
		(end 181.177438 -151.696166)
		(width 0.12065)
		(layer "In5.Cu")
		(net "PHY_DRV_B_TO_SCC_B_16_DP")
	)
	(arc
		(start 286.805116 -209.894424)
		(mid 286.920422 -209.846662)
		(end 286.968184 -209.731356)
		(width 0.12065)
		(layer "In5.Cu")
		(net "PHY_DRV_B_TO_SCC_B_16_DP")
	)
	(arc
		(start 158.829502 -133.918198)
		(mid 158.74419 -133.953536)
		(end 158.708852 -134.038848)
		(width 0.12065)
		(layer "In5.Cu")
		(net "PHY_DRV_B_TO_SCC_B_16_DP")
	)
	(arc
		(start 286.968184 -209.502756)
		(mid 286.868569 -209.262265)
		(end 286.628078 -209.16265)
		(width 0.12065)
		(layer "In5.Cu")
		(net "PHY_DRV_B_TO_SCC_B_16_DP")
	)
	(segment
		(start 157.559502 -133.11505)
		(end 157.686502 -133.24205)
		(width 0.127)
		(layer "F.Cu")
		(net "PHY_DRV_B_TO_SCC_B_16_DN")
	)
	(segment
		(start 156.224986 -133.11505)
		(end 157.559502 -133.11505)
		(width 0.127)
		(layer "F.Cu")
		(net "PHY_DRV_B_TO_SCC_B_16_DN")
	)
	(segment
		(start 157.686502 -133.477)
		(end 157.813502 -133.604)
		(width 0.127)
		(layer "F.Cu")
		(net "PHY_DRV_B_TO_SCC_B_16_DN")
	)
	(segment
		(start 158.708852 -133.477)
		(end 158.708852 -133.11505)
		(width 0.127)
		(layer "F.Cu")
		(net "PHY_DRV_B_TO_SCC_B_16_DN")
	)
	(segment
		(start 157.813502 -133.604)
		(end 158.581852 -133.604)
		(width 0.127)
		(layer "F.Cu")
		(net "PHY_DRV_B_TO_SCC_B_16_DN")
	)
	(segment
		(start 157.686502 -133.24205)
		(end 157.686502 -133.477)
		(width 0.127)
		(layer "F.Cu")
		(net "PHY_DRV_B_TO_SCC_B_16_DN")
	)
	(arc
		(start 158.581852 -133.604)
		(mid 158.671655 -133.566803)
		(end 158.708852 -133.477)
		(width 0.127)
		(layer "F.Cu")
		(net "PHY_DRV_B_TO_SCC_B_16_DN")
	)
	(segment
		(start 287.83661 -209.894424)
		(end 287.467802 -209.894424)
		(width 0.12065)
		(layer "In5.Cu")
		(net "PHY_DRV_B_TO_SCC_B_16_DN")
	)
	(segment
		(start 286.628078 -208.8261)
		(end 276.90191 -208.8261)
		(width 0.12065)
		(layer "In5.Cu")
		(net "PHY_DRV_B_TO_SCC_B_16_DN")
	)
	(segment
		(start 181.42077 -151.452834)
		(end 173.562264 -139.358624)
		(width 0.12065)
		(layer "In5.Cu")
		(net "PHY_DRV_B_TO_SCC_B_16_DN")
	)
	(segment
		(start 276.90191 -208.8261)
		(end 261.573518 -203.491592)
		(width 0.12065)
		(layer "In5.Cu")
		(net "PHY_DRV_B_TO_SCC_B_16_DN")
	)
	(segment
		(start 287.304734 -209.731356)
		(end 287.304734 -209.502756)
		(width 0.12065)
		(layer "In5.Cu")
		(net "PHY_DRV_B_TO_SCC_B_16_DN")
	)
	(segment
		(start 162.119564 -133.581648)
		(end 158.829502 -133.581648)
		(width 0.12065)
		(layer "In5.Cu")
		(net "PHY_DRV_B_TO_SCC_B_16_DN")
	)
	(segment
		(start 158.708852 -133.460998)
		(end 158.708852 -133.11505)
		(width 0.12065)
		(layer "In5.Cu")
		(net "PHY_DRV_B_TO_SCC_B_16_DN")
	)
	(segment
		(start 173.562264 -139.358624)
		(end 169.259758 -136.56437)
		(width 0.12065)
		(layer "In5.Cu")
		(net "PHY_DRV_B_TO_SCC_B_16_DN")
	)
	(segment
		(start 261.573518 -203.491592)
		(end 181.42077 -151.452834)
		(width 0.12065)
		(layer "In5.Cu")
		(net "PHY_DRV_B_TO_SCC_B_16_DN")
	)
	(segment
		(start 169.259758 -136.56437)
		(end 162.119564 -133.581648)
		(width 0.12065)
		(layer "In5.Cu")
		(net "PHY_DRV_B_TO_SCC_B_16_DN")
	)
	(arc
		(start 287.304734 -209.502756)
		(mid 287.106546 -209.024288)
		(end 286.628078 -208.8261)
		(width 0.12065)
		(layer "In5.Cu")
		(net "PHY_DRV_B_TO_SCC_B_16_DN")
	)
	(arc
		(start 158.829502 -133.581648)
		(mid 158.74419 -133.54631)
		(end 158.708852 -133.460998)
		(width 0.12065)
		(layer "In5.Cu")
		(net "PHY_DRV_B_TO_SCC_B_16_DN")
	)
	(arc
		(start 287.467802 -209.894424)
		(mid 287.352496 -209.846662)
		(end 287.304734 -209.731356)
		(width 0.12065)
		(layer "In5.Cu")
		(net "PHY_DRV_B_TO_SCC_B_16_DN")
	)
	(segment
		(start 126.0094 -134.38505)
		(end 126.1364 -134.25805)
		(width 0.127)
		(layer "F.Cu")
		(net "PHY_DRV_B_TO_SCC_B_15_DP")
	)
	(segment
		(start 126.1364 -134.0231)
		(end 126.2634 -133.8961)
		(width 0.127)
		(layer "F.Cu")
		(net "PHY_DRV_B_TO_SCC_B_15_DP")
	)
	(segment
		(start 124.674884 -134.38505)
		(end 126.0094 -134.38505)
		(width 0.127)
		(layer "F.Cu")
		(net "PHY_DRV_B_TO_SCC_B_15_DP")
	)
	(segment
		(start 126.1364 -134.25805)
		(end 126.1364 -134.0231)
		(width 0.127)
		(layer "F.Cu")
		(net "PHY_DRV_B_TO_SCC_B_15_DP")
	)
	(segment
		(start 127.15875 -134.0231)
		(end 127.15875 -134.38505)
		(width 0.127)
		(layer "F.Cu")
		(net "PHY_DRV_B_TO_SCC_B_15_DP")
	)
	(segment
		(start 126.2634 -133.8961)
		(end 127.03175 -133.8961)
		(width 0.127)
		(layer "F.Cu")
		(net "PHY_DRV_B_TO_SCC_B_15_DP")
	)
	(arc
		(start 127.03175 -133.8961)
		(mid 127.121553 -133.933297)
		(end 127.15875 -134.0231)
		(width 0.127)
		(layer "F.Cu")
		(net "PHY_DRV_B_TO_SCC_B_15_DP")
	)
	(segment
		(start 155.516072 -148.749004)
		(end 128.989836 -133.918198)
		(width 0.12065)
		(layer "In5.Cu")
		(net "PHY_DRV_B_TO_SCC_B_15_DP")
	)
	(segment
		(start 166.107618 -151.218646)
		(end 165.753542 -151.143462)
		(width 0.12065)
		(layer "In5.Cu")
		(net "PHY_DRV_B_TO_SCC_B_15_DP")
	)
	(segment
		(start 277.158958 -210.962748)
		(end 266.086082 -208.608676)
		(width 0.12065)
		(layer "In5.Cu")
		(net "PHY_DRV_B_TO_SCC_B_15_DP")
	)
	(segment
		(start 163.338256 -150.411942)
		(end 163.338002 -150.411688)
		(width 0.12065)
		(layer "In5.Cu")
		(net "PHY_DRV_B_TO_SCC_B_15_DP")
	)
	(segment
		(start 163.502594 -150.664926)
		(end 163.338256 -150.411942)
		(width 0.12065)
		(layer "In5.Cu")
		(net "PHY_DRV_B_TO_SCC_B_15_DP")
	)
	(segment
		(start 166.360602 -151.054308)
		(end 166.107618 -151.218646)
		(width 0.12065)
		(layer "In5.Cu")
		(net "PHY_DRV_B_TO_SCC_B_15_DP")
	)
	(segment
		(start 165.753542 -151.143462)
		(end 165.589204 -150.890224)
		(width 0.12065)
		(layer "In5.Cu")
		(net "PHY_DRV_B_TO_SCC_B_15_DP")
	)
	(segment
		(start 128.989836 -133.918198)
		(end 127.2794 -133.918198)
		(width 0.12065)
		(layer "In5.Cu")
		(net "PHY_DRV_B_TO_SCC_B_15_DP")
	)
	(segment
		(start 164.982144 -150.979378)
		(end 164.628068 -150.904194)
		(width 0.12065)
		(layer "In5.Cu")
		(net "PHY_DRV_B_TO_SCC_B_15_DP")
	)
	(segment
		(start 285.62808 -210.962748)
		(end 277.158958 -210.962748)
		(width 0.12065)
		(layer "In5.Cu")
		(net "PHY_DRV_B_TO_SCC_B_15_DP")
	)
	(segment
		(start 163.85667 -150.74011)
		(end 163.502594 -150.664926)
		(width 0.12065)
		(layer "In5.Cu")
		(net "PHY_DRV_B_TO_SCC_B_15_DP")
	)
	(segment
		(start 165.235128 -150.81504)
		(end 164.982144 -150.979378)
		(width 0.12065)
		(layer "In5.Cu")
		(net "PHY_DRV_B_TO_SCC_B_15_DP")
	)
	(segment
		(start 165.589204 -150.890224)
		(end 165.235128 -150.81504)
		(width 0.12065)
		(layer "In5.Cu")
		(net "PHY_DRV_B_TO_SCC_B_15_DP")
	)
	(segment
		(start 169.972482 -151.821896)
		(end 166.360602 -151.054308)
		(width 0.12065)
		(layer "In5.Cu")
		(net "PHY_DRV_B_TO_SCC_B_15_DP")
	)
	(segment
		(start 164.46373 -150.65121)
		(end 164.109654 -150.575772)
		(width 0.12065)
		(layer "In5.Cu")
		(net "PHY_DRV_B_TO_SCC_B_15_DP")
	)
	(segment
		(start 182.800244 -154.548586)
		(end 169.972482 -151.821896)
		(width 0.12065)
		(layer "In5.Cu")
		(net "PHY_DRV_B_TO_SCC_B_15_DP")
	)
	(segment
		(start 127.15875 -134.038848)
		(end 127.15875 -134.38505)
		(width 0.12065)
		(layer "In5.Cu")
		(net "PHY_DRV_B_TO_SCC_B_15_DP")
	)
	(segment
		(start 163.338002 -150.411688)
		(end 155.516072 -148.749004)
		(width 0.12065)
		(layer "In5.Cu")
		(net "PHY_DRV_B_TO_SCC_B_15_DP")
	)
	(segment
		(start 285.436564 -211.694522)
		(end 285.805118 -211.694522)
		(width 0.12065)
		(layer "In5.Cu")
		(net "PHY_DRV_B_TO_SCC_B_15_DP")
	)
	(segment
		(start 164.109654 -150.575772)
		(end 163.85667 -150.74011)
		(width 0.12065)
		(layer "In5.Cu")
		(net "PHY_DRV_B_TO_SCC_B_15_DP")
	)
	(segment
		(start 164.628068 -150.904194)
		(end 164.46373 -150.65121)
		(width 0.12065)
		(layer "In5.Cu")
		(net "PHY_DRV_B_TO_SCC_B_15_DP")
	)
	(segment
		(start 266.086082 -208.608676)
		(end 182.800244 -154.548586)
		(width 0.12065)
		(layer "In5.Cu")
		(net "PHY_DRV_B_TO_SCC_B_15_DP")
	)
	(segment
		(start 285.968186 -211.531454)
		(end 285.968186 -211.302854)
		(width 0.12065)
		(layer "In5.Cu")
		(net "PHY_DRV_B_TO_SCC_B_15_DP")
	)
	(arc
		(start 285.805118 -211.694522)
		(mid 285.920424 -211.64676)
		(end 285.968186 -211.531454)
		(width 0.12065)
		(layer "In5.Cu")
		(net "PHY_DRV_B_TO_SCC_B_15_DP")
	)
	(arc
		(start 285.968186 -211.302854)
		(mid 285.868571 -211.062363)
		(end 285.62808 -210.962748)
		(width 0.12065)
		(layer "In5.Cu")
		(net "PHY_DRV_B_TO_SCC_B_15_DP")
	)
	(arc
		(start 127.2794 -133.918198)
		(mid 127.194088 -133.953536)
		(end 127.15875 -134.038848)
		(width 0.12065)
		(layer "In5.Cu")
		(net "PHY_DRV_B_TO_SCC_B_15_DP")
	)
	(segment
		(start 126.1364 -133.24205)
		(end 126.1364 -133.477)
		(width 0.127)
		(layer "F.Cu")
		(net "PHY_DRV_B_TO_SCC_B_15_DN")
	)
	(segment
		(start 126.0094 -133.11505)
		(end 126.1364 -133.24205)
		(width 0.127)
		(layer "F.Cu")
		(net "PHY_DRV_B_TO_SCC_B_15_DN")
	)
	(segment
		(start 124.674884 -133.11505)
		(end 126.0094 -133.11505)
		(width 0.127)
		(layer "F.Cu")
		(net "PHY_DRV_B_TO_SCC_B_15_DN")
	)
	(segment
		(start 127.15875 -133.477)
		(end 127.15875 -133.11505)
		(width 0.127)
		(layer "F.Cu")
		(net "PHY_DRV_B_TO_SCC_B_15_DN")
	)
	(segment
		(start 126.2634 -133.604)
		(end 127.03175 -133.604)
		(width 0.127)
		(layer "F.Cu")
		(net "PHY_DRV_B_TO_SCC_B_15_DN")
	)
	(segment
		(start 126.1364 -133.477)
		(end 126.2634 -133.604)
		(width 0.127)
		(layer "F.Cu")
		(net "PHY_DRV_B_TO_SCC_B_15_DN")
	)
	(arc
		(start 127.03175 -133.604)
		(mid 127.121553 -133.566803)
		(end 127.15875 -133.477)
		(width 0.127)
		(layer "F.Cu")
		(net "PHY_DRV_B_TO_SCC_B_15_DN")
	)
	(segment
		(start 155.63596 -148.430234)
		(end 129.07772 -133.581648)
		(width 0.12065)
		(layer "In5.Cu")
		(net "PHY_DRV_B_TO_SCC_B_15_DN")
	)
	(segment
		(start 286.304736 -211.531454)
		(end 286.304736 -211.302854)
		(width 0.12065)
		(layer "In5.Cu")
		(net "PHY_DRV_B_TO_SCC_B_15_DN")
	)
	(segment
		(start 182.931308 -154.232356)
		(end 155.63596 -148.430234)
		(width 0.12065)
		(layer "In5.Cu")
		(net "PHY_DRV_B_TO_SCC_B_15_DN")
	)
	(segment
		(start 286.836612 -211.694522)
		(end 286.467804 -211.694522)
		(width 0.12065)
		(layer "In5.Cu")
		(net "PHY_DRV_B_TO_SCC_B_15_DN")
	)
	(segment
		(start 127.15875 -133.460998)
		(end 127.15875 -133.11505)
		(width 0.12065)
		(layer "In5.Cu")
		(net "PHY_DRV_B_TO_SCC_B_15_DN")
	)
	(segment
		(start 129.07772 -133.581648)
		(end 127.2794 -133.581648)
		(width 0.12065)
		(layer "In5.Cu")
		(net "PHY_DRV_B_TO_SCC_B_15_DN")
	)
	(segment
		(start 285.62808 -210.626198)
		(end 277.194518 -210.626198)
		(width 0.12065)
		(layer "In5.Cu")
		(net "PHY_DRV_B_TO_SCC_B_15_DN")
	)
	(segment
		(start 266.217146 -208.292446)
		(end 182.931308 -154.232356)
		(width 0.12065)
		(layer "In5.Cu")
		(net "PHY_DRV_B_TO_SCC_B_15_DN")
	)
	(segment
		(start 277.194518 -210.626198)
		(end 266.217146 -208.292446)
		(width 0.12065)
		(layer "In5.Cu")
		(net "PHY_DRV_B_TO_SCC_B_15_DN")
	)
	(arc
		(start 286.467804 -211.694522)
		(mid 286.352498 -211.64676)
		(end 286.304736 -211.531454)
		(width 0.12065)
		(layer "In5.Cu")
		(net "PHY_DRV_B_TO_SCC_B_15_DN")
	)
	(arc
		(start 127.2794 -133.581648)
		(mid 127.194088 -133.54631)
		(end 127.15875 -133.460998)
		(width 0.12065)
		(layer "In5.Cu")
		(net "PHY_DRV_B_TO_SCC_B_15_DN")
	)
	(arc
		(start 286.304736 -211.302854)
		(mid 286.106548 -210.824386)
		(end 285.62808 -210.626198)
		(width 0.12065)
		(layer "In5.Cu")
		(net "PHY_DRV_B_TO_SCC_B_15_DN")
	)
	(segment
		(start 94.586552 -134.0231)
		(end 94.713552 -133.8961)
		(width 0.127)
		(layer "F.Cu")
		(net "PHY_DRV_B_TO_SCC_B_14_DP")
	)
	(segment
		(start 93.125036 -134.38505)
		(end 94.459552 -134.38505)
		(width 0.127)
		(layer "F.Cu")
		(net "PHY_DRV_B_TO_SCC_B_14_DP")
	)
	(segment
		(start 94.459552 -134.38505)
		(end 94.586552 -134.25805)
		(width 0.127)
		(layer "F.Cu")
		(net "PHY_DRV_B_TO_SCC_B_14_DP")
	)
	(segment
		(start 95.608902 -134.0231)
		(end 95.608902 -134.38505)
		(width 0.127)
		(layer "F.Cu")
		(net "PHY_DRV_B_TO_SCC_B_14_DP")
	)
	(segment
		(start 94.713552 -133.8961)
		(end 95.481902 -133.8961)
		(width 0.127)
		(layer "F.Cu")
		(net "PHY_DRV_B_TO_SCC_B_14_DP")
	)
	(segment
		(start 94.586552 -134.25805)
		(end 94.586552 -134.0231)
		(width 0.127)
		(layer "F.Cu")
		(net "PHY_DRV_B_TO_SCC_B_14_DP")
	)
	(arc
		(start 95.481902 -133.8961)
		(mid 95.571705 -133.933297)
		(end 95.608902 -134.0231)
		(width 0.127)
		(layer "F.Cu")
		(net "PHY_DRV_B_TO_SCC_B_14_DP")
	)
	(segment
		(start 190.029084 -161.731198)
		(end 136.049766 -150.257764)
		(width 0.12065)
		(layer "In5.Cu")
		(net "PHY_DRV_B_TO_SCC_B_14_DP")
	)
	(segment
		(start 133.565646 -149.947884)
		(end 133.21157 -149.8727)
		(width 0.12065)
		(layer "In5.Cu")
		(net "PHY_DRV_B_TO_SCC_B_14_DP")
	)
	(segment
		(start 123.951492 -147.686268)
		(end 110.988856 -139.26693)
		(width 0.12065)
		(layer "In5.Cu")
		(net "PHY_DRV_B_TO_SCC_B_14_DP")
	)
	(segment
		(start 134.69112 -150.187152)
		(end 134.337044 -150.111968)
		(width 0.12065)
		(layer "In5.Cu")
		(net "PHY_DRV_B_TO_SCC_B_14_DP")
	)
	(segment
		(start 135.80872 -150.414228)
		(end 135.454644 -150.339044)
		(width 0.12065)
		(layer "In5.Cu")
		(net "PHY_DRV_B_TO_SCC_B_14_DP")
	)
	(segment
		(start 266.298172 -211.259166)
		(end 190.029084 -161.731198)
		(width 0.12065)
		(layer "In5.Cu")
		(net "PHY_DRV_B_TO_SCC_B_14_DP")
	)
	(segment
		(start 133.81863 -149.783546)
		(end 133.565646 -149.947884)
		(width 0.12065)
		(layer "In5.Cu")
		(net "PHY_DRV_B_TO_SCC_B_14_DP")
	)
	(segment
		(start 134.944104 -150.022814)
		(end 134.69112 -150.187152)
		(width 0.12065)
		(layer "In5.Cu")
		(net "PHY_DRV_B_TO_SCC_B_14_DP")
	)
	(segment
		(start 134.172706 -149.858984)
		(end 133.81863 -149.783546)
		(width 0.12065)
		(layer "In5.Cu")
		(net "PHY_DRV_B_TO_SCC_B_14_DP")
	)
	(segment
		(start 135.29818 -150.097998)
		(end 134.944104 -150.022814)
		(width 0.12065)
		(layer "In5.Cu")
		(net "PHY_DRV_B_TO_SCC_B_14_DP")
	)
	(segment
		(start 96.73336 -133.918198)
		(end 95.729552 -133.918198)
		(width 0.12065)
		(layer "In5.Cu")
		(net "PHY_DRV_B_TO_SCC_B_14_DP")
	)
	(segment
		(start 273.370294 -212.762592)
		(end 266.298172 -211.259166)
		(width 0.12065)
		(layer "In5.Cu")
		(net "PHY_DRV_B_TO_SCC_B_14_DP")
	)
	(segment
		(start 133.21157 -149.8727)
		(end 133.047232 -149.619716)
		(width 0.12065)
		(layer "In5.Cu")
		(net "PHY_DRV_B_TO_SCC_B_14_DP")
	)
	(segment
		(start 286.628078 -212.762592)
		(end 273.370294 -212.762592)
		(width 0.12065)
		(layer "In5.Cu")
		(net "PHY_DRV_B_TO_SCC_B_14_DP")
	)
	(segment
		(start 110.988856 -139.26693)
		(end 96.73336 -133.918198)
		(width 0.12065)
		(layer "In5.Cu")
		(net "PHY_DRV_B_TO_SCC_B_14_DP")
	)
	(segment
		(start 134.337044 -150.111968)
		(end 134.172706 -149.858984)
		(width 0.12065)
		(layer "In5.Cu")
		(net "PHY_DRV_B_TO_SCC_B_14_DP")
	)
	(segment
		(start 286.436562 -213.494366)
		(end 286.805116 -213.494366)
		(width 0.12065)
		(layer "In5.Cu")
		(net "PHY_DRV_B_TO_SCC_B_14_DP")
	)
	(segment
		(start 136.049766 -150.257764)
		(end 135.80872 -150.414228)
		(width 0.12065)
		(layer "In5.Cu")
		(net "PHY_DRV_B_TO_SCC_B_14_DP")
	)
	(segment
		(start 133.047232 -149.619716)
		(end 123.951492 -147.686268)
		(width 0.12065)
		(layer "In5.Cu")
		(net "PHY_DRV_B_TO_SCC_B_14_DP")
	)
	(segment
		(start 286.968184 -213.331298)
		(end 286.968184 -213.102698)
		(width 0.12065)
		(layer "In5.Cu")
		(net "PHY_DRV_B_TO_SCC_B_14_DP")
	)
	(segment
		(start 95.608902 -134.038848)
		(end 95.608902 -134.38505)
		(width 0.12065)
		(layer "In5.Cu")
		(net "PHY_DRV_B_TO_SCC_B_14_DP")
	)
	(segment
		(start 135.454644 -150.339044)
		(end 135.29818 -150.097998)
		(width 0.12065)
		(layer "In5.Cu")
		(net "PHY_DRV_B_TO_SCC_B_14_DP")
	)
	(arc
		(start 95.729552 -133.918198)
		(mid 95.64424 -133.953536)
		(end 95.608902 -134.038848)
		(width 0.12065)
		(layer "In5.Cu")
		(net "PHY_DRV_B_TO_SCC_B_14_DP")
	)
	(arc
		(start 286.968184 -213.102698)
		(mid 286.868569 -212.862207)
		(end 286.628078 -212.762592)
		(width 0.12065)
		(layer "In5.Cu")
		(net "PHY_DRV_B_TO_SCC_B_14_DP")
	)
	(arc
		(start 286.805116 -213.494366)
		(mid 286.920422 -213.446604)
		(end 286.968184 -213.331298)
		(width 0.12065)
		(layer "In5.Cu")
		(net "PHY_DRV_B_TO_SCC_B_14_DP")
	)
	(segment
		(start 94.713552 -133.604)
		(end 95.481902 -133.604)
		(width 0.127)
		(layer "F.Cu")
		(net "PHY_DRV_B_TO_SCC_B_14_DN")
	)
	(segment
		(start 95.608902 -133.477)
		(end 95.608902 -133.11505)
		(width 0.127)
		(layer "F.Cu")
		(net "PHY_DRV_B_TO_SCC_B_14_DN")
	)
	(segment
		(start 94.586552 -133.477)
		(end 94.713552 -133.604)
		(width 0.127)
		(layer "F.Cu")
		(net "PHY_DRV_B_TO_SCC_B_14_DN")
	)
	(segment
		(start 94.459552 -133.11505)
		(end 94.586552 -133.24205)
		(width 0.127)
		(layer "F.Cu")
		(net "PHY_DRV_B_TO_SCC_B_14_DN")
	)
	(segment
		(start 94.586552 -133.24205)
		(end 94.586552 -133.477)
		(width 0.127)
		(layer "F.Cu")
		(net "PHY_DRV_B_TO_SCC_B_14_DN")
	)
	(segment
		(start 93.125036 -133.11505)
		(end 94.459552 -133.11505)
		(width 0.127)
		(layer "F.Cu")
		(net "PHY_DRV_B_TO_SCC_B_14_DN")
	)
	(arc
		(start 95.481902 -133.604)
		(mid 95.571705 -133.566803)
		(end 95.608902 -133.477)
		(width 0.127)
		(layer "F.Cu")
		(net "PHY_DRV_B_TO_SCC_B_14_DN")
	)
	(segment
		(start 266.429236 -210.942936)
		(end 190.160148 -161.414968)
		(width 0.12065)
		(layer "In5.Cu")
		(net "PHY_DRV_B_TO_SCC_B_14_DN")
	)
	(segment
		(start 128.599946 -148.330158)
		(end 124.082556 -147.370038)
		(width 0.12065)
		(layer "In5.Cu")
		(net "PHY_DRV_B_TO_SCC_B_14_DN")
	)
	(segment
		(start 111.14151 -138.96467)
		(end 96.794574 -133.581648)
		(width 0.12065)
		(layer "In5.Cu")
		(net "PHY_DRV_B_TO_SCC_B_14_DN")
	)
	(segment
		(start 163.082732 -155.659582)
		(end 133.117336 -149.290278)
		(width 0.12065)
		(layer "In5.Cu")
		(net "PHY_DRV_B_TO_SCC_B_14_DN")
	)
	(segment
		(start 163.082732 -155.659328)
		(end 163.082732 -155.659582)
		(width 0.12065)
		(layer "In5.Cu")
		(net "PHY_DRV_B_TO_SCC_B_14_DN")
	)
	(segment
		(start 287.83661 -213.494366)
		(end 287.467802 -213.494366)
		(width 0.12065)
		(layer "In5.Cu")
		(net "PHY_DRV_B_TO_SCC_B_14_DN")
	)
	(segment
		(start 190.160148 -161.414968)
		(end 163.082732 -155.659328)
		(width 0.12065)
		(layer "In5.Cu")
		(net "PHY_DRV_B_TO_SCC_B_14_DN")
	)
	(segment
		(start 133.117336 -149.290024)
		(end 128.599946 -148.330158)
		(width 0.12065)
		(layer "In5.Cu")
		(net "PHY_DRV_B_TO_SCC_B_14_DN")
	)
	(segment
		(start 273.405854 -212.426042)
		(end 266.429236 -210.942936)
		(width 0.12065)
		(layer "In5.Cu")
		(net "PHY_DRV_B_TO_SCC_B_14_DN")
	)
	(segment
		(start 133.117336 -149.290278)
		(end 133.117336 -149.290024)
		(width 0.12065)
		(layer "In5.Cu")
		(net "PHY_DRV_B_TO_SCC_B_14_DN")
	)
	(segment
		(start 95.608902 -133.460998)
		(end 95.608902 -133.11505)
		(width 0.12065)
		(layer "In5.Cu")
		(net "PHY_DRV_B_TO_SCC_B_14_DN")
	)
	(segment
		(start 287.304734 -213.331298)
		(end 287.304734 -213.102698)
		(width 0.12065)
		(layer "In5.Cu")
		(net "PHY_DRV_B_TO_SCC_B_14_DN")
	)
	(segment
		(start 286.628078 -212.426042)
		(end 273.405854 -212.426042)
		(width 0.12065)
		(layer "In5.Cu")
		(net "PHY_DRV_B_TO_SCC_B_14_DN")
	)
	(segment
		(start 96.794574 -133.581648)
		(end 95.729552 -133.581648)
		(width 0.12065)
		(layer "In5.Cu")
		(net "PHY_DRV_B_TO_SCC_B_14_DN")
	)
	(segment
		(start 124.082556 -147.370038)
		(end 111.14151 -138.96467)
		(width 0.12065)
		(layer "In5.Cu")
		(net "PHY_DRV_B_TO_SCC_B_14_DN")
	)
	(arc
		(start 287.304734 -213.102698)
		(mid 287.106546 -212.62423)
		(end 286.628078 -212.426042)
		(width 0.12065)
		(layer "In5.Cu")
		(net "PHY_DRV_B_TO_SCC_B_14_DN")
	)
	(arc
		(start 95.729552 -133.581648)
		(mid 95.64424 -133.54631)
		(end 95.608902 -133.460998)
		(width 0.12065)
		(layer "In5.Cu")
		(net "PHY_DRV_B_TO_SCC_B_14_DN")
	)
	(arc
		(start 287.467802 -213.494366)
		(mid 287.352496 -213.446604)
		(end 287.304734 -213.331298)
		(width 0.12065)
		(layer "In5.Cu")
		(net "PHY_DRV_B_TO_SCC_B_14_DN")
	)
	(segment
		(start 63.1317 -133.8961)
		(end 63.9318 -133.8961)
		(width 0.127)
		(layer "F.Cu")
		(net "PHY_DRV_B_TO_SCC_B_13_DP")
	)
	(segment
		(start 61.574934 -134.38505)
		(end 62.90945 -134.38505)
		(width 0.127)
		(layer "F.Cu")
		(net "PHY_DRV_B_TO_SCC_B_13_DP")
	)
	(segment
		(start 62.90945 -134.38505)
		(end 63.03645 -134.25805)
		(width 0.127)
		(layer "F.Cu")
		(net "PHY_DRV_B_TO_SCC_B_13_DP")
	)
	(segment
		(start 63.03645 -133.99135)
		(end 63.1317 -133.8961)
		(width 0.127)
		(layer "F.Cu")
		(net "PHY_DRV_B_TO_SCC_B_13_DP")
	)
	(segment
		(start 63.03645 -134.25805)
		(end 63.03645 -133.99135)
		(width 0.127)
		(layer "F.Cu")
		(net "PHY_DRV_B_TO_SCC_B_13_DP")
	)
	(segment
		(start 64.0588 -134.0231)
		(end 64.0588 -134.38505)
		(width 0.127)
		(layer "F.Cu")
		(net "PHY_DRV_B_TO_SCC_B_13_DP")
	)
	(arc
		(start 63.9318 -133.8961)
		(mid 64.021603 -133.933297)
		(end 64.0588 -134.0231)
		(width 0.127)
		(layer "F.Cu")
		(net "PHY_DRV_B_TO_SCC_B_13_DP")
	)
	(segment
		(start 69.918326 -135.586978)
		(end 69.57822 -135.46328)
		(width 0.12065)
		(layer "In5.Cu")
		(net "PHY_DRV_B_TO_SCC_B_13_DP")
	)
	(segment
		(start 69.31787 -135.584692)
		(end 68.97751 -135.461248)
		(width 0.12065)
		(layer "In5.Cu")
		(net "PHY_DRV_B_TO_SCC_B_13_DP")
	)
	(segment
		(start 71.702676 -136.23544)
		(end 71.442326 -136.357106)
		(width 0.12065)
		(layer "In5.Cu")
		(net "PHY_DRV_B_TO_SCC_B_13_DP")
	)
	(segment
		(start 264.613136 -212.632798)
		(end 196.87413 -168.645332)
		(width 0.12065)
		(layer "In5.Cu")
		(net "PHY_DRV_B_TO_SCC_B_13_DP")
	)
	(segment
		(start 70.380098 -135.970772)
		(end 70.039992 -135.847328)
		(width 0.12065)
		(layer "In5.Cu")
		(net "PHY_DRV_B_TO_SCC_B_13_DP")
	)
	(segment
		(start 70.980554 -135.973058)
		(end 70.640448 -135.84936)
		(width 0.12065)
		(layer "In5.Cu")
		(net "PHY_DRV_B_TO_SCC_B_13_DP")
	)
	(segment
		(start 90.04808 -145.939764)
		(end 79.425038 -139.042394)
		(width 0.12065)
		(layer "In5.Cu")
		(net "PHY_DRV_B_TO_SCC_B_13_DP")
	)
	(segment
		(start 64.0588 -134.038848)
		(end 64.0588 -134.38505)
		(width 0.12065)
		(layer "In5.Cu")
		(net "PHY_DRV_B_TO_SCC_B_13_DP")
	)
	(segment
		(start 196.87413 -168.645332)
		(end 90.04808 -145.939764)
		(width 0.12065)
		(layer "In5.Cu")
		(net "PHY_DRV_B_TO_SCC_B_13_DP")
	)
	(segment
		(start 68.856098 -135.200644)
		(end 65.32753 -133.918198)
		(width 0.12065)
		(layer "In5.Cu")
		(net "PHY_DRV_B_TO_SCC_B_13_DP")
	)
	(segment
		(start 69.57822 -135.46328)
		(end 69.31787 -135.584692)
		(width 0.12065)
		(layer "In5.Cu")
		(net "PHY_DRV_B_TO_SCC_B_13_DP")
	)
	(segment
		(start 285.436564 -215.294464)
		(end 285.805118 -215.294464)
		(width 0.12065)
		(layer "In5.Cu")
		(net "PHY_DRV_B_TO_SCC_B_13_DP")
	)
	(segment
		(start 71.10222 -136.233408)
		(end 70.980554 -135.973058)
		(width 0.12065)
		(layer "In5.Cu")
		(net "PHY_DRV_B_TO_SCC_B_13_DP")
	)
	(segment
		(start 285.968186 -215.131396)
		(end 285.968186 -214.902796)
		(width 0.12065)
		(layer "In5.Cu")
		(net "PHY_DRV_B_TO_SCC_B_13_DP")
	)
	(segment
		(start 65.32753 -133.918198)
		(end 64.17945 -133.918198)
		(width 0.12065)
		(layer "In5.Cu")
		(net "PHY_DRV_B_TO_SCC_B_13_DP")
	)
	(segment
		(start 273.68373 -214.56269)
		(end 264.613136 -212.632798)
		(width 0.12065)
		(layer "In5.Cu")
		(net "PHY_DRV_B_TO_SCC_B_13_DP")
	)
	(segment
		(start 68.97751 -135.461248)
		(end 68.856098 -135.200644)
		(width 0.12065)
		(layer "In5.Cu")
		(net "PHY_DRV_B_TO_SCC_B_13_DP")
	)
	(segment
		(start 70.039992 -135.847328)
		(end 69.918326 -135.586978)
		(width 0.12065)
		(layer "In5.Cu")
		(net "PHY_DRV_B_TO_SCC_B_13_DP")
	)
	(segment
		(start 285.62808 -214.56269)
		(end 273.68373 -214.56269)
		(width 0.12065)
		(layer "In5.Cu")
		(net "PHY_DRV_B_TO_SCC_B_13_DP")
	)
	(segment
		(start 70.640448 -135.84936)
		(end 70.380098 -135.970772)
		(width 0.12065)
		(layer "In5.Cu")
		(net "PHY_DRV_B_TO_SCC_B_13_DP")
	)
	(segment
		(start 79.425038 -139.042394)
		(end 71.702676 -136.23544)
		(width 0.12065)
		(layer "In5.Cu")
		(net "PHY_DRV_B_TO_SCC_B_13_DP")
	)
	(segment
		(start 71.442326 -136.357106)
		(end 71.10222 -136.233408)
		(width 0.12065)
		(layer "In5.Cu")
		(net "PHY_DRV_B_TO_SCC_B_13_DP")
	)
	(arc
		(start 64.17945 -133.918198)
		(mid 64.094138 -133.953536)
		(end 64.0588 -134.038848)
		(width 0.12065)
		(layer "In5.Cu")
		(net "PHY_DRV_B_TO_SCC_B_13_DP")
	)
	(arc
		(start 285.805118 -215.294464)
		(mid 285.920424 -215.246702)
		(end 285.968186 -215.131396)
		(width 0.12065)
		(layer "In5.Cu")
		(net "PHY_DRV_B_TO_SCC_B_13_DP")
	)
	(arc
		(start 285.968186 -214.902796)
		(mid 285.868571 -214.662305)
		(end 285.62808 -214.56269)
		(width 0.12065)
		(layer "In5.Cu")
		(net "PHY_DRV_B_TO_SCC_B_13_DP")
	)
	(segment
		(start 61.574934 -133.11505)
		(end 62.90945 -133.11505)
		(width 0.127)
		(layer "F.Cu")
		(net "PHY_DRV_B_TO_SCC_B_13_DN")
	)
	(segment
		(start 63.03645 -133.24205)
		(end 63.03645 -133.477)
		(width 0.127)
		(layer "F.Cu")
		(net "PHY_DRV_B_TO_SCC_B_13_DN")
	)
	(segment
		(start 63.16345 -133.604)
		(end 63.9318 -133.604)
		(width 0.127)
		(layer "F.Cu")
		(net "PHY_DRV_B_TO_SCC_B_13_DN")
	)
	(segment
		(start 64.0588 -133.477)
		(end 64.0588 -133.11505)
		(width 0.127)
		(layer "F.Cu")
		(net "PHY_DRV_B_TO_SCC_B_13_DN")
	)
	(segment
		(start 62.90945 -133.11505)
		(end 63.03645 -133.24205)
		(width 0.127)
		(layer "F.Cu")
		(net "PHY_DRV_B_TO_SCC_B_13_DN")
	)
	(segment
		(start 63.03645 -133.477)
		(end 63.16345 -133.604)
		(width 0.127)
		(layer "F.Cu")
		(net "PHY_DRV_B_TO_SCC_B_13_DN")
	)
	(arc
		(start 63.9318 -133.604)
		(mid 64.021603 -133.566803)
		(end 64.0588 -133.477)
		(width 0.127)
		(layer "F.Cu")
		(net "PHY_DRV_B_TO_SCC_B_13_DN")
	)
	(segment
		(start 273.71929 -214.22614)
		(end 264.7442 -212.316568)
		(width 0.12065)
		(layer "In5.Cu")
		(net "PHY_DRV_B_TO_SCC_B_13_DN")
	)
	(segment
		(start 90.179144 -145.623534)
		(end 79.576168 -138.739118)
		(width 0.12065)
		(layer "In5.Cu")
		(net "PHY_DRV_B_TO_SCC_B_13_DN")
	)
	(segment
		(start 286.836612 -215.294464)
		(end 286.467804 -215.294464)
		(width 0.12065)
		(layer "In5.Cu")
		(net "PHY_DRV_B_TO_SCC_B_13_DN")
	)
	(segment
		(start 79.576168 -138.739118)
		(end 65.38722 -133.581648)
		(width 0.12065)
		(layer "In5.Cu")
		(net "PHY_DRV_B_TO_SCC_B_13_DN")
	)
	(segment
		(start 264.7442 -212.316568)
		(end 197.005194 -168.329102)
		(width 0.12065)
		(layer "In5.Cu")
		(net "PHY_DRV_B_TO_SCC_B_13_DN")
	)
	(segment
		(start 286.304736 -215.131396)
		(end 286.304736 -214.902796)
		(width 0.12065)
		(layer "In5.Cu")
		(net "PHY_DRV_B_TO_SCC_B_13_DN")
	)
	(segment
		(start 65.38722 -133.581648)
		(end 64.17945 -133.581648)
		(width 0.12065)
		(layer "In5.Cu")
		(net "PHY_DRV_B_TO_SCC_B_13_DN")
	)
	(segment
		(start 64.0588 -133.460998)
		(end 64.0588 -133.11505)
		(width 0.12065)
		(layer "In5.Cu")
		(net "PHY_DRV_B_TO_SCC_B_13_DN")
	)
	(segment
		(start 197.005194 -168.329102)
		(end 90.179144 -145.623534)
		(width 0.12065)
		(layer "In5.Cu")
		(net "PHY_DRV_B_TO_SCC_B_13_DN")
	)
	(segment
		(start 285.62808 -214.22614)
		(end 273.71929 -214.22614)
		(width 0.12065)
		(layer "In5.Cu")
		(net "PHY_DRV_B_TO_SCC_B_13_DN")
	)
	(arc
		(start 286.304736 -214.902796)
		(mid 286.106548 -214.424328)
		(end 285.62808 -214.22614)
		(width 0.12065)
		(layer "In5.Cu")
		(net "PHY_DRV_B_TO_SCC_B_13_DN")
	)
	(arc
		(start 286.467804 -215.294464)
		(mid 286.352498 -215.246702)
		(end 286.304736 -215.131396)
		(width 0.12065)
		(layer "In5.Cu")
		(net "PHY_DRV_B_TO_SCC_B_13_DN")
	)
	(arc
		(start 64.17945 -133.581648)
		(mid 64.094138 -133.54631)
		(end 64.0588 -133.460998)
		(width 0.12065)
		(layer "In5.Cu")
		(net "PHY_DRV_B_TO_SCC_B_13_DN")
	)
	(segment
		(start 31.613602 -133.8961)
		(end 32.381952 -133.8961)
		(width 0.127)
		(layer "F.Cu")
		(net "PHY_DRV_B_TO_SCC_B_12_DP")
	)
	(segment
		(start 31.486602 -134.0231)
		(end 31.613602 -133.8961)
		(width 0.127)
		(layer "F.Cu")
		(net "PHY_DRV_B_TO_SCC_B_12_DP")
	)
	(segment
		(start 31.359602 -134.38505)
		(end 31.486602 -134.25805)
		(width 0.127)
		(layer "F.Cu")
		(net "PHY_DRV_B_TO_SCC_B_12_DP")
	)
	(segment
		(start 30.025086 -134.38505)
		(end 31.359602 -134.38505)
		(width 0.127)
		(layer "F.Cu")
		(net "PHY_DRV_B_TO_SCC_B_12_DP")
	)
	(segment
		(start 31.486602 -134.25805)
		(end 31.486602 -134.0231)
		(width 0.127)
		(layer "F.Cu")
		(net "PHY_DRV_B_TO_SCC_B_12_DP")
	)
	(segment
		(start 32.508952 -134.0231)
		(end 32.508952 -134.38505)
		(width 0.127)
		(layer "F.Cu")
		(net "PHY_DRV_B_TO_SCC_B_12_DP")
	)
	(arc
		(start 32.381952 -133.8961)
		(mid 32.471755 -133.933297)
		(end 32.508952 -134.0231)
		(width 0.127)
		(layer "F.Cu")
		(net "PHY_DRV_B_TO_SCC_B_12_DP")
	)
	(segment
		(start 286.628078 -216.362788)
		(end 270.238982 -216.362788)
		(width 0.12065)
		(layer "In5.Cu")
		(net "PHY_DRV_B_TO_SCC_B_12_DP")
	)
	(segment
		(start 38.669722 -136.199118)
		(end 38.351206 -136.027414)
		(width 0.12065)
		(layer "In5.Cu")
		(net "PHY_DRV_B_TO_SCC_B_12_DP")
	)
	(segment
		(start 37.251894 -135.192008)
		(end 34.890964 -133.918198)
		(width 0.12065)
		(layer "In5.Cu")
		(net "PHY_DRV_B_TO_SCC_B_12_DP")
	)
	(segment
		(start 37.946076 -135.566404)
		(end 37.657024 -135.653018)
		(width 0.12065)
		(layer "In5.Cu")
		(net "PHY_DRV_B_TO_SCC_B_12_DP")
	)
	(segment
		(start 39.971472 -136.659112)
		(end 39.68242 -136.745472)
		(width 0.12065)
		(layer "In5.Cu")
		(net "PHY_DRV_B_TO_SCC_B_12_DP")
	)
	(segment
		(start 38.958774 -136.112758)
		(end 38.669722 -136.199118)
		(width 0.12065)
		(layer "In5.Cu")
		(net "PHY_DRV_B_TO_SCC_B_12_DP")
	)
	(segment
		(start 39.68242 -136.745472)
		(end 39.36365 -136.573768)
		(width 0.12065)
		(layer "In5.Cu")
		(net "PHY_DRV_B_TO_SCC_B_12_DP")
	)
	(segment
		(start 32.508952 -134.038848)
		(end 32.508952 -134.38505)
		(width 0.12065)
		(layer "In5.Cu")
		(net "PHY_DRV_B_TO_SCC_B_12_DP")
	)
	(segment
		(start 286.436562 -217.094562)
		(end 286.805116 -217.094562)
		(width 0.12065)
		(layer "In5.Cu")
		(net "PHY_DRV_B_TO_SCC_B_12_DP")
	)
	(segment
		(start 37.338508 -135.48106)
		(end 37.251894 -135.192008)
		(width 0.12065)
		(layer "In5.Cu")
		(net "PHY_DRV_B_TO_SCC_B_12_DP")
	)
	(segment
		(start 264.543794 -215.152224)
		(end 202.246484 -174.692564)
		(width 0.12065)
		(layer "In5.Cu")
		(net "PHY_DRV_B_TO_SCC_B_12_DP")
	)
	(segment
		(start 38.264592 -135.738362)
		(end 37.946076 -135.566404)
		(width 0.12065)
		(layer "In5.Cu")
		(net "PHY_DRV_B_TO_SCC_B_12_DP")
	)
	(segment
		(start 50.801016 -142.501874)
		(end 39.971472 -136.659112)
		(width 0.12065)
		(layer "In5.Cu")
		(net "PHY_DRV_B_TO_SCC_B_12_DP")
	)
	(segment
		(start 37.657024 -135.653018)
		(end 37.338508 -135.48106)
		(width 0.12065)
		(layer "In5.Cu")
		(net "PHY_DRV_B_TO_SCC_B_12_DP")
	)
	(segment
		(start 202.246484 -174.692564)
		(end 50.801016 -142.501874)
		(width 0.12065)
		(layer "In5.Cu")
		(net "PHY_DRV_B_TO_SCC_B_12_DP")
	)
	(segment
		(start 286.968184 -216.931494)
		(end 286.968184 -216.702894)
		(width 0.12065)
		(layer "In5.Cu")
		(net "PHY_DRV_B_TO_SCC_B_12_DP")
	)
	(segment
		(start 34.890964 -133.918198)
		(end 32.629602 -133.918198)
		(width 0.12065)
		(layer "In5.Cu")
		(net "PHY_DRV_B_TO_SCC_B_12_DP")
	)
	(segment
		(start 39.36365 -136.573768)
		(end 39.27729 -136.284716)
		(width 0.12065)
		(layer "In5.Cu")
		(net "PHY_DRV_B_TO_SCC_B_12_DP")
	)
	(segment
		(start 39.27729 -136.284716)
		(end 38.958774 -136.112758)
		(width 0.12065)
		(layer "In5.Cu")
		(net "PHY_DRV_B_TO_SCC_B_12_DP")
	)
	(segment
		(start 38.351206 -136.027414)
		(end 38.264592 -135.738362)
		(width 0.12065)
		(layer "In5.Cu")
		(net "PHY_DRV_B_TO_SCC_B_12_DP")
	)
	(segment
		(start 270.238982 -216.362788)
		(end 264.543794 -215.152224)
		(width 0.12065)
		(layer "In5.Cu")
		(net "PHY_DRV_B_TO_SCC_B_12_DP")
	)
	(arc
		(start 32.629602 -133.918198)
		(mid 32.54429 -133.953536)
		(end 32.508952 -134.038848)
		(width 0.12065)
		(layer "In5.Cu")
		(net "PHY_DRV_B_TO_SCC_B_12_DP")
	)
	(arc
		(start 286.805116 -217.094562)
		(mid 286.920422 -217.0468)
		(end 286.968184 -216.931494)
		(width 0.12065)
		(layer "In5.Cu")
		(net "PHY_DRV_B_TO_SCC_B_12_DP")
	)
	(arc
		(start 286.968184 -216.702894)
		(mid 286.868569 -216.462403)
		(end 286.628078 -216.362788)
		(width 0.12065)
		(layer "In5.Cu")
		(net "PHY_DRV_B_TO_SCC_B_12_DP")
	)
	(segment
		(start 31.486602 -133.477)
		(end 31.613602 -133.604)
		(width 0.127)
		(layer "F.Cu")
		(net "PHY_DRV_B_TO_SCC_B_12_DN")
	)
	(segment
		(start 30.025086 -133.11505)
		(end 31.359602 -133.11505)
		(width 0.127)
		(layer "F.Cu")
		(net "PHY_DRV_B_TO_SCC_B_12_DN")
	)
	(segment
		(start 31.486602 -133.24205)
		(end 31.486602 -133.477)
		(width 0.127)
		(layer "F.Cu")
		(net "PHY_DRV_B_TO_SCC_B_12_DN")
	)
	(segment
		(start 31.613602 -133.604)
		(end 32.381952 -133.604)
		(width 0.127)
		(layer "F.Cu")
		(net "PHY_DRV_B_TO_SCC_B_12_DN")
	)
	(segment
		(start 32.508952 -133.477)
		(end 32.508952 -133.11505)
		(width 0.127)
		(layer "F.Cu")
		(net "PHY_DRV_B_TO_SCC_B_12_DN")
	)
	(segment
		(start 31.359602 -133.11505)
		(end 31.486602 -133.24205)
		(width 0.127)
		(layer "F.Cu")
		(net "PHY_DRV_B_TO_SCC_B_12_DN")
	)
	(arc
		(start 32.381952 -133.604)
		(mid 32.471755 -133.566803)
		(end 32.508952 -133.477)
		(width 0.127)
		(layer "F.Cu")
		(net "PHY_DRV_B_TO_SCC_B_12_DN")
	)
	(segment
		(start 37.411914 -134.895844)
		(end 34.976054 -133.581648)
		(width 0.12065)
		(layer "In5.Cu")
		(net "PHY_DRV_B_TO_SCC_B_12_DN")
	)
	(segment
		(start 287.83661 -217.094562)
		(end 287.467802 -217.094562)
		(width 0.12065)
		(layer "In5.Cu")
		(net "PHY_DRV_B_TO_SCC_B_12_DN")
	)
	(segment
		(start 40.131238 -136.362694)
		(end 37.411914 -134.89559)
		(width 0.12065)
		(layer "In5.Cu")
		(net "PHY_DRV_B_TO_SCC_B_12_DN")
	)
	(segment
		(start 50.918364 -142.182596)
		(end 40.131492 -136.362948)
		(width 0.12065)
		(layer "In5.Cu")
		(net "PHY_DRV_B_TO_SCC_B_12_DN")
	)
	(segment
		(start 264.674858 -214.835994)
		(end 202.377548 -174.376334)
		(width 0.12065)
		(layer "In5.Cu")
		(net "PHY_DRV_B_TO_SCC_B_12_DN")
	)
	(segment
		(start 37.411914 -134.89559)
		(end 37.411914 -134.895844)
		(width 0.12065)
		(layer "In5.Cu")
		(net "PHY_DRV_B_TO_SCC_B_12_DN")
	)
	(segment
		(start 40.131492 -136.362948)
		(end 40.131238 -136.362694)
		(width 0.12065)
		(layer "In5.Cu")
		(net "PHY_DRV_B_TO_SCC_B_12_DN")
	)
	(segment
		(start 287.304734 -216.931494)
		(end 287.304734 -216.702894)
		(width 0.12065)
		(layer "In5.Cu")
		(net "PHY_DRV_B_TO_SCC_B_12_DN")
	)
	(segment
		(start 270.274542 -216.026238)
		(end 264.674858 -214.835994)
		(width 0.12065)
		(layer "In5.Cu")
		(net "PHY_DRV_B_TO_SCC_B_12_DN")
	)
	(segment
		(start 34.976054 -133.581648)
		(end 32.629602 -133.581648)
		(width 0.12065)
		(layer "In5.Cu")
		(net "PHY_DRV_B_TO_SCC_B_12_DN")
	)
	(segment
		(start 286.628078 -216.026238)
		(end 270.274542 -216.026238)
		(width 0.12065)
		(layer "In5.Cu")
		(net "PHY_DRV_B_TO_SCC_B_12_DN")
	)
	(segment
		(start 32.508952 -133.460998)
		(end 32.508952 -133.11505)
		(width 0.12065)
		(layer "In5.Cu")
		(net "PHY_DRV_B_TO_SCC_B_12_DN")
	)
	(segment
		(start 202.377548 -174.376334)
		(end 50.918364 -142.182596)
		(width 0.12065)
		(layer "In5.Cu")
		(net "PHY_DRV_B_TO_SCC_B_12_DN")
	)
	(arc
		(start 287.304734 -216.702894)
		(mid 287.106546 -216.224426)
		(end 286.628078 -216.026238)
		(width 0.12065)
		(layer "In5.Cu")
		(net "PHY_DRV_B_TO_SCC_B_12_DN")
	)
	(arc
		(start 32.629602 -133.581648)
		(mid 32.54429 -133.54631)
		(end 32.508952 -133.460998)
		(width 0.12065)
		(layer "In5.Cu")
		(net "PHY_DRV_B_TO_SCC_B_12_DN")
	)
	(arc
		(start 287.467802 -217.094562)
		(mid 287.352496 -217.0468)
		(end 287.304734 -216.931494)
		(width 0.12065)
		(layer "In5.Cu")
		(net "PHY_DRV_B_TO_SCC_B_12_DN")
	)
	(segment
		(start 485.125014 -249.385074)
		(end 483.827074 -249.385074)
		(width 0.127)
		(layer "F.Cu")
		(net "PHY_DRV_B_TO_SCC_B_11_DP")
	)
	(segment
		(start 481.339652 -249.064272)
		(end 481.339652 -249.385074)
		(width 0.127)
		(layer "F.Cu")
		(net "PHY_DRV_B_TO_SCC_B_11_DP")
	)
	(segment
		(start 483.827074 -249.385074)
		(end 483.663498 -249.221498)
		(width 0.127)
		(layer "F.Cu")
		(net "PHY_DRV_B_TO_SCC_B_11_DP")
	)
	(segment
		(start 483.663498 -249.023124)
		(end 483.536498 -248.896124)
		(width 0.127)
		(layer "F.Cu")
		(net "PHY_DRV_B_TO_SCC_B_11_DP")
	)
	(segment
		(start 483.536498 -248.896124)
		(end 481.5078 -248.896124)
		(width 0.127)
		(layer "F.Cu")
		(net "PHY_DRV_B_TO_SCC_B_11_DP")
	)
	(segment
		(start 483.663498 -249.221498)
		(end 483.663498 -249.023124)
		(width 0.127)
		(layer "F.Cu")
		(net "PHY_DRV_B_TO_SCC_B_11_DP")
	)
	(arc
		(start 481.5078 -248.896124)
		(mid 481.388901 -248.945373)
		(end 481.339652 -249.064272)
		(width 0.127)
		(layer "F.Cu")
		(net "PHY_DRV_B_TO_SCC_B_11_DP")
	)
	(segment
		(start 452.830946 -234.788456)
		(end 467.197948 -239.103154)
		(width 0.12065)
		(layer "In5.Cu")
		(net "PHY_DRV_B_TO_SCC_B_11_DP")
	)
	(segment
		(start 291.866574 -219.96273)
		(end 439.039508 -231.021636)
		(width 0.12065)
		(layer "In5.Cu")
		(net "PHY_DRV_B_TO_SCC_B_11_DP")
	)
	(segment
		(start 481.339652 -249.105674)
		(end 481.339652 -249.385074)
		(width 0.12065)
		(layer "In5.Cu")
		(net "PHY_DRV_B_TO_SCC_B_11_DP")
	)
	(segment
		(start 467.197948 -239.103154)
		(end 472.468956 -242.119912)
		(width 0.12065)
		(layer "In5.Cu")
		(net "PHY_DRV_B_TO_SCC_B_11_DP")
	)
	(segment
		(start 472.468956 -242.119912)
		(end 476.416624 -247.507506)
		(width 0.12065)
		(layer "In5.Cu")
		(net "PHY_DRV_B_TO_SCC_B_11_DP")
	)
	(segment
		(start 286.576516 -219.96273)
		(end 291.866574 -219.96273)
		(width 0.12065)
		(layer "In5.Cu")
		(net "PHY_DRV_B_TO_SCC_B_11_DP")
	)
	(segment
		(start 477.808544 -248.213118)
		(end 479.199702 -248.918222)
		(width 0.12065)
		(layer "In5.Cu")
		(net "PHY_DRV_B_TO_SCC_B_11_DP")
	)
	(segment
		(start 479.199702 -248.918222)
		(end 481.1522 -248.918222)
		(width 0.12065)
		(layer "In5.Cu")
		(net "PHY_DRV_B_TO_SCC_B_11_DP")
	)
	(segment
		(start 285.968186 -219.1004)
		(end 285.968186 -219.3544)
		(width 0.12065)
		(layer "In5.Cu")
		(net "PHY_DRV_B_TO_SCC_B_11_DP")
	)
	(segment
		(start 445.935608 -232.9053)
		(end 452.830946 -234.788456)
		(width 0.12065)
		(layer "In5.Cu")
		(net "PHY_DRV_B_TO_SCC_B_11_DP")
	)
	(segment
		(start 476.416624 -247.507506)
		(end 477.808544 -248.213118)
		(width 0.12065)
		(layer "In5.Cu")
		(net "PHY_DRV_B_TO_SCC_B_11_DP")
	)
	(segment
		(start 285.436564 -218.894406)
		(end 285.762192 -218.894406)
		(width 0.12065)
		(layer "In5.Cu")
		(net "PHY_DRV_B_TO_SCC_B_11_DP")
	)
	(segment
		(start 439.039508 -231.021636)
		(end 440.078114 -231.305354)
		(width 0.12065)
		(layer "In5.Cu")
		(net "PHY_DRV_B_TO_SCC_B_11_DP")
	)
	(segment
		(start 440.078114 -231.305354)
		(end 445.935608 -232.9053)
		(width 0.12065)
		(layer "In5.Cu")
		(net "PHY_DRV_B_TO_SCC_B_11_DP")
	)
	(arc
		(start 285.762192 -218.894406)
		(mid 285.907852 -218.95474)
		(end 285.968186 -219.1004)
		(width 0.12065)
		(layer "In5.Cu")
		(net "PHY_DRV_B_TO_SCC_B_11_DP")
	)
	(arc
		(start 481.1522 -248.918222)
		(mid 481.284749 -248.973125)
		(end 481.339652 -249.105674)
		(width 0.12065)
		(layer "In5.Cu")
		(net "PHY_DRV_B_TO_SCC_B_11_DP")
	)
	(arc
		(start 285.968186 -219.3544)
		(mid 286.146362 -219.784554)
		(end 286.576516 -219.96273)
		(width 0.12065)
		(layer "In5.Cu")
		(net "PHY_DRV_B_TO_SCC_B_11_DP")
	)
	(segment
		(start 481.339652 -248.435876)
		(end 481.339652 -248.115074)
		(width 0.127)
		(layer "F.Cu")
		(net "PHY_DRV_B_TO_SCC_B_11_DN")
	)
	(segment
		(start 483.663498 -248.242074)
		(end 483.663498 -248.477024)
		(width 0.127)
		(layer "F.Cu")
		(net "PHY_DRV_B_TO_SCC_B_11_DN")
	)
	(segment
		(start 483.663498 -248.477024)
		(end 483.536498 -248.604024)
		(width 0.127)
		(layer "F.Cu")
		(net "PHY_DRV_B_TO_SCC_B_11_DN")
	)
	(segment
		(start 485.125014 -248.115074)
		(end 483.790498 -248.115074)
		(width 0.127)
		(layer "F.Cu")
		(net "PHY_DRV_B_TO_SCC_B_11_DN")
	)
	(segment
		(start 483.790498 -248.115074)
		(end 483.663498 -248.242074)
		(width 0.127)
		(layer "F.Cu")
		(net "PHY_DRV_B_TO_SCC_B_11_DN")
	)
	(segment
		(start 483.536498 -248.604024)
		(end 481.5078 -248.604024)
		(width 0.127)
		(layer "F.Cu")
		(net "PHY_DRV_B_TO_SCC_B_11_DN")
	)
	(arc
		(start 481.5078 -248.604024)
		(mid 481.388901 -248.554775)
		(end 481.339652 -248.435876)
		(width 0.127)
		(layer "F.Cu")
		(net "PHY_DRV_B_TO_SCC_B_11_DN")
	)
	(segment
		(start 286.304736 -219.1004)
		(end 286.304736 -219.3544)
		(width 0.12065)
		(layer "In5.Cu")
		(net "PHY_DRV_B_TO_SCC_B_11_DN")
	)
	(segment
		(start 472.698318 -241.863118)
		(end 476.640652 -247.2436)
		(width 0.12065)
		(layer "In5.Cu")
		(net "PHY_DRV_B_TO_SCC_B_11_DN")
	)
	(segment
		(start 467.331806 -238.79175)
		(end 472.698318 -241.863118)
		(width 0.12065)
		(layer "In5.Cu")
		(net "PHY_DRV_B_TO_SCC_B_11_DN")
	)
	(segment
		(start 464.084162 -237.81639)
		(end 464.337146 -237.680246)
		(width 0.12065)
		(layer "In5.Cu")
		(net "PHY_DRV_B_TO_SCC_B_11_DN")
	)
	(segment
		(start 443.095888 -231.780588)
		(end 446.024254 -232.580434)
		(width 0.12065)
		(layer "In5.Cu")
		(net "PHY_DRV_B_TO_SCC_B_11_DN")
	)
	(segment
		(start 479.28022 -248.581672)
		(end 481.152454 -248.581672)
		(width 0.12065)
		(layer "In5.Cu")
		(net "PHY_DRV_B_TO_SCC_B_11_DN")
	)
	(segment
		(start 464.683856 -237.784386)
		(end 464.82 -238.03737)
		(width 0.12065)
		(layer "In5.Cu")
		(net "PHY_DRV_B_TO_SCC_B_11_DN")
	)
	(segment
		(start 465.419694 -238.005366)
		(end 465.766404 -238.109506)
		(width 0.12065)
		(layer "In5.Cu")
		(net "PHY_DRV_B_TO_SCC_B_11_DN")
	)
	(segment
		(start 466.502242 -238.330486)
		(end 466.848952 -238.434626)
		(width 0.12065)
		(layer "In5.Cu")
		(net "PHY_DRV_B_TO_SCC_B_11_DN")
	)
	(segment
		(start 464.337146 -237.680246)
		(end 464.683856 -237.784386)
		(width 0.12065)
		(layer "In5.Cu")
		(net "PHY_DRV_B_TO_SCC_B_11_DN")
	)
	(segment
		(start 452.923656 -234.46486)
		(end 464.084162 -237.81639)
		(width 0.12065)
		(layer "In5.Cu")
		(net "PHY_DRV_B_TO_SCC_B_11_DN")
	)
	(segment
		(start 481.339652 -248.394474)
		(end 481.339652 -248.115074)
		(width 0.12065)
		(layer "In5.Cu")
		(net "PHY_DRV_B_TO_SCC_B_11_DN")
	)
	(segment
		(start 466.249258 -238.46663)
		(end 466.502242 -238.330486)
		(width 0.12065)
		(layer "In5.Cu")
		(net "PHY_DRV_B_TO_SCC_B_11_DN")
	)
	(segment
		(start 291.88156 -219.62618)
		(end 439.096912 -230.688388)
		(width 0.12065)
		(layer "In5.Cu")
		(net "PHY_DRV_B_TO_SCC_B_11_DN")
	)
	(segment
		(start 477.96069 -247.91289)
		(end 479.28022 -248.581672)
		(width 0.12065)
		(layer "In5.Cu")
		(net "PHY_DRV_B_TO_SCC_B_11_DN")
	)
	(segment
		(start 465.902548 -238.36249)
		(end 466.249258 -238.46663)
		(width 0.12065)
		(layer "In5.Cu")
		(net "PHY_DRV_B_TO_SCC_B_11_DN")
	)
	(segment
		(start 465.16671 -238.14151)
		(end 465.419694 -238.005366)
		(width 0.12065)
		(layer "In5.Cu")
		(net "PHY_DRV_B_TO_SCC_B_11_DN")
	)
	(segment
		(start 464.82 -238.03737)
		(end 465.16671 -238.14151)
		(width 0.12065)
		(layer "In5.Cu")
		(net "PHY_DRV_B_TO_SCC_B_11_DN")
	)
	(segment
		(start 466.985096 -238.68761)
		(end 467.331806 -238.79175)
		(width 0.12065)
		(layer "In5.Cu")
		(net "PHY_DRV_B_TO_SCC_B_11_DN")
	)
	(segment
		(start 476.640652 -247.2436)
		(end 477.96069 -247.91289)
		(width 0.12065)
		(layer "In5.Cu")
		(net "PHY_DRV_B_TO_SCC_B_11_DN")
	)
	(segment
		(start 446.024254 -232.580434)
		(end 452.923656 -234.46486)
		(width 0.12065)
		(layer "In5.Cu")
		(net "PHY_DRV_B_TO_SCC_B_11_DN")
	)
	(segment
		(start 286.836612 -218.894406)
		(end 286.51073 -218.894406)
		(width 0.12065)
		(layer "In5.Cu")
		(net "PHY_DRV_B_TO_SCC_B_11_DN")
	)
	(segment
		(start 466.848952 -238.434626)
		(end 466.985096 -238.68761)
		(width 0.12065)
		(layer "In5.Cu")
		(net "PHY_DRV_B_TO_SCC_B_11_DN")
	)
	(segment
		(start 465.766404 -238.109506)
		(end 465.902548 -238.36249)
		(width 0.12065)
		(layer "In5.Cu")
		(net "PHY_DRV_B_TO_SCC_B_11_DN")
	)
	(segment
		(start 286.576516 -219.62618)
		(end 291.88156 -219.62618)
		(width 0.12065)
		(layer "In5.Cu")
		(net "PHY_DRV_B_TO_SCC_B_11_DN")
	)
	(segment
		(start 439.096912 -230.688388)
		(end 443.095888 -231.780588)
		(width 0.12065)
		(layer "In5.Cu")
		(net "PHY_DRV_B_TO_SCC_B_11_DN")
	)
	(arc
		(start 286.51073 -218.894406)
		(mid 286.36507 -218.95474)
		(end 286.304736 -219.1004)
		(width 0.12065)
		(layer "In5.Cu")
		(net "PHY_DRV_B_TO_SCC_B_11_DN")
	)
	(arc
		(start 286.304736 -219.3544)
		(mid 286.384339 -219.546577)
		(end 286.576516 -219.62618)
		(width 0.12065)
		(layer "In5.Cu")
		(net "PHY_DRV_B_TO_SCC_B_11_DN")
	)
	(arc
		(start 481.152454 -248.581672)
		(mid 481.284823 -248.526843)
		(end 481.339652 -248.394474)
		(width 0.12065)
		(layer "In5.Cu")
		(net "PHY_DRV_B_TO_SCC_B_11_DN")
	)
	(segment
		(start 452.113396 -249.023124)
		(end 451.986396 -248.896124)
		(width 0.127)
		(layer "F.Cu")
		(net "PHY_DRV_B_TO_SCC_B_10_DP")
	)
	(segment
		(start 453.574912 -249.385074)
		(end 452.254874 -249.385074)
		(width 0.127)
		(layer "F.Cu")
		(net "PHY_DRV_B_TO_SCC_B_10_DP")
	)
	(segment
		(start 449.78955 -249.023124)
		(end 449.78955 -249.385074)
		(width 0.127)
		(layer "F.Cu")
		(net "PHY_DRV_B_TO_SCC_B_10_DP")
	)
	(segment
		(start 452.254874 -249.385074)
		(end 452.113396 -249.243596)
		(width 0.127)
		(layer "F.Cu")
		(net "PHY_DRV_B_TO_SCC_B_10_DP")
	)
	(segment
		(start 452.113396 -249.243596)
		(end 452.113396 -249.023124)
		(width 0.127)
		(layer "F.Cu")
		(net "PHY_DRV_B_TO_SCC_B_10_DP")
	)
	(segment
		(start 451.986396 -248.896124)
		(end 449.91655 -248.896124)
		(width 0.127)
		(layer "F.Cu")
		(net "PHY_DRV_B_TO_SCC_B_10_DP")
	)
	(arc
		(start 449.91655 -248.896124)
		(mid 449.826747 -248.933321)
		(end 449.78955 -249.023124)
		(width 0.127)
		(layer "F.Cu")
		(net "PHY_DRV_B_TO_SCC_B_10_DP")
	)
	(segment
		(start 448.769232 -248.918222)
		(end 449.6689 -248.918222)
		(width 0.12065)
		(layer "In5.Cu")
		(net "PHY_DRV_B_TO_SCC_B_10_DP")
	)
	(segment
		(start 449.78955 -249.038872)
		(end 449.78955 -249.385074)
		(width 0.12065)
		(layer "In5.Cu")
		(net "PHY_DRV_B_TO_SCC_B_10_DP")
	)
	(segment
		(start 405.355806 -232.58526)
		(end 442.451236 -246.54129)
		(width 0.12065)
		(layer "In5.Cu")
		(net "PHY_DRV_B_TO_SCC_B_10_DP")
	)
	(segment
		(start 442.451236 -246.54129)
		(end 442.450982 -246.541544)
		(width 0.12065)
		(layer "In5.Cu")
		(net "PHY_DRV_B_TO_SCC_B_10_DP")
	)
	(segment
		(start 286.436562 -220.694504)
		(end 286.784288 -220.694504)
		(width 0.12065)
		(layer "In5.Cu")
		(net "PHY_DRV_B_TO_SCC_B_10_DP")
	)
	(segment
		(start 286.968184 -220.8784)
		(end 286.968184 -221.1324)
		(width 0.12065)
		(layer "In5.Cu")
		(net "PHY_DRV_B_TO_SCC_B_10_DP")
	)
	(segment
		(start 442.450982 -246.541544)
		(end 448.769232 -248.918222)
		(width 0.12065)
		(layer "In5.Cu")
		(net "PHY_DRV_B_TO_SCC_B_10_DP")
	)
	(segment
		(start 291.137848 -221.762828)
		(end 405.355806 -232.58526)
		(width 0.12065)
		(layer "In5.Cu")
		(net "PHY_DRV_B_TO_SCC_B_10_DP")
	)
	(segment
		(start 287.598612 -221.762828)
		(end 291.137848 -221.762828)
		(width 0.12065)
		(layer "In5.Cu")
		(net "PHY_DRV_B_TO_SCC_B_10_DP")
	)
	(arc
		(start 286.968184 -221.1324)
		(mid 287.152832 -221.57818)
		(end 287.598612 -221.762828)
		(width 0.12065)
		(layer "In5.Cu")
		(net "PHY_DRV_B_TO_SCC_B_10_DP")
	)
	(arc
		(start 449.6689 -248.918222)
		(mid 449.754212 -248.95356)
		(end 449.78955 -249.038872)
		(width 0.12065)
		(layer "In5.Cu")
		(net "PHY_DRV_B_TO_SCC_B_10_DP")
	)
	(arc
		(start 286.784288 -220.694504)
		(mid 286.914322 -220.748366)
		(end 286.968184 -220.8784)
		(width 0.12065)
		(layer "In5.Cu")
		(net "PHY_DRV_B_TO_SCC_B_10_DP")
	)
	(segment
		(start 452.240396 -248.115074)
		(end 452.113396 -248.242074)
		(width 0.127)
		(layer "F.Cu")
		(net "PHY_DRV_B_TO_SCC_B_10_DN")
	)
	(segment
		(start 452.113396 -248.520204)
		(end 452.029576 -248.604024)
		(width 0.127)
		(layer "F.Cu")
		(net "PHY_DRV_B_TO_SCC_B_10_DN")
	)
	(segment
		(start 452.113396 -248.242074)
		(end 452.113396 -248.520204)
		(width 0.127)
		(layer "F.Cu")
		(net "PHY_DRV_B_TO_SCC_B_10_DN")
	)
	(segment
		(start 449.78955 -248.477024)
		(end 449.78955 -248.115074)
		(width 0.127)
		(layer "F.Cu")
		(net "PHY_DRV_B_TO_SCC_B_10_DN")
	)
	(segment
		(start 453.574912 -248.115074)
		(end 452.240396 -248.115074)
		(width 0.127)
		(layer "F.Cu")
		(net "PHY_DRV_B_TO_SCC_B_10_DN")
	)
	(segment
		(start 452.029576 -248.604024)
		(end 449.91655 -248.604024)
		(width 0.127)
		(layer "F.Cu")
		(net "PHY_DRV_B_TO_SCC_B_10_DN")
	)
	(arc
		(start 449.91655 -248.604024)
		(mid 449.826747 -248.566827)
		(end 449.78955 -248.477024)
		(width 0.127)
		(layer "F.Cu")
		(net "PHY_DRV_B_TO_SCC_B_10_DN")
	)
	(segment
		(start 291.155882 -221.426278)
		(end 405.432768 -232.254298)
		(width 0.12065)
		(layer "In5.Cu")
		(net "PHY_DRV_B_TO_SCC_B_10_DN")
	)
	(segment
		(start 287.83661 -220.694504)
		(end 287.48863 -220.694504)
		(width 0.12065)
		(layer "In5.Cu")
		(net "PHY_DRV_B_TO_SCC_B_10_DN")
	)
	(segment
		(start 441.511944 -245.828058)
		(end 441.85078 -245.955566)
		(width 0.12065)
		(layer "In5.Cu")
		(net "PHY_DRV_B_TO_SCC_B_10_DN")
	)
	(segment
		(start 441.393326 -245.566438)
		(end 441.511944 -245.828058)
		(width 0.12065)
		(layer "In5.Cu")
		(net "PHY_DRV_B_TO_SCC_B_10_DN")
	)
	(segment
		(start 442.569854 -246.22633)
		(end 448.830446 -248.581672)
		(width 0.12065)
		(layer "In5.Cu")
		(net "PHY_DRV_B_TO_SCC_B_10_DN")
	)
	(segment
		(start 439.73496 -245.15953)
		(end 439.99658 -245.040912)
		(width 0.12065)
		(layer "In5.Cu")
		(net "PHY_DRV_B_TO_SCC_B_10_DN")
	)
	(segment
		(start 442.451236 -245.964456)
		(end 442.569854 -246.22633)
		(width 0.12065)
		(layer "In5.Cu")
		(net "PHY_DRV_B_TO_SCC_B_10_DN")
	)
	(segment
		(start 440.335416 -245.16842)
		(end 440.454034 -245.43004)
		(width 0.12065)
		(layer "In5.Cu")
		(net "PHY_DRV_B_TO_SCC_B_10_DN")
	)
	(segment
		(start 449.78955 -248.461022)
		(end 449.78955 -248.115074)
		(width 0.12065)
		(layer "In5.Cu")
		(net "PHY_DRV_B_TO_SCC_B_10_DN")
	)
	(segment
		(start 448.830446 -248.581672)
		(end 449.6689 -248.581672)
		(width 0.12065)
		(layer "In5.Cu")
		(net "PHY_DRV_B_TO_SCC_B_10_DN")
	)
	(segment
		(start 440.454034 -245.43004)
		(end 440.79287 -245.557548)
		(width 0.12065)
		(layer "In5.Cu")
		(net "PHY_DRV_B_TO_SCC_B_10_DN")
	)
	(segment
		(start 439.99658 -245.040912)
		(end 440.335416 -245.16842)
		(width 0.12065)
		(layer "In5.Cu")
		(net "PHY_DRV_B_TO_SCC_B_10_DN")
	)
	(segment
		(start 405.432768 -232.254298)
		(end 439.73496 -245.15953)
		(width 0.12065)
		(layer "In5.Cu")
		(net "PHY_DRV_B_TO_SCC_B_10_DN")
	)
	(segment
		(start 287.598612 -221.426278)
		(end 291.155882 -221.426278)
		(width 0.12065)
		(layer "In5.Cu")
		(net "PHY_DRV_B_TO_SCC_B_10_DN")
	)
	(segment
		(start 441.05449 -245.43893)
		(end 441.393326 -245.566438)
		(width 0.12065)
		(layer "In5.Cu")
		(net "PHY_DRV_B_TO_SCC_B_10_DN")
	)
	(segment
		(start 287.304734 -220.8784)
		(end 287.304734 -221.1324)
		(width 0.12065)
		(layer "In5.Cu")
		(net "PHY_DRV_B_TO_SCC_B_10_DN")
	)
	(segment
		(start 440.79287 -245.557548)
		(end 441.05449 -245.43893)
		(width 0.12065)
		(layer "In5.Cu")
		(net "PHY_DRV_B_TO_SCC_B_10_DN")
	)
	(segment
		(start 442.112654 -245.836948)
		(end 442.451236 -245.964456)
		(width 0.12065)
		(layer "In5.Cu")
		(net "PHY_DRV_B_TO_SCC_B_10_DN")
	)
	(segment
		(start 441.85078 -245.955566)
		(end 442.112654 -245.836948)
		(width 0.12065)
		(layer "In5.Cu")
		(net "PHY_DRV_B_TO_SCC_B_10_DN")
	)
	(arc
		(start 449.6689 -248.581672)
		(mid 449.754212 -248.546334)
		(end 449.78955 -248.461022)
		(width 0.12065)
		(layer "In5.Cu")
		(net "PHY_DRV_B_TO_SCC_B_10_DN")
	)
	(arc
		(start 287.48863 -220.694504)
		(mid 287.358596 -220.748366)
		(end 287.304734 -220.8784)
		(width 0.12065)
		(layer "In5.Cu")
		(net "PHY_DRV_B_TO_SCC_B_10_DN")
	)
	(arc
		(start 287.304734 -221.1324)
		(mid 287.390809 -221.340203)
		(end 287.598612 -221.426278)
		(width 0.12065)
		(layer "In5.Cu")
		(net "PHY_DRV_B_TO_SCC_B_10_DN")
	)
	(segment
		(start 61.574934 -249.385074)
		(end 62.90945 -249.385074)
		(width 0.127)
		(layer "F.Cu")
		(net "PHY_DRV_B_TO_SCC_B_1_DP")
	)
	(segment
		(start 63.03645 -249.258074)
		(end 63.03645 -249.023124)
		(width 0.127)
		(layer "F.Cu")
		(net "PHY_DRV_B_TO_SCC_B_1_DP")
	)
	(segment
		(start 64.0588 -249.023124)
		(end 64.0588 -249.385074)
		(width 0.127)
		(layer "F.Cu")
		(net "PHY_DRV_B_TO_SCC_B_1_DP")
	)
	(segment
		(start 63.16345 -248.896124)
		(end 63.9318 -248.896124)
		(width 0.127)
		(layer "F.Cu")
		(net "PHY_DRV_B_TO_SCC_B_1_DP")
	)
	(segment
		(start 63.03645 -249.023124)
		(end 63.16345 -248.896124)
		(width 0.127)
		(layer "F.Cu")
		(net "PHY_DRV_B_TO_SCC_B_1_DP")
	)
	(segment
		(start 62.90945 -249.385074)
		(end 63.03645 -249.258074)
		(width 0.127)
		(layer "F.Cu")
		(net "PHY_DRV_B_TO_SCC_B_1_DP")
	)
	(arc
		(start 63.9318 -248.896124)
		(mid 64.021603 -248.933321)
		(end 64.0588 -249.023124)
		(width 0.127)
		(layer "F.Cu")
		(net "PHY_DRV_B_TO_SCC_B_1_DP")
	)
	(segment
		(start 64.0588 -249.038872)
		(end 64.0588 -249.385074)
		(width 0.12065)
		(layer "In5.Cu")
		(net "PHY_DRV_B_TO_SCC_B_1_DP")
	)
	(segment
		(start 252.076458 -232.480612)
		(end 240.880646 -230.100378)
		(width 0.12065)
		(layer "In5.Cu")
		(net "PHY_DRV_B_TO_SCC_B_1_DP")
	)
	(segment
		(start 286.436562 -231.494584)
		(end 286.805116 -231.494584)
		(width 0.12065)
		(layer "In5.Cu")
		(net "PHY_DRV_B_TO_SCC_B_1_DP")
	)
	(segment
		(start 120.939052 -238.459518)
		(end 97.747582 -242.78336)
		(width 0.12065)
		(layer "In5.Cu")
		(net "PHY_DRV_B_TO_SCC_B_1_DP")
	)
	(segment
		(start 286.968184 -231.331516)
		(end 286.968184 -231.102916)
		(width 0.12065)
		(layer "In5.Cu")
		(net "PHY_DRV_B_TO_SCC_B_1_DP")
	)
	(segment
		(start 260.157976 -230.76281)
		(end 252.076458 -232.480612)
		(width 0.12065)
		(layer "In5.Cu")
		(net "PHY_DRV_B_TO_SCC_B_1_DP")
	)
	(segment
		(start 122.287284 -238.414814)
		(end 122.050302 -238.252254)
		(width 0.12065)
		(layer "In5.Cu")
		(net "PHY_DRV_B_TO_SCC_B_1_DP")
	)
	(segment
		(start 64.842644 -248.918222)
		(end 64.17945 -248.918222)
		(width 0.12065)
		(layer "In5.Cu")
		(net "PHY_DRV_B_TO_SCC_B_1_DP")
	)
	(segment
		(start 121.531888 -238.555784)
		(end 121.176034 -238.622078)
		(width 0.12065)
		(layer "In5.Cu")
		(net "PHY_DRV_B_TO_SCC_B_1_DP")
	)
	(segment
		(start 123.916694 -237.904274)
		(end 123.754134 -238.141256)
		(width 0.12065)
		(layer "In5.Cu")
		(net "PHY_DRV_B_TO_SCC_B_1_DP")
	)
	(segment
		(start 222.405194 -234.02798)
		(end 185.27268 -226.464368)
		(width 0.12065)
		(layer "In5.Cu")
		(net "PHY_DRV_B_TO_SCC_B_1_DP")
	)
	(segment
		(start 123.39828 -238.207804)
		(end 123.161298 -238.045244)
		(width 0.12065)
		(layer "In5.Cu")
		(net "PHY_DRV_B_TO_SCC_B_1_DP")
	)
	(segment
		(start 121.176034 -238.622078)
		(end 120.939052 -238.459518)
		(width 0.12065)
		(layer "In5.Cu")
		(net "PHY_DRV_B_TO_SCC_B_1_DP")
	)
	(segment
		(start 123.161298 -238.045244)
		(end 122.805444 -238.111538)
		(width 0.12065)
		(layer "In5.Cu")
		(net "PHY_DRV_B_TO_SCC_B_1_DP")
	)
	(segment
		(start 122.050302 -238.252254)
		(end 121.694448 -238.318802)
		(width 0.12065)
		(layer "In5.Cu")
		(net "PHY_DRV_B_TO_SCC_B_1_DP")
	)
	(segment
		(start 122.805444 -238.111538)
		(end 122.643138 -238.34852)
		(width 0.12065)
		(layer "In5.Cu")
		(net "PHY_DRV_B_TO_SCC_B_1_DP")
	)
	(segment
		(start 122.643138 -238.34852)
		(end 122.287284 -238.414814)
		(width 0.12065)
		(layer "In5.Cu")
		(net "PHY_DRV_B_TO_SCC_B_1_DP")
	)
	(segment
		(start 121.694448 -238.318802)
		(end 121.531888 -238.555784)
		(width 0.12065)
		(layer "In5.Cu")
		(net "PHY_DRV_B_TO_SCC_B_1_DP")
	)
	(segment
		(start 185.27268 -226.464368)
		(end 123.916694 -237.904274)
		(width 0.12065)
		(layer "In5.Cu")
		(net "PHY_DRV_B_TO_SCC_B_1_DP")
	)
	(segment
		(start 286.628078 -230.76281)
		(end 260.157976 -230.76281)
		(width 0.12065)
		(layer "In5.Cu")
		(net "PHY_DRV_B_TO_SCC_B_1_DP")
	)
	(segment
		(start 240.880646 -230.100378)
		(end 222.405194 -234.02798)
		(width 0.12065)
		(layer "In5.Cu")
		(net "PHY_DRV_B_TO_SCC_B_1_DP")
	)
	(segment
		(start 123.754134 -238.141256)
		(end 123.39828 -238.207804)
		(width 0.12065)
		(layer "In5.Cu")
		(net "PHY_DRV_B_TO_SCC_B_1_DP")
	)
	(segment
		(start 97.747582 -242.78336)
		(end 64.842644 -248.918222)
		(width 0.12065)
		(layer "In5.Cu")
		(net "PHY_DRV_B_TO_SCC_B_1_DP")
	)
	(arc
		(start 64.17945 -248.918222)
		(mid 64.094138 -248.95356)
		(end 64.0588 -249.038872)
		(width 0.12065)
		(layer "In5.Cu")
		(net "PHY_DRV_B_TO_SCC_B_1_DP")
	)
	(arc
		(start 286.968184 -231.102916)
		(mid 286.868569 -230.862425)
		(end 286.628078 -230.76281)
		(width 0.12065)
		(layer "In5.Cu")
		(net "PHY_DRV_B_TO_SCC_B_1_DP")
	)
	(arc
		(start 286.805116 -231.494584)
		(mid 286.920422 -231.446822)
		(end 286.968184 -231.331516)
		(width 0.12065)
		(layer "In5.Cu")
		(net "PHY_DRV_B_TO_SCC_B_1_DP")
	)
	(segment
		(start 64.0588 -248.477024)
		(end 64.0588 -248.115074)
		(width 0.127)
		(layer "F.Cu")
		(net "PHY_DRV_B_TO_SCC_B_1_DN")
	)
	(segment
		(start 63.03645 -248.45645)
		(end 63.184024 -248.604024)
		(width 0.127)
		(layer "F.Cu")
		(net "PHY_DRV_B_TO_SCC_B_1_DN")
	)
	(segment
		(start 63.03645 -248.242074)
		(end 63.03645 -248.45645)
		(width 0.127)
		(layer "F.Cu")
		(net "PHY_DRV_B_TO_SCC_B_1_DN")
	)
	(segment
		(start 63.184024 -248.604024)
		(end 63.9318 -248.604024)
		(width 0.127)
		(layer "F.Cu")
		(net "PHY_DRV_B_TO_SCC_B_1_DN")
	)
	(segment
		(start 62.90945 -248.115074)
		(end 63.03645 -248.242074)
		(width 0.127)
		(layer "F.Cu")
		(net "PHY_DRV_B_TO_SCC_B_1_DN")
	)
	(segment
		(start 61.574934 -248.115074)
		(end 62.90945 -248.115074)
		(width 0.127)
		(layer "F.Cu")
		(net "PHY_DRV_B_TO_SCC_B_1_DN")
	)
	(arc
		(start 63.9318 -248.604024)
		(mid 64.021603 -248.566827)
		(end 64.0588 -248.477024)
		(width 0.127)
		(layer "F.Cu")
		(net "PHY_DRV_B_TO_SCC_B_1_DN")
	)
	(segment
		(start 260.122416 -230.42626)
		(end 252.076458 -232.136442)
		(width 0.12065)
		(layer "In5.Cu")
		(net "PHY_DRV_B_TO_SCC_B_1_DN")
	)
	(segment
		(start 222.40367 -233.684064)
		(end 185.275474 -226.121468)
		(width 0.12065)
		(layer "In5.Cu")
		(net "PHY_DRV_B_TO_SCC_B_1_DN")
	)
	(segment
		(start 286.628078 -230.42626)
		(end 260.122416 -230.42626)
		(width 0.12065)
		(layer "In5.Cu")
		(net "PHY_DRV_B_TO_SCC_B_1_DN")
	)
	(segment
		(start 287.304734 -231.331516)
		(end 287.304734 -231.102916)
		(width 0.12065)
		(layer "In5.Cu")
		(net "PHY_DRV_B_TO_SCC_B_1_DN")
	)
	(segment
		(start 287.83661 -231.494584)
		(end 287.467802 -231.494584)
		(width 0.12065)
		(layer "In5.Cu")
		(net "PHY_DRV_B_TO_SCC_B_1_DN")
	)
	(segment
		(start 64.0588 -248.461022)
		(end 64.0588 -248.115074)
		(width 0.12065)
		(layer "In5.Cu")
		(net "PHY_DRV_B_TO_SCC_B_1_DN")
	)
	(segment
		(start 240.880646 -229.756208)
		(end 222.40367 -233.684064)
		(width 0.12065)
		(layer "In5.Cu")
		(net "PHY_DRV_B_TO_SCC_B_1_DN")
	)
	(segment
		(start 185.275474 -226.121468)
		(end 64.807338 -248.581672)
		(width 0.12065)
		(layer "In5.Cu")
		(net "PHY_DRV_B_TO_SCC_B_1_DN")
	)
	(segment
		(start 252.076458 -232.136442)
		(end 240.880646 -229.756208)
		(width 0.12065)
		(layer "In5.Cu")
		(net "PHY_DRV_B_TO_SCC_B_1_DN")
	)
	(segment
		(start 64.807338 -248.581672)
		(end 64.17945 -248.581672)
		(width 0.12065)
		(layer "In5.Cu")
		(net "PHY_DRV_B_TO_SCC_B_1_DN")
	)
	(arc
		(start 64.17945 -248.581672)
		(mid 64.094138 -248.546334)
		(end 64.0588 -248.461022)
		(width 0.12065)
		(layer "In5.Cu")
		(net "PHY_DRV_B_TO_SCC_B_1_DN")
	)
	(arc
		(start 287.467802 -231.494584)
		(mid 287.352496 -231.446822)
		(end 287.304734 -231.331516)
		(width 0.12065)
		(layer "In5.Cu")
		(net "PHY_DRV_B_TO_SCC_B_1_DN")
	)
	(arc
		(start 287.304734 -231.102916)
		(mid 287.106546 -230.624448)
		(end 286.628078 -230.42626)
		(width 0.12065)
		(layer "In5.Cu")
		(net "PHY_DRV_B_TO_SCC_B_1_DN")
	)
	(segment
		(start 31.359602 -249.385074)
		(end 31.486602 -249.258074)
		(width 0.127)
		(layer "F.Cu")
		(net "PHY_DRV_B_TO_SCC_B_0_DP")
	)
	(segment
		(start 31.486602 -249.023124)
		(end 31.613602 -248.896124)
		(width 0.127)
		(layer "F.Cu")
		(net "PHY_DRV_B_TO_SCC_B_0_DP")
	)
	(segment
		(start 31.613602 -248.896124)
		(end 32.381952 -248.896124)
		(width 0.127)
		(layer "F.Cu")
		(net "PHY_DRV_B_TO_SCC_B_0_DP")
	)
	(segment
		(start 30.025086 -249.385074)
		(end 31.359602 -249.385074)
		(width 0.127)
		(layer "F.Cu")
		(net "PHY_DRV_B_TO_SCC_B_0_DP")
	)
	(segment
		(start 32.508952 -249.023124)
		(end 32.508952 -249.385074)
		(width 0.127)
		(layer "F.Cu")
		(net "PHY_DRV_B_TO_SCC_B_0_DP")
	)
	(segment
		(start 31.486602 -249.258074)
		(end 31.486602 -249.023124)
		(width 0.127)
		(layer "F.Cu")
		(net "PHY_DRV_B_TO_SCC_B_0_DP")
	)
	(arc
		(start 32.381952 -248.896124)
		(mid 32.471755 -248.933321)
		(end 32.508952 -249.023124)
		(width 0.127)
		(layer "F.Cu")
		(net "PHY_DRV_B_TO_SCC_B_0_DP")
	)
	(segment
		(start 222.618808 -232.794048)
		(end 172.616876 -222.21571)
		(width 0.12065)
		(layer "In5.Cu")
		(net "PHY_DRV_B_TO_SCC_B_0_DP")
	)
	(segment
		(start 33.494472 -248.918222)
		(end 32.629602 -248.918222)
		(width 0.12065)
		(layer "In5.Cu")
		(net "PHY_DRV_B_TO_SCC_B_0_DP")
	)
	(segment
		(start 106.943652 -234.821984)
		(end 106.588052 -234.89031)
		(width 0.12065)
		(layer "In5.Cu")
		(net "PHY_DRV_B_TO_SCC_B_0_DP")
	)
	(segment
		(start 108.678726 -234.70616)
		(end 108.32338 -234.774486)
		(width 0.12065)
		(layer "In5.Cu")
		(net "PHY_DRV_B_TO_SCC_B_0_DP")
	)
	(segment
		(start 108.848144 -234.456478)
		(end 108.678726 -234.70616)
		(width 0.12065)
		(layer "In5.Cu")
		(net "PHY_DRV_B_TO_SCC_B_0_DP")
	)
	(segment
		(start 285.436564 -229.694486)
		(end 285.805118 -229.694486)
		(width 0.12065)
		(layer "In5.Cu")
		(net "PHY_DRV_B_TO_SCC_B_0_DP")
	)
	(segment
		(start 108.073444 -234.605068)
		(end 107.718098 -234.673394)
		(width 0.12065)
		(layer "In5.Cu")
		(net "PHY_DRV_B_TO_SCC_B_0_DP")
	)
	(segment
		(start 172.616876 -222.21571)
		(end 108.848144 -234.456478)
		(width 0.12065)
		(layer "In5.Cu")
		(net "PHY_DRV_B_TO_SCC_B_0_DP")
	)
	(segment
		(start 106.588052 -234.89031)
		(end 106.418888 -235.139992)
		(width 0.12065)
		(layer "In5.Cu")
		(net "PHY_DRV_B_TO_SCC_B_0_DP")
	)
	(segment
		(start 107.54868 -234.923076)
		(end 107.193334 -234.991402)
		(width 0.12065)
		(layer "In5.Cu")
		(net "PHY_DRV_B_TO_SCC_B_0_DP")
	)
	(segment
		(start 252.995938 -231.087676)
		(end 241.821462 -228.712522)
		(width 0.12065)
		(layer "In5.Cu")
		(net "PHY_DRV_B_TO_SCC_B_0_DP")
	)
	(segment
		(start 106.418888 -235.139992)
		(end 106.063288 -235.208318)
		(width 0.12065)
		(layer "In5.Cu")
		(net "PHY_DRV_B_TO_SCC_B_0_DP")
	)
	(segment
		(start 107.193334 -234.991402)
		(end 106.943652 -234.821984)
		(width 0.12065)
		(layer "In5.Cu")
		(net "PHY_DRV_B_TO_SCC_B_0_DP")
	)
	(segment
		(start 285.968186 -229.531418)
		(end 285.968186 -229.302818)
		(width 0.12065)
		(layer "In5.Cu")
		(net "PHY_DRV_B_TO_SCC_B_0_DP")
	)
	(segment
		(start 261.761986 -228.962712)
		(end 252.995938 -231.087676)
		(width 0.12065)
		(layer "In5.Cu")
		(net "PHY_DRV_B_TO_SCC_B_0_DP")
	)
	(segment
		(start 32.508952 -249.038872)
		(end 32.508952 -249.385074)
		(width 0.12065)
		(layer "In5.Cu")
		(net "PHY_DRV_B_TO_SCC_B_0_DP")
	)
	(segment
		(start 106.063288 -235.208318)
		(end 105.813606 -235.0389)
		(width 0.12065)
		(layer "In5.Cu")
		(net "PHY_DRV_B_TO_SCC_B_0_DP")
	)
	(segment
		(start 107.718098 -234.673394)
		(end 107.54868 -234.923076)
		(width 0.12065)
		(layer "In5.Cu")
		(net "PHY_DRV_B_TO_SCC_B_0_DP")
	)
	(segment
		(start 108.32338 -234.774486)
		(end 108.073444 -234.605068)
		(width 0.12065)
		(layer "In5.Cu")
		(net "PHY_DRV_B_TO_SCC_B_0_DP")
	)
	(segment
		(start 241.821462 -228.712522)
		(end 222.618808 -232.794048)
		(width 0.12065)
		(layer "In5.Cu")
		(net "PHY_DRV_B_TO_SCC_B_0_DP")
	)
	(segment
		(start 105.813606 -235.0389)
		(end 33.494472 -248.918222)
		(width 0.12065)
		(layer "In5.Cu")
		(net "PHY_DRV_B_TO_SCC_B_0_DP")
	)
	(segment
		(start 285.62808 -228.962712)
		(end 261.761986 -228.962712)
		(width 0.12065)
		(layer "In5.Cu")
		(net "PHY_DRV_B_TO_SCC_B_0_DP")
	)
	(arc
		(start 285.968186 -229.302818)
		(mid 285.868571 -229.062327)
		(end 285.62808 -228.962712)
		(width 0.12065)
		(layer "In5.Cu")
		(net "PHY_DRV_B_TO_SCC_B_0_DP")
	)
	(arc
		(start 32.629602 -248.918222)
		(mid 32.54429 -248.95356)
		(end 32.508952 -249.038872)
		(width 0.12065)
		(layer "In5.Cu")
		(net "PHY_DRV_B_TO_SCC_B_0_DP")
	)
	(arc
		(start 285.805118 -229.694486)
		(mid 285.920424 -229.646724)
		(end 285.968186 -229.531418)
		(width 0.12065)
		(layer "In5.Cu")
		(net "PHY_DRV_B_TO_SCC_B_0_DP")
	)
	(segment
		(start 31.486602 -248.242074)
		(end 31.486602 -248.477024)
		(width 0.127)
		(layer "F.Cu")
		(net "PHY_DRV_B_TO_SCC_B_0_DN")
	)
	(segment
		(start 31.359602 -248.115074)
		(end 31.486602 -248.242074)
		(width 0.127)
		(layer "F.Cu")
		(net "PHY_DRV_B_TO_SCC_B_0_DN")
	)
	(segment
		(start 31.613602 -248.604024)
		(end 32.381952 -248.604024)
		(width 0.127)
		(layer "F.Cu")
		(net "PHY_DRV_B_TO_SCC_B_0_DN")
	)
	(segment
		(start 32.508952 -248.477024)
		(end 32.508952 -248.115074)
		(width 0.127)
		(layer "F.Cu")
		(net "PHY_DRV_B_TO_SCC_B_0_DN")
	)
	(segment
		(start 30.025086 -248.115074)
		(end 31.359602 -248.115074)
		(width 0.127)
		(layer "F.Cu")
		(net "PHY_DRV_B_TO_SCC_B_0_DN")
	)
	(segment
		(start 31.486602 -248.477024)
		(end 31.613602 -248.604024)
		(width 0.127)
		(layer "F.Cu")
		(net "PHY_DRV_B_TO_SCC_B_0_DN")
	)
	(arc
		(start 32.381952 -248.604024)
		(mid 32.471755 -248.566827)
		(end 32.508952 -248.477024)
		(width 0.127)
		(layer "F.Cu")
		(net "PHY_DRV_B_TO_SCC_B_0_DN")
	)
	(segment
		(start 33.462468 -248.581672)
		(end 32.629602 -248.581672)
		(width 0.12065)
		(layer "In5.Cu")
		(net "PHY_DRV_B_TO_SCC_B_0_DN")
	)
	(segment
		(start 241.821462 -228.368352)
		(end 222.618554 -232.449878)
		(width 0.12065)
		(layer "In5.Cu")
		(net "PHY_DRV_B_TO_SCC_B_0_DN")
	)
	(segment
		(start 222.618554 -232.449878)
		(end 172.620178 -221.872302)
		(width 0.12065)
		(layer "In5.Cu")
		(net "PHY_DRV_B_TO_SCC_B_0_DN")
	)
	(segment
		(start 105.887266 -234.68203)
		(end 33.462468 -248.581672)
		(width 0.12065)
		(layer "In5.Cu")
		(net "PHY_DRV_B_TO_SCC_B_0_DN")
	)
	(segment
		(start 261.7216 -228.626162)
		(end 252.991112 -230.74249)
		(width 0.12065)
		(layer "In5.Cu")
		(net "PHY_DRV_B_TO_SCC_B_0_DN")
	)
	(segment
		(start 285.62808 -228.626162)
		(end 261.7216 -228.626162)
		(width 0.12065)
		(layer "In5.Cu")
		(net "PHY_DRV_B_TO_SCC_B_0_DN")
	)
	(segment
		(start 172.620178 -221.872302)
		(end 105.887266 -234.681776)
		(width 0.12065)
		(layer "In5.Cu")
		(net "PHY_DRV_B_TO_SCC_B_0_DN")
	)
	(segment
		(start 252.991112 -230.74249)
		(end 241.821462 -228.368352)
		(width 0.12065)
		(layer "In5.Cu")
		(net "PHY_DRV_B_TO_SCC_B_0_DN")
	)
	(segment
		(start 32.508952 -248.461022)
		(end 32.508952 -248.115074)
		(width 0.12065)
		(layer "In5.Cu")
		(net "PHY_DRV_B_TO_SCC_B_0_DN")
	)
	(segment
		(start 286.304736 -229.531418)
		(end 286.304736 -229.302818)
		(width 0.12065)
		(layer "In5.Cu")
		(net "PHY_DRV_B_TO_SCC_B_0_DN")
	)
	(segment
		(start 286.836612 -229.694486)
		(end 286.467804 -229.694486)
		(width 0.12065)
		(layer "In5.Cu")
		(net "PHY_DRV_B_TO_SCC_B_0_DN")
	)
	(segment
		(start 105.887266 -234.681776)
		(end 105.887266 -234.68203)
		(width 0.12065)
		(layer "In5.Cu")
		(net "PHY_DRV_B_TO_SCC_B_0_DN")
	)
	(arc
		(start 286.304736 -229.302818)
		(mid 286.106548 -228.82435)
		(end 285.62808 -228.626162)
		(width 0.12065)
		(layer "In5.Cu")
		(net "PHY_DRV_B_TO_SCC_B_0_DN")
	)
	(arc
		(start 32.629602 -248.581672)
		(mid 32.54429 -248.546334)
		(end 32.508952 -248.461022)
		(width 0.12065)
		(layer "In5.Cu")
		(net "PHY_DRV_B_TO_SCC_B_0_DN")
	)
	(arc
		(start 286.467804 -229.694486)
		(mid 286.352498 -229.646724)
		(end 286.304736 -229.531418)
		(width 0.12065)
		(layer "In5.Cu")
		(net "PHY_DRV_B_TO_SCC_B_0_DN")
	)
	(segment
		(start 223.630744 -84.21116)
		(end 223.630744 -77.56779)
		(width 0.1651)
		(layer "B.Cu")
		(net "PCIE_SCC_B_TO_COMP_B_7_DP")
	)
	(segment
		(start 279.082754 -131.384548)
		(end 278.746712 -131.048506)
		(width 0.1651)
		(layer "B.Cu")
		(net "PCIE_SCC_B_TO_COMP_B_7_DP")
	)
	(segment
		(start 223.016826 -76.953872)
		(end 222.788226 -76.953872)
		(width 0.1651)
		(layer "B.Cu")
		(net "PCIE_SCC_B_TO_COMP_B_7_DP")
	)
	(segment
		(start 222.600012 -76.765658)
		(end 222.600012 -76.399898)
		(width 0.1651)
		(layer "B.Cu")
		(net "PCIE_SCC_B_TO_COMP_B_7_DP")
	)
	(segment
		(start 278.746712 -131.048506)
		(end 236.034326 -103.31069)
		(width 0.1651)
		(layer "B.Cu")
		(net "PCIE_SCC_B_TO_COMP_B_7_DP")
	)
	(segment
		(start 236.034326 -103.31069)
		(end 223.630744 -84.21116)
		(width 0.1651)
		(layer "B.Cu")
		(net "PCIE_SCC_B_TO_COMP_B_7_DP")
	)
	(segment
		(start 279.082754 -131.902708)
		(end 279.082754 -131.384548)
		(width 0.1651)
		(layer "B.Cu")
		(net "PCIE_SCC_B_TO_COMP_B_7_DP")
	)
	(segment
		(start 279.636728 -132.094478)
		(end 279.274524 -132.094478)
		(width 0.1651)
		(layer "B.Cu")
		(net "PCIE_SCC_B_TO_COMP_B_7_DP")
	)
	(arc
		(start 279.274524 -132.094478)
		(mid 279.138922 -132.03831)
		(end 279.082754 -131.902708)
		(width 0.1651)
		(layer "B.Cu")
		(net "PCIE_SCC_B_TO_COMP_B_7_DP")
	)
	(arc
		(start 223.630744 -77.56779)
		(mid 223.450932 -77.133684)
		(end 223.016826 -76.953872)
		(width 0.1651)
		(layer "B.Cu")
		(net "PCIE_SCC_B_TO_COMP_B_7_DP")
	)
	(arc
		(start 222.788226 -76.953872)
		(mid 222.655139 -76.898745)
		(end 222.600012 -76.765658)
		(width 0.1651)
		(layer "B.Cu")
		(net "PCIE_SCC_B_TO_COMP_B_7_DP")
	)
	(segment
		(start 222.600012 -77.434186)
		(end 222.600012 -77.799946)
		(width 0.1651)
		(layer "B.Cu")
		(net "PCIE_SCC_B_TO_COMP_B_7_DN")
	)
	(segment
		(start 235.822998 -103.522018)
		(end 223.338644 -84.297774)
		(width 0.1651)
		(layer "B.Cu")
		(net "PCIE_SCC_B_TO_COMP_B_7_DN")
	)
	(segment
		(start 244.536468 -109.317028)
		(end 244.121178 -109.04728)
		(width 0.1651)
		(layer "B.Cu")
		(net "PCIE_SCC_B_TO_COMP_B_7_DN")
	)
	(segment
		(start 244.08765 -108.889292)
		(end 239.179862 -105.701846)
		(width 0.1651)
		(layer "B.Cu")
		(net "PCIE_SCC_B_TO_COMP_B_7_DN")
	)
	(segment
		(start 238.157258 -105.03789)
		(end 237.999016 -105.071418)
		(width 0.1651)
		(layer "B.Cu")
		(net "PCIE_SCC_B_TO_COMP_B_7_DN")
	)
	(segment
		(start 278.23668 -132.094478)
		(end 278.598884 -132.094478)
		(width 0.1651)
		(layer "B.Cu")
		(net "PCIE_SCC_B_TO_COMP_B_7_DN")
	)
	(segment
		(start 246.581676 -110.645194)
		(end 246.166132 -110.375446)
		(width 0.1651)
		(layer "B.Cu")
		(net "PCIE_SCC_B_TO_COMP_B_7_DN")
	)
	(segment
		(start 239.02162 -105.735628)
		(end 238.60633 -105.46588)
		(width 0.1651)
		(layer "B.Cu")
		(net "PCIE_SCC_B_TO_COMP_B_7_DN")
	)
	(segment
		(start 237.999016 -105.071418)
		(end 237.583726 -104.80167)
		(width 0.1651)
		(layer "B.Cu")
		(net "PCIE_SCC_B_TO_COMP_B_7_DN")
	)
	(segment
		(start 245.11 -109.553248)
		(end 244.69471 -109.2835)
		(width 0.1651)
		(layer "B.Cu")
		(net "PCIE_SCC_B_TO_COMP_B_7_DN")
	)
	(segment
		(start 237.550198 -104.643682)
		(end 235.822998 -103.522018)
		(width 0.1651)
		(layer "B.Cu")
		(net "PCIE_SCC_B_TO_COMP_B_7_DN")
	)
	(segment
		(start 245.559072 -109.981238)
		(end 245.143782 -109.711236)
		(width 0.1651)
		(layer "B.Cu")
		(net "PCIE_SCC_B_TO_COMP_B_7_DN")
	)
	(segment
		(start 246.166132 -110.375446)
		(end 246.132604 -110.217204)
		(width 0.1651)
		(layer "B.Cu")
		(net "PCIE_SCC_B_TO_COMP_B_7_DN")
	)
	(segment
		(start 245.143782 -109.711236)
		(end 245.11 -109.553248)
		(width 0.1651)
		(layer "B.Cu")
		(net "PCIE_SCC_B_TO_COMP_B_7_DN")
	)
	(segment
		(start 223.338644 -84.297774)
		(end 223.338644 -77.56779)
		(width 0.1651)
		(layer "B.Cu")
		(net "PCIE_SCC_B_TO_COMP_B_7_DN")
	)
	(segment
		(start 237.583726 -104.80167)
		(end 237.550198 -104.643682)
		(width 0.1651)
		(layer "B.Cu")
		(net "PCIE_SCC_B_TO_COMP_B_7_DN")
	)
	(segment
		(start 245.71706 -109.947456)
		(end 245.559072 -109.981238)
		(width 0.1651)
		(layer "B.Cu")
		(net "PCIE_SCC_B_TO_COMP_B_7_DN")
	)
	(segment
		(start 278.790654 -131.902708)
		(end 278.790654 -131.505706)
		(width 0.1651)
		(layer "B.Cu")
		(net "PCIE_SCC_B_TO_COMP_B_7_DN")
	)
	(segment
		(start 278.790654 -131.505706)
		(end 278.5618 -131.276852)
		(width 0.1651)
		(layer "B.Cu")
		(net "PCIE_SCC_B_TO_COMP_B_7_DN")
	)
	(segment
		(start 244.121178 -109.04728)
		(end 244.08765 -108.889292)
		(width 0.1651)
		(layer "B.Cu")
		(net "PCIE_SCC_B_TO_COMP_B_7_DN")
	)
	(segment
		(start 246.739664 -110.611412)
		(end 246.581676 -110.645194)
		(width 0.1651)
		(layer "B.Cu")
		(net "PCIE_SCC_B_TO_COMP_B_7_DN")
	)
	(segment
		(start 239.179862 -105.701846)
		(end 239.02162 -105.735628)
		(width 0.1651)
		(layer "B.Cu")
		(net "PCIE_SCC_B_TO_COMP_B_7_DN")
	)
	(segment
		(start 238.572548 -105.307638)
		(end 238.157258 -105.03789)
		(width 0.1651)
		(layer "B.Cu")
		(net "PCIE_SCC_B_TO_COMP_B_7_DN")
	)
	(segment
		(start 278.5618 -131.276852)
		(end 246.739664 -110.611412)
		(width 0.1651)
		(layer "B.Cu")
		(net "PCIE_SCC_B_TO_COMP_B_7_DN")
	)
	(segment
		(start 223.016826 -77.245972)
		(end 222.788226 -77.245972)
		(width 0.1651)
		(layer "B.Cu")
		(net "PCIE_SCC_B_TO_COMP_B_7_DN")
	)
	(segment
		(start 246.132604 -110.217204)
		(end 245.71706 -109.947456)
		(width 0.1651)
		(layer "B.Cu")
		(net "PCIE_SCC_B_TO_COMP_B_7_DN")
	)
	(segment
		(start 238.60633 -105.46588)
		(end 238.572548 -105.307638)
		(width 0.1651)
		(layer "B.Cu")
		(net "PCIE_SCC_B_TO_COMP_B_7_DN")
	)
	(segment
		(start 244.69471 -109.2835)
		(end 244.536468 -109.317028)
		(width 0.1651)
		(layer "B.Cu")
		(net "PCIE_SCC_B_TO_COMP_B_7_DN")
	)
	(arc
		(start 278.598884 -132.094478)
		(mid 278.734486 -132.03831)
		(end 278.790654 -131.902708)
		(width 0.1651)
		(layer "B.Cu")
		(net "PCIE_SCC_B_TO_COMP_B_7_DN")
	)
	(arc
		(start 223.338644 -77.56779)
		(mid 223.244386 -77.34023)
		(end 223.016826 -77.245972)
		(width 0.1651)
		(layer "B.Cu")
		(net "PCIE_SCC_B_TO_COMP_B_7_DN")
	)
	(arc
		(start 222.788226 -77.245972)
		(mid 222.655139 -77.301099)
		(end 222.600012 -77.434186)
		(width 0.1651)
		(layer "B.Cu")
		(net "PCIE_SCC_B_TO_COMP_B_7_DN")
	)
	(segment
		(start 280.082752 -133.702552)
		(end 280.082752 -133.5024)
		(width 0.1651)
		(layer "B.Cu")
		(net "PCIE_SCC_B_TO_COMP_B_6_DP")
	)
	(segment
		(start 280.636726 -133.894322)
		(end 280.274522 -133.894322)
		(width 0.1651)
		(layer "B.Cu")
		(net "PCIE_SCC_B_TO_COMP_B_6_DP")
	)
	(segment
		(start 222.534988 -86.708488)
		(end 221.84614 -83.463892)
		(width 0.1651)
		(layer "B.Cu")
		(net "PCIE_SCC_B_TO_COMP_B_6_DP")
	)
	(segment
		(start 221.216982 -78.153768)
		(end 220.988382 -78.153768)
		(width 0.1651)
		(layer "B.Cu")
		(net "PCIE_SCC_B_TO_COMP_B_6_DP")
	)
	(segment
		(start 220.800168 -77.965554)
		(end 220.800168 -77.600048)
		(width 0.1651)
		(layer "B.Cu")
		(net "PCIE_SCC_B_TO_COMP_B_6_DP")
	)
	(segment
		(start 279.428702 -132.84835)
		(end 276.378162 -132.84835)
		(width 0.1651)
		(layer "B.Cu")
		(net "PCIE_SCC_B_TO_COMP_B_6_DP")
	)
	(segment
		(start 221.84614 -83.463892)
		(end 221.84614 -78.782926)
		(width 0.1651)
		(layer "B.Cu")
		(net "PCIE_SCC_B_TO_COMP_B_6_DP")
	)
	(segment
		(start 255.73101 -119.439944)
		(end 235.08462 -106.031792)
		(width 0.1651)
		(layer "B.Cu")
		(net "PCIE_SCC_B_TO_COMP_B_6_DP")
	)
	(segment
		(start 276.378162 -132.84835)
		(end 255.73101 -119.439944)
		(width 0.1651)
		(layer "B.Cu")
		(net "PCIE_SCC_B_TO_COMP_B_6_DP")
	)
	(segment
		(start 235.08462 -106.031792)
		(end 222.534988 -86.708488)
		(width 0.1651)
		(layer "B.Cu")
		(net "PCIE_SCC_B_TO_COMP_B_6_DP")
	)
	(arc
		(start 221.84614 -78.782926)
		(mid 221.661864 -78.338044)
		(end 221.216982 -78.153768)
		(width 0.1651)
		(layer "B.Cu")
		(net "PCIE_SCC_B_TO_COMP_B_6_DP")
	)
	(arc
		(start 280.082752 -133.5024)
		(mid 279.891185 -133.039917)
		(end 279.428702 -132.84835)
		(width 0.1651)
		(layer "B.Cu")
		(net "PCIE_SCC_B_TO_COMP_B_6_DP")
	)
	(arc
		(start 220.988382 -78.153768)
		(mid 220.855295 -78.098641)
		(end 220.800168 -77.965554)
		(width 0.1651)
		(layer "B.Cu")
		(net "PCIE_SCC_B_TO_COMP_B_6_DP")
	)
	(arc
		(start 280.274522 -133.894322)
		(mid 280.13892 -133.838154)
		(end 280.082752 -133.702552)
		(width 0.1651)
		(layer "B.Cu")
		(net "PCIE_SCC_B_TO_COMP_B_6_DP")
	)
	(segment
		(start 230.861616 -100.275898)
		(end 230.591868 -99.860608)
		(width 0.1651)
		(layer "B.Cu")
		(net "PCIE_SCC_B_TO_COMP_B_6_DN")
	)
	(segment
		(start 224.696274 -90.782394)
		(end 224.729802 -90.624406)
		(width 0.1651)
		(layer "B.Cu")
		(net "PCIE_SCC_B_TO_COMP_B_6_DN")
	)
	(segment
		(start 229.297484 -97.657412)
		(end 225.78822 -92.25407)
		(width 0.1651)
		(layer "B.Cu")
		(net "PCIE_SCC_B_TO_COMP_B_6_DN")
	)
	(segment
		(start 279.428702 -133.14045)
		(end 276.291548 -133.14045)
		(width 0.1651)
		(layer "B.Cu")
		(net "PCIE_SCC_B_TO_COMP_B_6_DN")
	)
	(segment
		(start 225.36023 -91.804998)
		(end 225.393758 -91.646756)
		(width 0.1651)
		(layer "B.Cu")
		(net "PCIE_SCC_B_TO_COMP_B_6_DN")
	)
	(segment
		(start 225.629978 -92.220288)
		(end 225.36023 -91.804998)
		(width 0.1651)
		(layer "B.Cu")
		(net "PCIE_SCC_B_TO_COMP_B_6_DN")
	)
	(segment
		(start 279.236678 -133.894322)
		(end 279.598882 -133.894322)
		(width 0.1651)
		(layer "B.Cu")
		(net "PCIE_SCC_B_TO_COMP_B_6_DN")
	)
	(segment
		(start 224.966022 -91.197938)
		(end 224.696274 -90.782394)
		(width 0.1651)
		(layer "B.Cu")
		(net "PCIE_SCC_B_TO_COMP_B_6_DN")
	)
	(segment
		(start 279.790652 -133.702552)
		(end 279.790652 -133.5024)
		(width 0.1651)
		(layer "B.Cu")
		(net "PCIE_SCC_B_TO_COMP_B_6_DN")
	)
	(segment
		(start 276.291548 -133.14045)
		(end 234.873292 -106.24312)
		(width 0.1651)
		(layer "B.Cu")
		(net "PCIE_SCC_B_TO_COMP_B_6_DN")
	)
	(segment
		(start 229.691692 -98.264472)
		(end 229.533704 -98.230944)
		(width 0.1651)
		(layer "B.Cu")
		(net "PCIE_SCC_B_TO_COMP_B_6_DN")
	)
	(segment
		(start 229.533704 -98.230944)
		(end 229.263956 -97.8154)
		(width 0.1651)
		(layer "B.Cu")
		(net "PCIE_SCC_B_TO_COMP_B_6_DN")
	)
	(segment
		(start 222.260414 -86.822026)
		(end 221.55404 -83.494626)
		(width 0.1651)
		(layer "B.Cu")
		(net "PCIE_SCC_B_TO_COMP_B_6_DN")
	)
	(segment
		(start 229.96144 -98.679762)
		(end 229.691692 -98.264472)
		(width 0.1651)
		(layer "B.Cu")
		(net "PCIE_SCC_B_TO_COMP_B_6_DN")
	)
	(segment
		(start 225.78822 -92.25407)
		(end 225.629978 -92.220288)
		(width 0.1651)
		(layer "B.Cu")
		(net "PCIE_SCC_B_TO_COMP_B_6_DN")
	)
	(segment
		(start 230.625396 -99.702366)
		(end 230.355648 -99.287076)
		(width 0.1651)
		(layer "B.Cu")
		(net "PCIE_SCC_B_TO_COMP_B_6_DN")
	)
	(segment
		(start 230.591868 -99.860608)
		(end 230.625396 -99.702366)
		(width 0.1651)
		(layer "B.Cu")
		(net "PCIE_SCC_B_TO_COMP_B_6_DN")
	)
	(segment
		(start 225.12401 -91.231466)
		(end 224.966022 -91.197938)
		(width 0.1651)
		(layer "B.Cu")
		(net "PCIE_SCC_B_TO_COMP_B_6_DN")
	)
	(segment
		(start 224.729802 -90.624406)
		(end 222.260414 -86.822026)
		(width 0.1651)
		(layer "B.Cu")
		(net "PCIE_SCC_B_TO_COMP_B_6_DN")
	)
	(segment
		(start 230.355648 -99.287076)
		(end 230.19766 -99.253294)
		(width 0.1651)
		(layer "B.Cu")
		(net "PCIE_SCC_B_TO_COMP_B_6_DN")
	)
	(segment
		(start 230.19766 -99.253294)
		(end 229.927912 -98.838004)
		(width 0.1651)
		(layer "B.Cu")
		(net "PCIE_SCC_B_TO_COMP_B_6_DN")
	)
	(segment
		(start 220.800168 -78.634082)
		(end 220.800168 -78.999842)
		(width 0.1651)
		(layer "B.Cu")
		(net "PCIE_SCC_B_TO_COMP_B_6_DN")
	)
	(segment
		(start 229.927912 -98.838004)
		(end 229.96144 -98.679762)
		(width 0.1651)
		(layer "B.Cu")
		(net "PCIE_SCC_B_TO_COMP_B_6_DN")
	)
	(segment
		(start 221.216982 -78.445868)
		(end 220.988382 -78.445868)
		(width 0.1651)
		(layer "B.Cu")
		(net "PCIE_SCC_B_TO_COMP_B_6_DN")
	)
	(segment
		(start 234.873292 -106.24312)
		(end 231.019858 -100.309426)
		(width 0.1651)
		(layer "B.Cu")
		(net "PCIE_SCC_B_TO_COMP_B_6_DN")
	)
	(segment
		(start 231.019858 -100.309426)
		(end 230.861616 -100.275898)
		(width 0.1651)
		(layer "B.Cu")
		(net "PCIE_SCC_B_TO_COMP_B_6_DN")
	)
	(segment
		(start 221.55404 -83.494626)
		(end 221.55404 -78.782926)
		(width 0.1651)
		(layer "B.Cu")
		(net "PCIE_SCC_B_TO_COMP_B_6_DN")
	)
	(segment
		(start 229.263956 -97.8154)
		(end 229.297484 -97.657412)
		(width 0.1651)
		(layer "B.Cu")
		(net "PCIE_SCC_B_TO_COMP_B_6_DN")
	)
	(segment
		(start 225.393758 -91.646756)
		(end 225.12401 -91.231466)
		(width 0.1651)
		(layer "B.Cu")
		(net "PCIE_SCC_B_TO_COMP_B_6_DN")
	)
	(arc
		(start 220.988382 -78.445868)
		(mid 220.855295 -78.500995)
		(end 220.800168 -78.634082)
		(width 0.1651)
		(layer "B.Cu")
		(net "PCIE_SCC_B_TO_COMP_B_6_DN")
	)
	(arc
		(start 279.790652 -133.5024)
		(mid 279.684639 -133.246463)
		(end 279.428702 -133.14045)
		(width 0.1651)
		(layer "B.Cu")
		(net "PCIE_SCC_B_TO_COMP_B_6_DN")
	)
	(arc
		(start 279.598882 -133.894322)
		(mid 279.734484 -133.838154)
		(end 279.790652 -133.702552)
		(width 0.1651)
		(layer "B.Cu")
		(net "PCIE_SCC_B_TO_COMP_B_6_DN")
	)
	(arc
		(start 221.55404 -78.782926)
		(mid 221.455318 -78.54459)
		(end 221.216982 -78.445868)
		(width 0.1651)
		(layer "B.Cu")
		(net "PCIE_SCC_B_TO_COMP_B_6_DN")
	)
	(segment
		(start 219.00007 -76.765658)
		(end 219.00007 -76.399898)
		(width 0.1651)
		(layer "B.Cu")
		(net "PCIE_SCC_B_TO_COMP_B_5_DP")
	)
	(segment
		(start 278.428704 -134.648448)
		(end 276.105366 -134.648448)
		(width 0.1651)
		(layer "B.Cu")
		(net "PCIE_SCC_B_TO_COMP_B_5_DP")
	)
	(segment
		(start 220.046042 -82.586068)
		(end 220.046042 -77.58303)
		(width 0.1651)
		(layer "B.Cu")
		(net "PCIE_SCC_B_TO_COMP_B_5_DP")
	)
	(segment
		(start 276.105366 -134.648448)
		(end 233.73334 -107.131612)
		(width 0.1651)
		(layer "B.Cu")
		(net "PCIE_SCC_B_TO_COMP_B_5_DP")
	)
	(segment
		(start 233.73334 -107.131612)
		(end 221.14129 -87.740744)
		(width 0.1651)
		(layer "B.Cu")
		(net "PCIE_SCC_B_TO_COMP_B_5_DP")
	)
	(segment
		(start 279.636728 -135.69442)
		(end 279.274524 -135.69442)
		(width 0.1651)
		(layer "B.Cu")
		(net "PCIE_SCC_B_TO_COMP_B_5_DP")
	)
	(segment
		(start 279.082754 -135.50265)
		(end 279.082754 -135.302498)
		(width 0.1651)
		(layer "B.Cu")
		(net "PCIE_SCC_B_TO_COMP_B_5_DP")
	)
	(segment
		(start 221.14129 -87.740744)
		(end 220.046042 -82.586068)
		(width 0.1651)
		(layer "B.Cu")
		(net "PCIE_SCC_B_TO_COMP_B_5_DP")
	)
	(segment
		(start 219.416884 -76.953872)
		(end 219.188284 -76.953872)
		(width 0.1651)
		(layer "B.Cu")
		(net "PCIE_SCC_B_TO_COMP_B_5_DP")
	)
	(arc
		(start 219.188284 -76.953872)
		(mid 219.055197 -76.898745)
		(end 219.00007 -76.765658)
		(width 0.1651)
		(layer "B.Cu")
		(net "PCIE_SCC_B_TO_COMP_B_5_DP")
	)
	(arc
		(start 279.082754 -135.302498)
		(mid 278.891187 -134.840015)
		(end 278.428704 -134.648448)
		(width 0.1651)
		(layer "B.Cu")
		(net "PCIE_SCC_B_TO_COMP_B_5_DP")
	)
	(arc
		(start 220.046042 -77.58303)
		(mid 219.861766 -77.138148)
		(end 219.416884 -76.953872)
		(width 0.1651)
		(layer "B.Cu")
		(net "PCIE_SCC_B_TO_COMP_B_5_DP")
	)
	(arc
		(start 279.274524 -135.69442)
		(mid 279.138922 -135.638252)
		(end 279.082754 -135.50265)
		(width 0.1651)
		(layer "B.Cu")
		(net "PCIE_SCC_B_TO_COMP_B_5_DP")
	)
	(segment
		(start 229.451916 -101.28504)
		(end 229.182168 -100.869496)
		(width 0.1651)
		(layer "B.Cu")
		(net "PCIE_SCC_B_TO_COMP_B_5_DN")
	)
	(segment
		(start 233.522012 -107.34294)
		(end 229.609904 -101.318568)
		(width 0.1651)
		(layer "B.Cu")
		(net "PCIE_SCC_B_TO_COMP_B_5_DN")
	)
	(segment
		(start 228.281992 -99.273614)
		(end 228.124004 -99.240086)
		(width 0.1651)
		(layer "B.Cu")
		(net "PCIE_SCC_B_TO_COMP_B_5_DN")
	)
	(segment
		(start 228.518212 -99.847146)
		(end 228.55174 -99.688904)
		(width 0.1651)
		(layer "B.Cu")
		(net "PCIE_SCC_B_TO_COMP_B_5_DN")
	)
	(segment
		(start 221.102936 -88.428068)
		(end 221.136464 -88.269826)
		(width 0.1651)
		(layer "B.Cu")
		(net "PCIE_SCC_B_TO_COMP_B_5_DN")
	)
	(segment
		(start 221.530672 -88.87714)
		(end 221.372684 -88.843358)
		(width 0.1651)
		(layer "B.Cu")
		(net "PCIE_SCC_B_TO_COMP_B_5_DN")
	)
	(segment
		(start 278.23668 -135.69442)
		(end 278.598884 -135.69442)
		(width 0.1651)
		(layer "B.Cu")
		(net "PCIE_SCC_B_TO_COMP_B_5_DN")
	)
	(segment
		(start 222.03664 -89.865962)
		(end 221.766892 -89.450672)
		(width 0.1651)
		(layer "B.Cu")
		(net "PCIE_SCC_B_TO_COMP_B_5_DN")
	)
	(segment
		(start 276.018752 -134.940548)
		(end 233.522012 -107.34294)
		(width 0.1651)
		(layer "B.Cu")
		(net "PCIE_SCC_B_TO_COMP_B_5_DN")
	)
	(segment
		(start 219.753942 -82.616802)
		(end 219.753942 -77.58303)
		(width 0.1651)
		(layer "B.Cu")
		(net "PCIE_SCC_B_TO_COMP_B_5_DN")
	)
	(segment
		(start 228.945948 -100.296218)
		(end 228.78796 -100.262436)
		(width 0.1651)
		(layer "B.Cu")
		(net "PCIE_SCC_B_TO_COMP_B_5_DN")
	)
	(segment
		(start 227.854256 -98.824542)
		(end 227.887784 -98.666554)
		(width 0.1651)
		(layer "B.Cu")
		(net "PCIE_SCC_B_TO_COMP_B_5_DN")
	)
	(segment
		(start 228.78796 -100.262436)
		(end 228.518212 -99.847146)
		(width 0.1651)
		(layer "B.Cu")
		(net "PCIE_SCC_B_TO_COMP_B_5_DN")
	)
	(segment
		(start 229.215696 -100.711508)
		(end 228.945948 -100.296218)
		(width 0.1651)
		(layer "B.Cu")
		(net "PCIE_SCC_B_TO_COMP_B_5_DN")
	)
	(segment
		(start 222.194628 -89.89949)
		(end 222.03664 -89.865962)
		(width 0.1651)
		(layer "B.Cu")
		(net "PCIE_SCC_B_TO_COMP_B_5_DN")
	)
	(segment
		(start 220.866716 -87.854536)
		(end 219.753942 -82.616802)
		(width 0.1651)
		(layer "B.Cu")
		(net "PCIE_SCC_B_TO_COMP_B_5_DN")
	)
	(segment
		(start 219.00007 -77.434186)
		(end 219.00007 -77.799946)
		(width 0.1651)
		(layer "B.Cu")
		(net "PCIE_SCC_B_TO_COMP_B_5_DN")
	)
	(segment
		(start 221.136464 -88.269826)
		(end 220.866716 -87.854536)
		(width 0.1651)
		(layer "B.Cu")
		(net "PCIE_SCC_B_TO_COMP_B_5_DN")
	)
	(segment
		(start 278.790654 -135.50265)
		(end 278.790654 -135.302498)
		(width 0.1651)
		(layer "B.Cu")
		(net "PCIE_SCC_B_TO_COMP_B_5_DN")
	)
	(segment
		(start 221.766892 -89.450672)
		(end 221.80042 -89.29243)
		(width 0.1651)
		(layer "B.Cu")
		(net "PCIE_SCC_B_TO_COMP_B_5_DN")
	)
	(segment
		(start 219.416884 -77.245972)
		(end 219.188284 -77.245972)
		(width 0.1651)
		(layer "B.Cu")
		(net "PCIE_SCC_B_TO_COMP_B_5_DN")
	)
	(segment
		(start 228.55174 -99.688904)
		(end 228.281992 -99.273614)
		(width 0.1651)
		(layer "B.Cu")
		(net "PCIE_SCC_B_TO_COMP_B_5_DN")
	)
	(segment
		(start 229.182168 -100.869496)
		(end 229.215696 -100.711508)
		(width 0.1651)
		(layer "B.Cu")
		(net "PCIE_SCC_B_TO_COMP_B_5_DN")
	)
	(segment
		(start 278.428704 -134.940548)
		(end 276.018752 -134.940548)
		(width 0.1651)
		(layer "B.Cu")
		(net "PCIE_SCC_B_TO_COMP_B_5_DN")
	)
	(segment
		(start 228.124004 -99.240086)
		(end 227.854256 -98.824542)
		(width 0.1651)
		(layer "B.Cu")
		(net "PCIE_SCC_B_TO_COMP_B_5_DN")
	)
	(segment
		(start 229.609904 -101.318568)
		(end 229.451916 -101.28504)
		(width 0.1651)
		(layer "B.Cu")
		(net "PCIE_SCC_B_TO_COMP_B_5_DN")
	)
	(segment
		(start 227.887784 -98.666554)
		(end 222.194628 -89.89949)
		(width 0.1651)
		(layer "B.Cu")
		(net "PCIE_SCC_B_TO_COMP_B_5_DN")
	)
	(segment
		(start 221.372684 -88.843358)
		(end 221.102936 -88.428068)
		(width 0.1651)
		(layer "B.Cu")
		(net "PCIE_SCC_B_TO_COMP_B_5_DN")
	)
	(segment
		(start 221.80042 -89.29243)
		(end 221.530672 -88.87714)
		(width 0.1651)
		(layer "B.Cu")
		(net "PCIE_SCC_B_TO_COMP_B_5_DN")
	)
	(arc
		(start 219.188284 -77.245972)
		(mid 219.055197 -77.301099)
		(end 219.00007 -77.434186)
		(width 0.1651)
		(layer "B.Cu")
		(net "PCIE_SCC_B_TO_COMP_B_5_DN")
	)
	(arc
		(start 278.598884 -135.69442)
		(mid 278.734486 -135.638252)
		(end 278.790654 -135.50265)
		(width 0.1651)
		(layer "B.Cu")
		(net "PCIE_SCC_B_TO_COMP_B_5_DN")
	)
	(arc
		(start 278.790654 -135.302498)
		(mid 278.684641 -135.046561)
		(end 278.428704 -134.940548)
		(width 0.1651)
		(layer "B.Cu")
		(net "PCIE_SCC_B_TO_COMP_B_5_DN")
	)
	(arc
		(start 219.753942 -77.58303)
		(mid 219.65522 -77.344694)
		(end 219.416884 -77.245972)
		(width 0.1651)
		(layer "B.Cu")
		(net "PCIE_SCC_B_TO_COMP_B_5_DN")
	)
	(segment
		(start 217.616786 -78.153768)
		(end 217.388186 -78.153768)
		(width 0.1651)
		(layer "B.Cu")
		(net "PCIE_SCC_B_TO_COMP_B_4_DP")
	)
	(segment
		(start 280.082752 -137.302748)
		(end 280.082752 -137.102596)
		(width 0.1651)
		(layer "B.Cu")
		(net "PCIE_SCC_B_TO_COMP_B_4_DP")
	)
	(segment
		(start 280.636726 -137.494518)
		(end 280.274522 -137.494518)
		(width 0.1651)
		(layer "B.Cu")
		(net "PCIE_SCC_B_TO_COMP_B_4_DP")
	)
	(segment
		(start 232.448862 -108.26242)
		(end 219.69095 -88.61806)
		(width 0.1651)
		(layer "B.Cu")
		(net "PCIE_SCC_B_TO_COMP_B_4_DP")
	)
	(segment
		(start 219.69095 -88.61806)
		(end 218.245944 -81.819496)
		(width 0.1651)
		(layer "B.Cu")
		(net "PCIE_SCC_B_TO_COMP_B_4_DP")
	)
	(segment
		(start 217.199972 -77.965554)
		(end 217.199972 -77.600048)
		(width 0.1651)
		(layer "B.Cu")
		(net "PCIE_SCC_B_TO_COMP_B_4_DP")
	)
	(segment
		(start 218.245944 -81.819496)
		(end 218.245944 -78.782926)
		(width 0.1651)
		(layer "B.Cu")
		(net "PCIE_SCC_B_TO_COMP_B_4_DP")
	)
	(segment
		(start 279.428702 -136.448546)
		(end 275.851874 -136.448546)
		(width 0.1651)
		(layer "B.Cu")
		(net "PCIE_SCC_B_TO_COMP_B_4_DP")
	)
	(segment
		(start 275.851874 -136.448546)
		(end 232.448862 -108.26242)
		(width 0.1651)
		(layer "B.Cu")
		(net "PCIE_SCC_B_TO_COMP_B_4_DP")
	)
	(arc
		(start 218.245944 -78.782926)
		(mid 218.061668 -78.338044)
		(end 217.616786 -78.153768)
		(width 0.1651)
		(layer "B.Cu")
		(net "PCIE_SCC_B_TO_COMP_B_4_DP")
	)
	(arc
		(start 280.274522 -137.494518)
		(mid 280.13892 -137.43835)
		(end 280.082752 -137.302748)
		(width 0.1651)
		(layer "B.Cu")
		(net "PCIE_SCC_B_TO_COMP_B_4_DP")
	)
	(arc
		(start 280.082752 -137.102596)
		(mid 279.891185 -136.640113)
		(end 279.428702 -136.448546)
		(width 0.1651)
		(layer "B.Cu")
		(net "PCIE_SCC_B_TO_COMP_B_4_DP")
	)
	(arc
		(start 217.388186 -78.153768)
		(mid 217.255099 -78.098641)
		(end 217.199972 -77.965554)
		(width 0.1651)
		(layer "B.Cu")
		(net "PCIE_SCC_B_TO_COMP_B_4_DP")
	)
	(segment
		(start 231.34066 -107.302808)
		(end 231.374442 -107.144566)
		(width 0.1651)
		(layer "B.Cu")
		(net "PCIE_SCC_B_TO_COMP_B_4_DN")
	)
	(segment
		(start 217.199972 -78.634082)
		(end 217.199972 -78.999842)
		(width 0.1651)
		(layer "B.Cu")
		(net "PCIE_SCC_B_TO_COMP_B_4_DN")
	)
	(segment
		(start 231.76865 -107.751626)
		(end 231.610408 -107.718098)
		(width 0.1651)
		(layer "B.Cu")
		(net "PCIE_SCC_B_TO_COMP_B_4_DN")
	)
	(segment
		(start 218.6559 -85.154262)
		(end 217.953336 -81.847944)
		(width 0.1651)
		(layer "B.Cu")
		(net "PCIE_SCC_B_TO_COMP_B_4_DN")
	)
	(segment
		(start 219.074746 -87.674958)
		(end 219.162884 -87.539322)
		(width 0.1651)
		(layer "B.Cu")
		(net "PCIE_SCC_B_TO_COMP_B_4_DN")
	)
	(segment
		(start 218.806522 -85.86216)
		(end 218.670886 -85.774276)
		(width 0.1651)
		(layer "B.Cu")
		(net "PCIE_SCC_B_TO_COMP_B_4_DN")
	)
	(segment
		(start 279.790652 -137.302748)
		(end 279.790652 -137.102596)
		(width 0.1651)
		(layer "B.Cu")
		(net "PCIE_SCC_B_TO_COMP_B_4_DN")
	)
	(segment
		(start 217.953844 -81.84515)
		(end 217.953844 -78.782926)
		(width 0.1651)
		(layer "B.Cu")
		(net "PCIE_SCC_B_TO_COMP_B_4_DN")
	)
	(segment
		(start 218.909392 -86.346792)
		(end 218.806522 -85.86216)
		(width 0.1651)
		(layer "B.Cu")
		(net "PCIE_SCC_B_TO_COMP_B_4_DN")
	)
	(segment
		(start 279.428702 -136.740646)
		(end 275.76526 -136.740646)
		(width 0.1651)
		(layer "B.Cu")
		(net "PCIE_SCC_B_TO_COMP_B_4_DN")
	)
	(segment
		(start 231.610408 -107.718098)
		(end 231.34066 -107.302808)
		(width 0.1651)
		(layer "B.Cu")
		(net "PCIE_SCC_B_TO_COMP_B_4_DN")
	)
	(segment
		(start 218.821508 -86.482174)
		(end 218.909392 -86.346792)
		(width 0.1651)
		(layer "B.Cu")
		(net "PCIE_SCC_B_TO_COMP_B_4_DN")
	)
	(segment
		(start 218.568016 -85.289644)
		(end 218.6559 -85.154262)
		(width 0.1651)
		(layer "B.Cu")
		(net "PCIE_SCC_B_TO_COMP_B_4_DN")
	)
	(segment
		(start 232.237534 -108.473748)
		(end 231.76865 -107.751626)
		(width 0.1651)
		(layer "B.Cu")
		(net "PCIE_SCC_B_TO_COMP_B_4_DN")
	)
	(segment
		(start 230.946452 -106.695494)
		(end 230.676704 -106.280204)
		(width 0.1651)
		(layer "B.Cu")
		(net "PCIE_SCC_B_TO_COMP_B_4_DN")
	)
	(segment
		(start 231.10444 -106.729276)
		(end 230.946452 -106.695494)
		(width 0.1651)
		(layer "B.Cu")
		(net "PCIE_SCC_B_TO_COMP_B_4_DN")
	)
	(segment
		(start 218.924378 -86.966806)
		(end 218.821508 -86.482174)
		(width 0.1651)
		(layer "B.Cu")
		(net "PCIE_SCC_B_TO_COMP_B_4_DN")
	)
	(segment
		(start 219.17787 -88.159336)
		(end 219.074746 -87.674958)
		(width 0.1651)
		(layer "B.Cu")
		(net "PCIE_SCC_B_TO_COMP_B_4_DN")
	)
	(segment
		(start 219.162884 -87.539322)
		(end 219.060014 -87.05469)
		(width 0.1651)
		(layer "B.Cu")
		(net "PCIE_SCC_B_TO_COMP_B_4_DN")
	)
	(segment
		(start 219.060014 -87.05469)
		(end 218.924378 -86.966806)
		(width 0.1651)
		(layer "B.Cu")
		(net "PCIE_SCC_B_TO_COMP_B_4_DN")
	)
	(segment
		(start 231.374442 -107.144566)
		(end 231.10444 -106.729276)
		(width 0.1651)
		(layer "B.Cu")
		(net "PCIE_SCC_B_TO_COMP_B_4_DN")
	)
	(segment
		(start 217.953336 -81.847944)
		(end 217.953844 -81.84515)
		(width 0.1651)
		(layer "B.Cu")
		(net "PCIE_SCC_B_TO_COMP_B_4_DN")
	)
	(segment
		(start 218.670886 -85.774276)
		(end 218.568016 -85.289644)
		(width 0.1651)
		(layer "B.Cu")
		(net "PCIE_SCC_B_TO_COMP_B_4_DN")
	)
	(segment
		(start 219.416376 -88.731852)
		(end 219.313506 -88.247474)
		(width 0.1651)
		(layer "B.Cu")
		(net "PCIE_SCC_B_TO_COMP_B_4_DN")
	)
	(segment
		(start 279.236678 -137.494518)
		(end 279.598882 -137.494518)
		(width 0.1651)
		(layer "B.Cu")
		(net "PCIE_SCC_B_TO_COMP_B_4_DN")
	)
	(segment
		(start 217.616786 -78.445868)
		(end 217.388186 -78.445868)
		(width 0.1651)
		(layer "B.Cu")
		(net "PCIE_SCC_B_TO_COMP_B_4_DN")
	)
	(segment
		(start 230.676704 -106.280204)
		(end 230.710232 -106.121962)
		(width 0.1651)
		(layer "B.Cu")
		(net "PCIE_SCC_B_TO_COMP_B_4_DN")
	)
	(segment
		(start 230.710232 -106.121962)
		(end 219.416376 -88.731852)
		(width 0.1651)
		(layer "B.Cu")
		(net "PCIE_SCC_B_TO_COMP_B_4_DN")
	)
	(segment
		(start 219.313506 -88.247474)
		(end 219.17787 -88.159336)
		(width 0.1651)
		(layer "B.Cu")
		(net "PCIE_SCC_B_TO_COMP_B_4_DN")
	)
	(segment
		(start 275.76526 -136.740646)
		(end 232.237534 -108.473748)
		(width 0.1651)
		(layer "B.Cu")
		(net "PCIE_SCC_B_TO_COMP_B_4_DN")
	)
	(arc
		(start 217.953844 -78.782926)
		(mid 217.855122 -78.54459)
		(end 217.616786 -78.445868)
		(width 0.1651)
		(layer "B.Cu")
		(net "PCIE_SCC_B_TO_COMP_B_4_DN")
	)
	(arc
		(start 279.790652 -137.102596)
		(mid 279.684639 -136.846659)
		(end 279.428702 -136.740646)
		(width 0.1651)
		(layer "B.Cu")
		(net "PCIE_SCC_B_TO_COMP_B_4_DN")
	)
	(arc
		(start 217.388186 -78.445868)
		(mid 217.255099 -78.500995)
		(end 217.199972 -78.634082)
		(width 0.1651)
		(layer "B.Cu")
		(net "PCIE_SCC_B_TO_COMP_B_4_DN")
	)
	(arc
		(start 279.598882 -137.494518)
		(mid 279.734484 -137.43835)
		(end 279.790652 -137.302748)
		(width 0.1651)
		(layer "B.Cu")
		(net "PCIE_SCC_B_TO_COMP_B_4_DN")
	)
	(segment
		(start 216.4461 -83.431888)
		(end 216.4461 -77.58303)
		(width 0.1651)
		(layer "B.Cu")
		(net "PCIE_SCC_B_TO_COMP_B_3_DP")
	)
	(segment
		(start 275.676868 -138.24839)
		(end 230.856536 -109.138974)
		(width 0.1651)
		(layer "B.Cu")
		(net "PCIE_SCC_B_TO_COMP_B_3_DP")
	)
	(segment
		(start 230.856536 -109.138974)
		(end 217.55608 -88.6587)
		(width 0.1651)
		(layer "B.Cu")
		(net "PCIE_SCC_B_TO_COMP_B_3_DP")
	)
	(segment
		(start 217.55608 -88.658446)
		(end 216.4461 -83.431888)
		(width 0.1651)
		(layer "B.Cu")
		(net "PCIE_SCC_B_TO_COMP_B_3_DP")
	)
	(segment
		(start 278.428704 -138.24839)
		(end 275.676868 -138.24839)
		(width 0.1651)
		(layer "B.Cu")
		(net "PCIE_SCC_B_TO_COMP_B_3_DP")
	)
	(segment
		(start 279.082754 -139.102592)
		(end 279.082754 -138.90244)
		(width 0.1651)
		(layer "B.Cu")
		(net "PCIE_SCC_B_TO_COMP_B_3_DP")
	)
	(segment
		(start 279.636728 -139.294362)
		(end 279.274524 -139.294362)
		(width 0.1651)
		(layer "B.Cu")
		(net "PCIE_SCC_B_TO_COMP_B_3_DP")
	)
	(segment
		(start 217.55608 -88.6587)
		(end 217.55608 -88.658446)
		(width 0.1651)
		(layer "B.Cu")
		(net "PCIE_SCC_B_TO_COMP_B_3_DP")
	)
	(segment
		(start 215.400128 -76.765658)
		(end 215.400128 -76.399898)
		(width 0.1651)
		(layer "B.Cu")
		(net "PCIE_SCC_B_TO_COMP_B_3_DP")
	)
	(segment
		(start 215.816942 -76.953872)
		(end 215.588342 -76.953872)
		(width 0.1651)
		(layer "B.Cu")
		(net "PCIE_SCC_B_TO_COMP_B_3_DP")
	)
	(arc
		(start 279.274524 -139.294362)
		(mid 279.138922 -139.238194)
		(end 279.082754 -139.102592)
		(width 0.1651)
		(layer "B.Cu")
		(net "PCIE_SCC_B_TO_COMP_B_3_DP")
	)
	(arc
		(start 215.588342 -76.953872)
		(mid 215.455255 -76.898745)
		(end 215.400128 -76.765658)
		(width 0.1651)
		(layer "B.Cu")
		(net "PCIE_SCC_B_TO_COMP_B_3_DP")
	)
	(arc
		(start 279.082754 -138.90244)
		(mid 278.891187 -138.439957)
		(end 278.428704 -138.24839)
		(width 0.1651)
		(layer "B.Cu")
		(net "PCIE_SCC_B_TO_COMP_B_3_DP")
	)
	(arc
		(start 216.4461 -77.58303)
		(mid 216.261824 -77.138148)
		(end 215.816942 -76.953872)
		(width 0.1651)
		(layer "B.Cu")
		(net "PCIE_SCC_B_TO_COMP_B_3_DP")
	)
	(segment
		(start 278.23668 -139.294362)
		(end 278.598884 -139.294362)
		(width 0.1651)
		(layer "B.Cu")
		(net "PCIE_SCC_B_TO_COMP_B_3_DN")
	)
	(segment
		(start 216.903046 -87.540846)
		(end 216.991184 -87.405464)
		(width 0.1651)
		(layer "B.Cu")
		(net "PCIE_SCC_B_TO_COMP_B_3_DN")
	)
	(segment
		(start 232.690162 -110.678468)
		(end 232.532174 -110.711996)
		(width 0.1651)
		(layer "B.Cu")
		(net "PCIE_SCC_B_TO_COMP_B_3_DN")
	)
	(segment
		(start 216.888314 -86.920832)
		(end 216.752678 -86.832694)
		(width 0.1651)
		(layer "B.Cu")
		(net "PCIE_SCC_B_TO_COMP_B_3_DN")
	)
	(segment
		(start 216.49944 -85.640164)
		(end 216.39657 -85.155786)
		(width 0.1651)
		(layer "B.Cu")
		(net "PCIE_SCC_B_TO_COMP_B_3_DN")
	)
	(segment
		(start 278.790654 -139.102592)
		(end 278.790654 -138.90244)
		(width 0.1651)
		(layer "B.Cu")
		(net "PCIE_SCC_B_TO_COMP_B_3_DN")
	)
	(segment
		(start 215.816942 -77.245972)
		(end 215.588342 -77.245972)
		(width 0.1651)
		(layer "B.Cu")
		(net "PCIE_SCC_B_TO_COMP_B_3_DN")
	)
	(segment
		(start 216.635076 -85.728302)
		(end 216.49944 -85.640164)
		(width 0.1651)
		(layer "B.Cu")
		(net "PCIE_SCC_B_TO_COMP_B_3_DN")
	)
	(segment
		(start 231.09428 -109.778292)
		(end 231.060498 -109.62005)
		(width 0.1651)
		(layer "B.Cu")
		(net "PCIE_SCC_B_TO_COMP_B_3_DN")
	)
	(segment
		(start 230.645208 -109.350302)
		(end 217.281506 -88.772238)
		(width 0.1651)
		(layer "B.Cu")
		(net "PCIE_SCC_B_TO_COMP_B_3_DN")
	)
	(segment
		(start 231.50957 -110.04804)
		(end 231.09428 -109.778292)
		(width 0.1651)
		(layer "B.Cu")
		(net "PCIE_SCC_B_TO_COMP_B_3_DN")
	)
	(segment
		(start 215.400128 -77.434186)
		(end 215.400128 -77.799946)
		(width 0.1651)
		(layer "B.Cu")
		(net "PCIE_SCC_B_TO_COMP_B_3_DN")
	)
	(segment
		(start 216.39657 -85.155786)
		(end 216.484708 -85.02015)
		(width 0.1651)
		(layer "B.Cu")
		(net "PCIE_SCC_B_TO_COMP_B_3_DN")
	)
	(segment
		(start 278.428704 -138.54049)
		(end 275.590254 -138.54049)
		(width 0.1651)
		(layer "B.Cu")
		(net "PCIE_SCC_B_TO_COMP_B_3_DN")
	)
	(segment
		(start 232.11663 -110.442248)
		(end 232.083102 -110.28426)
		(width 0.1651)
		(layer "B.Cu")
		(net "PCIE_SCC_B_TO_COMP_B_3_DN")
	)
	(segment
		(start 216.154 -83.462622)
		(end 216.154 -77.58303)
		(width 0.1651)
		(layer "B.Cu")
		(net "PCIE_SCC_B_TO_COMP_B_3_DN")
	)
	(segment
		(start 217.141552 -88.113362)
		(end 217.00617 -88.025478)
		(width 0.1651)
		(layer "B.Cu")
		(net "PCIE_SCC_B_TO_COMP_B_3_DN")
	)
	(segment
		(start 217.00617 -88.025478)
		(end 216.903046 -87.540846)
		(width 0.1651)
		(layer "B.Cu")
		(net "PCIE_SCC_B_TO_COMP_B_3_DN")
	)
	(segment
		(start 232.083102 -110.28426)
		(end 231.667812 -110.014258)
		(width 0.1651)
		(layer "B.Cu")
		(net "PCIE_SCC_B_TO_COMP_B_3_DN")
	)
	(segment
		(start 232.532174 -110.711996)
		(end 232.11663 -110.442248)
		(width 0.1651)
		(layer "B.Cu")
		(net "PCIE_SCC_B_TO_COMP_B_3_DN")
	)
	(segment
		(start 231.060498 -109.62005)
		(end 230.645208 -109.350302)
		(width 0.1651)
		(layer "B.Cu")
		(net "PCIE_SCC_B_TO_COMP_B_3_DN")
	)
	(segment
		(start 216.752678 -86.832694)
		(end 216.649808 -86.348316)
		(width 0.1651)
		(layer "B.Cu")
		(net "PCIE_SCC_B_TO_COMP_B_3_DN")
	)
	(segment
		(start 216.484708 -85.02015)
		(end 216.154 -83.462622)
		(width 0.1651)
		(layer "B.Cu")
		(net "PCIE_SCC_B_TO_COMP_B_3_DN")
	)
	(segment
		(start 216.737946 -86.21268)
		(end 216.635076 -85.728302)
		(width 0.1651)
		(layer "B.Cu")
		(net "PCIE_SCC_B_TO_COMP_B_3_DN")
	)
	(segment
		(start 231.667812 -110.014258)
		(end 231.50957 -110.04804)
		(width 0.1651)
		(layer "B.Cu")
		(net "PCIE_SCC_B_TO_COMP_B_3_DN")
	)
	(segment
		(start 275.590254 -138.54049)
		(end 232.690162 -110.678468)
		(width 0.1651)
		(layer "B.Cu")
		(net "PCIE_SCC_B_TO_COMP_B_3_DN")
	)
	(segment
		(start 217.281506 -88.772238)
		(end 217.141552 -88.113362)
		(width 0.1651)
		(layer "B.Cu")
		(net "PCIE_SCC_B_TO_COMP_B_3_DN")
	)
	(segment
		(start 216.991184 -87.405464)
		(end 216.888314 -86.920832)
		(width 0.1651)
		(layer "B.Cu")
		(net "PCIE_SCC_B_TO_COMP_B_3_DN")
	)
	(segment
		(start 216.649808 -86.348316)
		(end 216.737946 -86.21268)
		(width 0.1651)
		(layer "B.Cu")
		(net "PCIE_SCC_B_TO_COMP_B_3_DN")
	)
	(arc
		(start 215.588342 -77.245972)
		(mid 215.455255 -77.301099)
		(end 215.400128 -77.434186)
		(width 0.1651)
		(layer "B.Cu")
		(net "PCIE_SCC_B_TO_COMP_B_3_DN")
	)
	(arc
		(start 216.154 -77.58303)
		(mid 216.055278 -77.344694)
		(end 215.816942 -77.245972)
		(width 0.1651)
		(layer "B.Cu")
		(net "PCIE_SCC_B_TO_COMP_B_3_DN")
	)
	(arc
		(start 278.598884 -139.294362)
		(mid 278.734486 -139.238194)
		(end 278.790654 -139.102592)
		(width 0.1651)
		(layer "B.Cu")
		(net "PCIE_SCC_B_TO_COMP_B_3_DN")
	)
	(arc
		(start 278.790654 -138.90244)
		(mid 278.684641 -138.646503)
		(end 278.428704 -138.54049)
		(width 0.1651)
		(layer "B.Cu")
		(net "PCIE_SCC_B_TO_COMP_B_3_DN")
	)
	(segment
		(start 214.646002 -83.173316)
		(end 214.646002 -78.782926)
		(width 0.1651)
		(layer "B.Cu")
		(net "PCIE_SCC_B_TO_COMP_B_2_DP")
	)
	(segment
		(start 213.60003 -77.965554)
		(end 213.60003 -77.600048)
		(width 0.1651)
		(layer "B.Cu")
		(net "PCIE_SCC_B_TO_COMP_B_2_DP")
	)
	(segment
		(start 279.428702 -140.048488)
		(end 275.157438 -140.048488)
		(width 0.1651)
		(layer "B.Cu")
		(net "PCIE_SCC_B_TO_COMP_B_2_DP")
	)
	(segment
		(start 215.9635 -89.370662)
		(end 214.646002 -83.173316)
		(width 0.1651)
		(layer "B.Cu")
		(net "PCIE_SCC_B_TO_COMP_B_2_DP")
	)
	(segment
		(start 229.703122 -110.527592)
		(end 215.9635 -89.370662)
		(width 0.1651)
		(layer "B.Cu")
		(net "PCIE_SCC_B_TO_COMP_B_2_DP")
	)
	(segment
		(start 214.016844 -78.153768)
		(end 213.788244 -78.153768)
		(width 0.1651)
		(layer "B.Cu")
		(net "PCIE_SCC_B_TO_COMP_B_2_DP")
	)
	(segment
		(start 275.157438 -140.048488)
		(end 229.703122 -110.527592)
		(width 0.1651)
		(layer "B.Cu")
		(net "PCIE_SCC_B_TO_COMP_B_2_DP")
	)
	(segment
		(start 280.636726 -141.09446)
		(end 280.274522 -141.09446)
		(width 0.1651)
		(layer "B.Cu")
		(net "PCIE_SCC_B_TO_COMP_B_2_DP")
	)
	(segment
		(start 280.082752 -140.90269)
		(end 280.082752 -140.702538)
		(width 0.1651)
		(layer "B.Cu")
		(net "PCIE_SCC_B_TO_COMP_B_2_DP")
	)
	(arc
		(start 213.788244 -78.153768)
		(mid 213.655157 -78.098641)
		(end 213.60003 -77.965554)
		(width 0.1651)
		(layer "B.Cu")
		(net "PCIE_SCC_B_TO_COMP_B_2_DP")
	)
	(arc
		(start 280.082752 -140.702538)
		(mid 279.891185 -140.240055)
		(end 279.428702 -140.048488)
		(width 0.1651)
		(layer "B.Cu")
		(net "PCIE_SCC_B_TO_COMP_B_2_DP")
	)
	(arc
		(start 214.646002 -78.782926)
		(mid 214.461726 -78.338044)
		(end 214.016844 -78.153768)
		(width 0.1651)
		(layer "B.Cu")
		(net "PCIE_SCC_B_TO_COMP_B_2_DP")
	)
	(arc
		(start 280.274522 -141.09446)
		(mid 280.13892 -141.038292)
		(end 280.082752 -140.90269)
		(width 0.1651)
		(layer "B.Cu")
		(net "PCIE_SCC_B_TO_COMP_B_2_DP")
	)
	(segment
		(start 230.356156 -111.436658)
		(end 229.940866 -111.16691)
		(width 0.1651)
		(layer "B.Cu")
		(net "PCIE_SCC_B_TO_COMP_B_2_DN")
	)
	(segment
		(start 279.236678 -141.09446)
		(end 279.598882 -141.09446)
		(width 0.1651)
		(layer "B.Cu")
		(net "PCIE_SCC_B_TO_COMP_B_2_DN")
	)
	(segment
		(start 214.368888 -83.824064)
		(end 214.456772 -83.688428)
		(width 0.1651)
		(layer "B.Cu")
		(net "PCIE_SCC_B_TO_COMP_B_2_DN")
	)
	(segment
		(start 214.875872 -86.209124)
		(end 214.963756 -86.073488)
		(width 0.1651)
		(layer "B.Cu")
		(net "PCIE_SCC_B_TO_COMP_B_2_DN")
	)
	(segment
		(start 229.907084 -111.008668)
		(end 229.491794 -110.73892)
		(width 0.1651)
		(layer "B.Cu")
		(net "PCIE_SCC_B_TO_COMP_B_2_DN")
	)
	(segment
		(start 279.790652 -140.90269)
		(end 279.790652 -140.702538)
		(width 0.1651)
		(layer "B.Cu")
		(net "PCIE_SCC_B_TO_COMP_B_2_DN")
	)
	(segment
		(start 214.471758 -84.308442)
		(end 214.368888 -83.824064)
		(width 0.1651)
		(layer "B.Cu")
		(net "PCIE_SCC_B_TO_COMP_B_2_DN")
	)
	(segment
		(start 230.929688 -111.672878)
		(end 230.514398 -111.402876)
		(width 0.1651)
		(layer "B.Cu")
		(net "PCIE_SCC_B_TO_COMP_B_2_DN")
	)
	(segment
		(start 214.860886 -85.58911)
		(end 214.72525 -85.500972)
		(width 0.1651)
		(layer "B.Cu")
		(net "PCIE_SCC_B_TO_COMP_B_2_DN")
	)
	(segment
		(start 214.72525 -85.500972)
		(end 214.62238 -85.016594)
		(width 0.1651)
		(layer "B.Cu")
		(net "PCIE_SCC_B_TO_COMP_B_2_DN")
	)
	(segment
		(start 214.963756 -86.073488)
		(end 214.860886 -85.58911)
		(width 0.1651)
		(layer "B.Cu")
		(net "PCIE_SCC_B_TO_COMP_B_2_DN")
	)
	(segment
		(start 229.491794 -110.73892)
		(end 215.688926 -89.484454)
		(width 0.1651)
		(layer "B.Cu")
		(net "PCIE_SCC_B_TO_COMP_B_2_DN")
	)
	(segment
		(start 231.536748 -112.067086)
		(end 231.37876 -112.100614)
		(width 0.1651)
		(layer "B.Cu")
		(net "PCIE_SCC_B_TO_COMP_B_2_DN")
	)
	(segment
		(start 214.710264 -84.880958)
		(end 214.607394 -84.39658)
		(width 0.1651)
		(layer "B.Cu")
		(net "PCIE_SCC_B_TO_COMP_B_2_DN")
	)
	(segment
		(start 214.978742 -86.693502)
		(end 214.875872 -86.209124)
		(width 0.1651)
		(layer "B.Cu")
		(net "PCIE_SCC_B_TO_COMP_B_2_DN")
	)
	(segment
		(start 229.940866 -111.16691)
		(end 229.907084 -111.008668)
		(width 0.1651)
		(layer "B.Cu")
		(net "PCIE_SCC_B_TO_COMP_B_2_DN")
	)
	(segment
		(start 231.37876 -112.100614)
		(end 230.963216 -111.830866)
		(width 0.1651)
		(layer "B.Cu")
		(net "PCIE_SCC_B_TO_COMP_B_2_DN")
	)
	(segment
		(start 214.62238 -85.016594)
		(end 214.710264 -84.880958)
		(width 0.1651)
		(layer "B.Cu")
		(net "PCIE_SCC_B_TO_COMP_B_2_DN")
	)
	(segment
		(start 214.016844 -78.445868)
		(end 213.788244 -78.445868)
		(width 0.1651)
		(layer "B.Cu")
		(net "PCIE_SCC_B_TO_COMP_B_2_DN")
	)
	(segment
		(start 275.070824 -140.340588)
		(end 231.536748 -112.067086)
		(width 0.1651)
		(layer "B.Cu")
		(net "PCIE_SCC_B_TO_COMP_B_2_DN")
	)
	(segment
		(start 213.60003 -78.634082)
		(end 213.60003 -78.999842)
		(width 0.1651)
		(layer "B.Cu")
		(net "PCIE_SCC_B_TO_COMP_B_2_DN")
	)
	(segment
		(start 215.688926 -89.484454)
		(end 215.114378 -86.78164)
		(width 0.1651)
		(layer "B.Cu")
		(net "PCIE_SCC_B_TO_COMP_B_2_DN")
	)
	(segment
		(start 214.353902 -83.20405)
		(end 214.353902 -78.782926)
		(width 0.1651)
		(layer "B.Cu")
		(net "PCIE_SCC_B_TO_COMP_B_2_DN")
	)
	(segment
		(start 214.607394 -84.39658)
		(end 214.471758 -84.308442)
		(width 0.1651)
		(layer "B.Cu")
		(net "PCIE_SCC_B_TO_COMP_B_2_DN")
	)
	(segment
		(start 230.514398 -111.402876)
		(end 230.356156 -111.436658)
		(width 0.1651)
		(layer "B.Cu")
		(net "PCIE_SCC_B_TO_COMP_B_2_DN")
	)
	(segment
		(start 279.428702 -140.340588)
		(end 275.070824 -140.340588)
		(width 0.1651)
		(layer "B.Cu")
		(net "PCIE_SCC_B_TO_COMP_B_2_DN")
	)
	(segment
		(start 230.963216 -111.830866)
		(end 230.929688 -111.672878)
		(width 0.1651)
		(layer "B.Cu")
		(net "PCIE_SCC_B_TO_COMP_B_2_DN")
	)
	(segment
		(start 214.456772 -83.688428)
		(end 214.353902 -83.20405)
		(width 0.1651)
		(layer "B.Cu")
		(net "PCIE_SCC_B_TO_COMP_B_2_DN")
	)
	(segment
		(start 215.114378 -86.78164)
		(end 214.978742 -86.693502)
		(width 0.1651)
		(layer "B.Cu")
		(net "PCIE_SCC_B_TO_COMP_B_2_DN")
	)
	(arc
		(start 279.790652 -140.702538)
		(mid 279.684639 -140.446601)
		(end 279.428702 -140.340588)
		(width 0.1651)
		(layer "B.Cu")
		(net "PCIE_SCC_B_TO_COMP_B_2_DN")
	)
	(arc
		(start 214.353902 -78.782926)
		(mid 214.25518 -78.54459)
		(end 214.016844 -78.445868)
		(width 0.1651)
		(layer "B.Cu")
		(net "PCIE_SCC_B_TO_COMP_B_2_DN")
	)
	(arc
		(start 213.788244 -78.445868)
		(mid 213.655157 -78.500995)
		(end 213.60003 -78.634082)
		(width 0.1651)
		(layer "B.Cu")
		(net "PCIE_SCC_B_TO_COMP_B_2_DN")
	)
	(arc
		(start 279.598882 -141.09446)
		(mid 279.734484 -141.038292)
		(end 279.790652 -140.90269)
		(width 0.1651)
		(layer "B.Cu")
		(net "PCIE_SCC_B_TO_COMP_B_2_DN")
	)
	(segment
		(start 279.636728 -142.894304)
		(end 279.274524 -142.894304)
		(width 0.1651)
		(layer "B.Cu")
		(net "PCIE_SCC_B_TO_COMP_B_1_DP")
	)
	(segment
		(start 213.757002 -89.108026)
		(end 212.846158 -85.5218)
		(width 0.1651)
		(layer "B.Cu")
		(net "PCIE_SCC_B_TO_COMP_B_1_DP")
	)
	(segment
		(start 278.428704 -141.848332)
		(end 274.39239 -141.848332)
		(width 0.1651)
		(layer "B.Cu")
		(net "PCIE_SCC_B_TO_COMP_B_1_DP")
	)
	(segment
		(start 279.082754 -142.702534)
		(end 279.082754 -142.502382)
		(width 0.1651)
		(layer "B.Cu")
		(net "PCIE_SCC_B_TO_COMP_B_1_DP")
	)
	(segment
		(start 274.39239 -141.848332)
		(end 228.808534 -112.248696)
		(width 0.1651)
		(layer "B.Cu")
		(net "PCIE_SCC_B_TO_COMP_B_1_DP")
	)
	(segment
		(start 211.800186 -76.765658)
		(end 211.800186 -76.399898)
		(width 0.1651)
		(layer "B.Cu")
		(net "PCIE_SCC_B_TO_COMP_B_1_DP")
	)
	(segment
		(start 212.846158 -85.5218)
		(end 212.846158 -77.58303)
		(width 0.1651)
		(layer "B.Cu")
		(net "PCIE_SCC_B_TO_COMP_B_1_DP")
	)
	(segment
		(start 228.808534 -112.248696)
		(end 213.757002 -89.108026)
		(width 0.1651)
		(layer "B.Cu")
		(net "PCIE_SCC_B_TO_COMP_B_1_DP")
	)
	(segment
		(start 212.217 -76.953872)
		(end 211.9884 -76.953872)
		(width 0.1651)
		(layer "B.Cu")
		(net "PCIE_SCC_B_TO_COMP_B_1_DP")
	)
	(arc
		(start 212.846158 -77.58303)
		(mid 212.661882 -77.138148)
		(end 212.217 -76.953872)
		(width 0.1651)
		(layer "B.Cu")
		(net "PCIE_SCC_B_TO_COMP_B_1_DP")
	)
	(arc
		(start 211.9884 -76.953872)
		(mid 211.855313 -76.898745)
		(end 211.800186 -76.765658)
		(width 0.1651)
		(layer "B.Cu")
		(net "PCIE_SCC_B_TO_COMP_B_1_DP")
	)
	(arc
		(start 279.274524 -142.894304)
		(mid 279.138922 -142.838136)
		(end 279.082754 -142.702534)
		(width 0.1651)
		(layer "B.Cu")
		(net "PCIE_SCC_B_TO_COMP_B_1_DP")
	)
	(arc
		(start 279.082754 -142.502382)
		(mid 278.891187 -142.039899)
		(end 278.428704 -141.848332)
		(width 0.1651)
		(layer "B.Cu")
		(net "PCIE_SCC_B_TO_COMP_B_1_DP")
	)
	(segment
		(start 225.794316 -108.150914)
		(end 225.524314 -107.735624)
		(width 0.1651)
		(layer "B.Cu")
		(net "PCIE_SCC_B_TO_COMP_B_1_DN")
	)
	(segment
		(start 225.096324 -107.286806)
		(end 225.129598 -107.128564)
		(width 0.1651)
		(layer "B.Cu")
		(net "PCIE_SCC_B_TO_COMP_B_1_DN")
	)
	(segment
		(start 225.760788 -108.308902)
		(end 225.794316 -108.150914)
		(width 0.1651)
		(layer "B.Cu")
		(net "PCIE_SCC_B_TO_COMP_B_1_DN")
	)
	(segment
		(start 228.266752 -111.95177)
		(end 227.97008 -111.495586)
		(width 0.1651)
		(layer "B.Cu")
		(net "PCIE_SCC_B_TO_COMP_B_1_DN")
	)
	(segment
		(start 274.305776 -142.140432)
		(end 228.59746 -112.460024)
		(width 0.1651)
		(layer "B.Cu")
		(net "PCIE_SCC_B_TO_COMP_B_1_DN")
	)
	(segment
		(start 213.485476 -89.226644)
		(end 212.554058 -85.558884)
		(width 0.1651)
		(layer "B.Cu")
		(net "PCIE_SCC_B_TO_COMP_B_1_DN")
	)
	(segment
		(start 227.376482 -110.582964)
		(end 226.189032 -108.75772)
		(width 0.1651)
		(layer "B.Cu")
		(net "PCIE_SCC_B_TO_COMP_B_1_DN")
	)
	(segment
		(start 226.189032 -108.75772)
		(end 226.031044 -108.724192)
		(width 0.1651)
		(layer "B.Cu")
		(net "PCIE_SCC_B_TO_COMP_B_1_DN")
	)
	(segment
		(start 216.404698 -93.714824)
		(end 216.24671 -93.681296)
		(width 0.1651)
		(layer "B.Cu")
		(net "PCIE_SCC_B_TO_COMP_B_1_DN")
	)
	(segment
		(start 215.271604 -92.182442)
		(end 215.305132 -92.0242)
		(width 0.1651)
		(layer "B.Cu")
		(net "PCIE_SCC_B_TO_COMP_B_1_DN")
	)
	(segment
		(start 216.24671 -93.681296)
		(end 215.976708 -93.26626)
		(width 0.1651)
		(layer "B.Cu")
		(net "PCIE_SCC_B_TO_COMP_B_1_DN")
	)
	(segment
		(start 212.554058 -85.558884)
		(end 212.554058 -77.58303)
		(width 0.1651)
		(layer "B.Cu")
		(net "PCIE_SCC_B_TO_COMP_B_1_DN")
	)
	(segment
		(start 226.031044 -108.724192)
		(end 225.760788 -108.308902)
		(width 0.1651)
		(layer "B.Cu")
		(net "PCIE_SCC_B_TO_COMP_B_1_DN")
	)
	(segment
		(start 278.790654 -142.702534)
		(end 278.790654 -142.502382)
		(width 0.1651)
		(layer "B.Cu")
		(net "PCIE_SCC_B_TO_COMP_B_1_DN")
	)
	(segment
		(start 215.305132 -92.0242)
		(end 213.485476 -89.226644)
		(width 0.1651)
		(layer "B.Cu")
		(net "PCIE_SCC_B_TO_COMP_B_1_DN")
	)
	(segment
		(start 215.976708 -93.26626)
		(end 216.009982 -93.108018)
		(width 0.1651)
		(layer "B.Cu")
		(net "PCIE_SCC_B_TO_COMP_B_1_DN")
	)
	(segment
		(start 227.97008 -111.495586)
		(end 227.376482 -110.582964)
		(width 0.1651)
		(layer "B.Cu")
		(net "PCIE_SCC_B_TO_COMP_B_1_DN")
	)
	(segment
		(start 216.009982 -93.108018)
		(end 215.699848 -92.631006)
		(width 0.1651)
		(layer "B.Cu")
		(net "PCIE_SCC_B_TO_COMP_B_1_DN")
	)
	(segment
		(start 216.6747 -94.130114)
		(end 216.404698 -93.714824)
		(width 0.1651)
		(layer "B.Cu")
		(net "PCIE_SCC_B_TO_COMP_B_1_DN")
	)
	(segment
		(start 216.641172 -94.288102)
		(end 216.6747 -94.130114)
		(width 0.1651)
		(layer "B.Cu")
		(net "PCIE_SCC_B_TO_COMP_B_1_DN")
	)
	(segment
		(start 278.23668 -142.894304)
		(end 278.598884 -142.894304)
		(width 0.1651)
		(layer "B.Cu")
		(net "PCIE_SCC_B_TO_COMP_B_1_DN")
	)
	(segment
		(start 278.428704 -142.140432)
		(end 274.305776 -142.140432)
		(width 0.1651)
		(layer "B.Cu")
		(net "PCIE_SCC_B_TO_COMP_B_1_DN")
	)
	(segment
		(start 217.069416 -94.73692)
		(end 216.911428 -94.703392)
		(width 0.1651)
		(layer "B.Cu")
		(net "PCIE_SCC_B_TO_COMP_B_1_DN")
	)
	(segment
		(start 225.524314 -107.735624)
		(end 225.366326 -107.702096)
		(width 0.1651)
		(layer "B.Cu")
		(net "PCIE_SCC_B_TO_COMP_B_1_DN")
	)
	(segment
		(start 225.129598 -107.128564)
		(end 217.069416 -94.73692)
		(width 0.1651)
		(layer "B.Cu")
		(net "PCIE_SCC_B_TO_COMP_B_1_DN")
	)
	(segment
		(start 225.366326 -107.702096)
		(end 225.096324 -107.286806)
		(width 0.1651)
		(layer "B.Cu")
		(net "PCIE_SCC_B_TO_COMP_B_1_DN")
	)
	(segment
		(start 216.911428 -94.703392)
		(end 216.641172 -94.288102)
		(width 0.1651)
		(layer "B.Cu")
		(net "PCIE_SCC_B_TO_COMP_B_1_DN")
	)
	(segment
		(start 228.59746 -112.460024)
		(end 228.266752 -111.95177)
		(width 0.1651)
		(layer "B.Cu")
		(net "PCIE_SCC_B_TO_COMP_B_1_DN")
	)
	(segment
		(start 215.699848 -92.631006)
		(end 215.541606 -92.597478)
		(width 0.1651)
		(layer "B.Cu")
		(net "PCIE_SCC_B_TO_COMP_B_1_DN")
	)
	(segment
		(start 211.800186 -77.434186)
		(end 211.800186 -77.799946)
		(width 0.1651)
		(layer "B.Cu")
		(net "PCIE_SCC_B_TO_COMP_B_1_DN")
	)
	(segment
		(start 212.217 -77.245972)
		(end 211.9884 -77.245972)
		(width 0.1651)
		(layer "B.Cu")
		(net "PCIE_SCC_B_TO_COMP_B_1_DN")
	)
	(segment
		(start 215.541606 -92.597478)
		(end 215.271604 -92.182442)
		(width 0.1651)
		(layer "B.Cu")
		(net "PCIE_SCC_B_TO_COMP_B_1_DN")
	)
	(arc
		(start 212.554058 -77.58303)
		(mid 212.455336 -77.344694)
		(end 212.217 -77.245972)
		(width 0.1651)
		(layer "B.Cu")
		(net "PCIE_SCC_B_TO_COMP_B_1_DN")
	)
	(arc
		(start 278.790654 -142.502382)
		(mid 278.684641 -142.246445)
		(end 278.428704 -142.140432)
		(width 0.1651)
		(layer "B.Cu")
		(net "PCIE_SCC_B_TO_COMP_B_1_DN")
	)
	(arc
		(start 211.9884 -77.245972)
		(mid 211.855313 -77.301099)
		(end 211.800186 -77.434186)
		(width 0.1651)
		(layer "B.Cu")
		(net "PCIE_SCC_B_TO_COMP_B_1_DN")
	)
	(arc
		(start 278.598884 -142.894304)
		(mid 278.734486 -142.838136)
		(end 278.790654 -142.702534)
		(width 0.1651)
		(layer "B.Cu")
		(net "PCIE_SCC_B_TO_COMP_B_1_DN")
	)
	(segment
		(start 227.518722 -113.30686)
		(end 212.936836 -91.286838)
		(width 0.1651)
		(layer "B.Cu")
		(net "PCIE_SCC_B_TO_COMP_B_0_DP")
	)
	(segment
		(start 211.04606 -85.281516)
		(end 211.04606 -78.719426)
		(width 0.1651)
		(layer "B.Cu")
		(net "PCIE_SCC_B_TO_COMP_B_0_DP")
	)
	(segment
		(start 279.22855 -143.64843)
		(end 274.168362 -143.64843)
		(width 0.1651)
		(layer "B.Cu")
		(net "PCIE_SCC_B_TO_COMP_B_0_DP")
	)
	(segment
		(start 227.518976 -113.307368)
		(end 227.518722 -113.30686)
		(width 0.1651)
		(layer "B.Cu")
		(net "PCIE_SCC_B_TO_COMP_B_0_DP")
	)
	(segment
		(start 280.636726 -144.694402)
		(end 280.274522 -144.694402)
		(width 0.1651)
		(layer "B.Cu")
		(net "PCIE_SCC_B_TO_COMP_B_0_DP")
	)
	(segment
		(start 210.4898 -78.153768)
		(end 210.188302 -78.153768)
		(width 0.1651)
		(layer "B.Cu")
		(net "PCIE_SCC_B_TO_COMP_B_0_DP")
	)
	(segment
		(start 210.000088 -77.965554)
		(end 210.000088 -77.600048)
		(width 0.1651)
		(layer "B.Cu")
		(net "PCIE_SCC_B_TO_COMP_B_0_DP")
	)
	(segment
		(start 274.168362 -143.64843)
		(end 270.718026 -141.40434)
		(width 0.1651)
		(layer "B.Cu")
		(net "PCIE_SCC_B_TO_COMP_B_0_DP")
	)
	(segment
		(start 270.718026 -141.40434)
		(end 267.267944 -139.16025)
		(width 0.1651)
		(layer "B.Cu")
		(net "PCIE_SCC_B_TO_COMP_B_0_DP")
	)
	(segment
		(start 212.936836 -91.286838)
		(end 212.023452 -89.88044)
		(width 0.1651)
		(layer "B.Cu")
		(net "PCIE_SCC_B_TO_COMP_B_0_DP")
	)
	(segment
		(start 267.267944 -139.16025)
		(end 227.518976 -113.307368)
		(width 0.1651)
		(layer "B.Cu")
		(net "PCIE_SCC_B_TO_COMP_B_0_DP")
	)
	(segment
		(start 212.023452 -89.88044)
		(end 211.04606 -85.281516)
		(width 0.1651)
		(layer "B.Cu")
		(net "PCIE_SCC_B_TO_COMP_B_0_DP")
	)
	(arc
		(start 210.188302 -78.153768)
		(mid 210.055215 -78.098641)
		(end 210.000088 -77.965554)
		(width 0.1651)
		(layer "B.Cu")
		(net "PCIE_SCC_B_TO_COMP_B_0_DP")
	)
	(arc
		(start 280.274522 -144.694402)
		(mid 280.13892 -144.638234)
		(end 280.082752 -144.502632)
		(width 0.1651)
		(layer "B.Cu")
		(net "PCIE_SCC_B_TO_COMP_B_0_DP")
	)
	(arc
		(start 280.082752 -144.502632)
		(mid 279.832562 -143.89862)
		(end 279.22855 -143.64843)
		(width 0.1651)
		(layer "B.Cu")
		(net "PCIE_SCC_B_TO_COMP_B_0_DP")
	)
	(arc
		(start 211.04606 -78.719426)
		(mid 210.8865 -78.319973)
		(end 210.4898 -78.153768)
		(width 0.1651)
		(layer "B.Cu")
		(net "PCIE_SCC_B_TO_COMP_B_0_DP")
	)
	(segment
		(start 265.683492 -138.478514)
		(end 236.767116 -119.671084)
		(width 0.1651)
		(layer "B.Cu")
		(net "PCIE_SCC_B_TO_COMP_B_0_DN")
	)
	(segment
		(start 236.16031 -119.276368)
		(end 235.74502 -119.006366)
		(width 0.1651)
		(layer "B.Cu")
		(net "PCIE_SCC_B_TO_COMP_B_0_DN")
	)
	(segment
		(start 234.149646 -118.105174)
		(end 234.116372 -117.946932)
		(width 0.1651)
		(layer "B.Cu")
		(net "PCIE_SCC_B_TO_COMP_B_0_DN")
	)
	(segment
		(start 279.236678 -144.694402)
		(end 279.598882 -144.694402)
		(width 0.1651)
		(layer "B.Cu")
		(net "PCIE_SCC_B_TO_COMP_B_0_DN")
	)
	(segment
		(start 234.564936 -118.375176)
		(end 234.149646 -118.105174)
		(width 0.1651)
		(layer "B.Cu")
		(net "PCIE_SCC_B_TO_COMP_B_0_DN")
	)
	(segment
		(start 236.767116 -119.671084)
		(end 236.609128 -119.704612)
		(width 0.1651)
		(layer "B.Cu")
		(net "PCIE_SCC_B_TO_COMP_B_0_DN")
	)
	(segment
		(start 211.748878 -89.994232)
		(end 210.75396 -85.31225)
		(width 0.1651)
		(layer "B.Cu")
		(net "PCIE_SCC_B_TO_COMP_B_0_DN")
	)
	(segment
		(start 267.312394 -139.537948)
		(end 267.154406 -139.571476)
		(width 0.1651)
		(layer "B.Cu")
		(net "PCIE_SCC_B_TO_COMP_B_0_DN")
	)
	(segment
		(start 279.22855 -143.94053)
		(end 274.081494 -143.94053)
		(width 0.1651)
		(layer "B.Cu")
		(net "PCIE_SCC_B_TO_COMP_B_0_DN")
	)
	(segment
		(start 236.193838 -119.43461)
		(end 236.16031 -119.276368)
		(width 0.1651)
		(layer "B.Cu")
		(net "PCIE_SCC_B_TO_COMP_B_0_DN")
	)
	(segment
		(start 266.739116 -139.301474)
		(end 266.705588 -139.143232)
		(width 0.1651)
		(layer "B.Cu")
		(net "PCIE_SCC_B_TO_COMP_B_0_DN")
	)
	(segment
		(start 266.705588 -139.143232)
		(end 266.290298 -138.87323)
		(width 0.1651)
		(layer "B.Cu")
		(net "PCIE_SCC_B_TO_COMP_B_0_DN")
	)
	(segment
		(start 234.116372 -117.946932)
		(end 227.308156 -113.51895)
		(width 0.1651)
		(layer "B.Cu")
		(net "PCIE_SCC_B_TO_COMP_B_0_DN")
	)
	(segment
		(start 235.171742 -118.769892)
		(end 235.138214 -118.61165)
		(width 0.1651)
		(layer "B.Cu")
		(net "PCIE_SCC_B_TO_COMP_B_0_DN")
	)
	(segment
		(start 266.290298 -138.87323)
		(end 266.13231 -138.906758)
		(width 0.1651)
		(layer "B.Cu")
		(net "PCIE_SCC_B_TO_COMP_B_0_DN")
	)
	(segment
		(start 236.609128 -119.704612)
		(end 236.193838 -119.43461)
		(width 0.1651)
		(layer "B.Cu")
		(net "PCIE_SCC_B_TO_COMP_B_0_DN")
	)
	(segment
		(start 210.000088 -78.634082)
		(end 210.000088 -78.999842)
		(width 0.1651)
		(layer "B.Cu")
		(net "PCIE_SCC_B_TO_COMP_B_0_DN")
	)
	(segment
		(start 266.13231 -138.906758)
		(end 265.71702 -138.636756)
		(width 0.1651)
		(layer "B.Cu")
		(net "PCIE_SCC_B_TO_COMP_B_0_DN")
	)
	(segment
		(start 267.154406 -139.571476)
		(end 266.739116 -139.301474)
		(width 0.1651)
		(layer "B.Cu")
		(net "PCIE_SCC_B_TO_COMP_B_0_DN")
	)
	(segment
		(start 274.081494 -143.94053)
		(end 267.312394 -139.537948)
		(width 0.1651)
		(layer "B.Cu")
		(net "PCIE_SCC_B_TO_COMP_B_0_DN")
	)
	(segment
		(start 210.4898 -78.445868)
		(end 210.188302 -78.445868)
		(width 0.1651)
		(layer "B.Cu")
		(net "PCIE_SCC_B_TO_COMP_B_0_DN")
	)
	(segment
		(start 210.75396 -85.31225)
		(end 210.75396 -78.7146)
		(width 0.1651)
		(layer "B.Cu")
		(net "PCIE_SCC_B_TO_COMP_B_0_DN")
	)
	(segment
		(start 234.723178 -118.341648)
		(end 234.564936 -118.375176)
		(width 0.1651)
		(layer "B.Cu")
		(net "PCIE_SCC_B_TO_COMP_B_0_DN")
	)
	(segment
		(start 212.694012 -91.449398)
		(end 211.748878 -89.994232)
		(width 0.1651)
		(layer "B.Cu")
		(net "PCIE_SCC_B_TO_COMP_B_0_DN")
	)
	(segment
		(start 227.30841 -113.51895)
		(end 212.694012 -91.449398)
		(width 0.1651)
		(layer "B.Cu")
		(net "PCIE_SCC_B_TO_COMP_B_0_DN")
	)
	(segment
		(start 235.587032 -119.039894)
		(end 235.171742 -118.769892)
		(width 0.1651)
		(layer "B.Cu")
		(net "PCIE_SCC_B_TO_COMP_B_0_DN")
	)
	(segment
		(start 235.138214 -118.61165)
		(end 234.723178 -118.341648)
		(width 0.1651)
		(layer "B.Cu")
		(net "PCIE_SCC_B_TO_COMP_B_0_DN")
	)
	(segment
		(start 227.308156 -113.51895)
		(end 227.30841 -113.51895)
		(width 0.1651)
		(layer "B.Cu")
		(net "PCIE_SCC_B_TO_COMP_B_0_DN")
	)
	(segment
		(start 265.71702 -138.636756)
		(end 265.683492 -138.478514)
		(width 0.1651)
		(layer "B.Cu")
		(net "PCIE_SCC_B_TO_COMP_B_0_DN")
	)
	(segment
		(start 235.74502 -119.006366)
		(end 235.587032 -119.039894)
		(width 0.1651)
		(layer "B.Cu")
		(net "PCIE_SCC_B_TO_COMP_B_0_DN")
	)
	(arc
		(start 210.188302 -78.445868)
		(mid 210.055215 -78.500995)
		(end 210.000088 -78.634082)
		(width 0.1651)
		(layer "B.Cu")
		(net "PCIE_SCC_B_TO_COMP_B_0_DN")
	)
	(arc
		(start 279.598882 -144.694402)
		(mid 279.734484 -144.638234)
		(end 279.790652 -144.502632)
		(width 0.1651)
		(layer "B.Cu")
		(net "PCIE_SCC_B_TO_COMP_B_0_DN")
	)
	(arc
		(start 210.75396 -78.7146)
		(mid 210.678227 -78.524834)
		(end 210.4898 -78.445868)
		(width 0.1651)
		(layer "B.Cu")
		(net "PCIE_SCC_B_TO_COMP_B_0_DN")
	)
	(arc
		(start 279.790652 -144.502632)
		(mid 279.626016 -144.105166)
		(end 279.22855 -143.94053)
		(width 0.1651)
		(layer "B.Cu")
		(net "PCIE_SCC_B_TO_COMP_B_0_DN")
	)
	(via
		(at 211.433918 -116.590318)
		(size 0.6604)
		(drill 0.3048)
		(layers "F.Cu" "B.Cu")
		(net "PCIE_COMP_B_TO_SCC_B_RST_0")
	)
	(via
		(at 289.2806 -148.5646)
		(size 0.5588)
		(drill 0.3048)
		(layers "F.Cu" "B.Cu")
		(net "PCIE_COMP_B_TO_SCC_B_RST_0")
	)
	(segment
		(start 289.487864 -148.357336)
		(end 289.2806 -148.5646)
		(width 0.14605)
		(layer "In2.Cu")
		(net "PCIE_COMP_B_TO_SCC_B_RST_0")
	)
	(segment
		(start 214.762334 -80.047846)
		(end 214.920576 -80.206088)
		(width 0.14605)
		(layer "In2.Cu")
		(net "PCIE_COMP_B_TO_SCC_B_RST_0")
	)
	(segment
		(start 214.920576 -81.370424)
		(end 212.070696 -84.220304)
		(width 0.14605)
		(layer "In2.Cu")
		(net "PCIE_COMP_B_TO_SCC_B_RST_0")
	)
	(segment
		(start 284.80512 -134.8486)
		(end 288.9377 -134.8486)
		(width 0.14605)
		(layer "In2.Cu")
		(net "PCIE_COMP_B_TO_SCC_B_RST_0")
	)
	(segment
		(start 289.487864 -145.26514)
		(end 289.487864 -148.357336)
		(width 0.14605)
		(layer "In2.Cu")
		(net "PCIE_COMP_B_TO_SCC_B_RST_0")
	)
	(segment
		(start 284.236668 -133.894322)
		(end 284.236668 -134.280148)
		(width 0.14605)
		(layer "In2.Cu")
		(net "PCIE_COMP_B_TO_SCC_B_RST_0")
	)
	(segment
		(start 289.518852 -145.234152)
		(end 289.487864 -145.26514)
		(width 0.14605)
		(layer "In2.Cu")
		(net "PCIE_COMP_B_TO_SCC_B_RST_0")
	)
	(segment
		(start 215.400128 -74.200004)
		(end 214.762334 -74.837798)
		(width 0.14605)
		(layer "In2.Cu")
		(net "PCIE_COMP_B_TO_SCC_B_RST_0")
	)
	(segment
		(start 288.9377 -134.8486)
		(end 289.518852 -135.429752)
		(width 0.14605)
		(layer "In2.Cu")
		(net "PCIE_COMP_B_TO_SCC_B_RST_0")
	)
	(segment
		(start 214.762334 -74.837798)
		(end 214.762334 -80.047846)
		(width 0.14605)
		(layer "In2.Cu")
		(net "PCIE_COMP_B_TO_SCC_B_RST_0")
	)
	(segment
		(start 214.920576 -80.206088)
		(end 214.920576 -81.370424)
		(width 0.14605)
		(layer "In2.Cu")
		(net "PCIE_COMP_B_TO_SCC_B_RST_0")
	)
	(segment
		(start 284.236668 -134.280148)
		(end 284.80512 -134.8486)
		(width 0.14605)
		(layer "In2.Cu")
		(net "PCIE_COMP_B_TO_SCC_B_RST_0")
	)
	(segment
		(start 211.433918 -112.543082)
		(end 211.433918 -116.590318)
		(width 0.14605)
		(layer "In2.Cu")
		(net "PCIE_COMP_B_TO_SCC_B_RST_0")
	)
	(segment
		(start 289.518852 -135.429752)
		(end 289.518852 -145.234152)
		(width 0.14605)
		(layer "In2.Cu")
		(net "PCIE_COMP_B_TO_SCC_B_RST_0")
	)
	(segment
		(start 212.070696 -111.906304)
		(end 211.433918 -112.543082)
		(width 0.14605)
		(layer "In2.Cu")
		(net "PCIE_COMP_B_TO_SCC_B_RST_0")
	)
	(segment
		(start 212.070696 -84.220304)
		(end 212.070696 -111.906304)
		(width 0.14605)
		(layer "In2.Cu")
		(net "PCIE_COMP_B_TO_SCC_B_RST_0")
	)
	(segment
		(start 218.16822 -117.20322)
		(end 236.0168 -135.0518)
		(width 0.14605)
		(layer "In5.Cu")
		(net "PCIE_COMP_B_TO_SCC_B_RST_0")
	)
	(segment
		(start 211.433918 -116.590318)
		(end 212.04682 -117.20322)
		(width 0.14605)
		(layer "In5.Cu")
		(net "PCIE_COMP_B_TO_SCC_B_RST_0")
	)
	(segment
		(start 253.426722 -137.551922)
		(end 264.4394 -148.5646)
		(width 0.14605)
		(layer "In5.Cu")
		(net "PCIE_COMP_B_TO_SCC_B_RST_0")
	)
	(segment
		(start 236.0168 -135.0518)
		(end 247.8532 -135.0518)
		(width 0.14605)
		(layer "In5.Cu")
		(net "PCIE_COMP_B_TO_SCC_B_RST_0")
	)
	(segment
		(start 250.353322 -137.551922)
		(end 253.426722 -137.551922)
		(width 0.14605)
		(layer "In5.Cu")
		(net "PCIE_COMP_B_TO_SCC_B_RST_0")
	)
	(segment
		(start 264.4394 -148.5646)
		(end 289.2806 -148.5646)
		(width 0.14605)
		(layer "In5.Cu")
		(net "PCIE_COMP_B_TO_SCC_B_RST_0")
	)
	(segment
		(start 247.8532 -135.0518)
		(end 250.353322 -137.551922)
		(width 0.14605)
		(layer "In5.Cu")
		(net "PCIE_COMP_B_TO_SCC_B_RST_0")
	)
	(segment
		(start 212.04682 -117.20322)
		(end 218.16822 -117.20322)
		(width 0.14605)
		(layer "In5.Cu")
		(net "PCIE_COMP_B_TO_SCC_B_RST_0")
	)
	(segment
		(start 213.959186 -96.482154)
		(end 210.260184 -90.785696)
		(width 0.1651)
		(layer "B.Cu")
		(net "PCIE_COMP_B_TO_SCC_B_CLK_0_DP")
	)
	(segment
		(start 210.000088 -74.365612)
		(end 210.000088 -73.999852)
		(width 0.1651)
		(layer "B.Cu")
		(net "PCIE_COMP_B_TO_SCC_B_CLK_0_DP")
	)
	(segment
		(start 209.583274 -74.553826)
		(end 209.811874 -74.553826)
		(width 0.1651)
		(layer "B.Cu")
		(net "PCIE_COMP_B_TO_SCC_B_CLK_0_DP")
	)
	(segment
		(start 230.86822 -118.032022)
		(end 230.886254 -118.032022)
		(width 0.1651)
		(layer "B.Cu")
		(net "PCIE_COMP_B_TO_SCC_B_CLK_0_DP")
	)
	(segment
		(start 225.807016 -114.72799)
		(end 213.958932 -96.482154)
		(width 0.1651)
		(layer "B.Cu")
		(net "PCIE_COMP_B_TO_SCC_B_CLK_0_DP")
	)
	(segment
		(start 213.958932 -96.482154)
		(end 213.959186 -96.482154)
		(width 0.1651)
		(layer "B.Cu")
		(net "PCIE_COMP_B_TO_SCC_B_CLK_0_DP")
	)
	(segment
		(start 273.536156 -145.740374)
		(end 230.86822 -118.032022)
		(width 0.1651)
		(layer "B.Cu")
		(net "PCIE_COMP_B_TO_SCC_B_CLK_0_DP")
	)
	(segment
		(start 283.682694 -144.886172)
		(end 283.682694 -145.086324)
		(width 0.1651)
		(layer "B.Cu")
		(net "PCIE_COMP_B_TO_SCC_B_CLK_0_DP")
	)
	(segment
		(start 208.954116 -84.641182)
		(end 208.954116 -75.182984)
		(width 0.1651)
		(layer "B.Cu")
		(net "PCIE_COMP_B_TO_SCC_B_CLK_0_DP")
	)
	(segment
		(start 210.260184 -90.785696)
		(end 208.954116 -84.641182)
		(width 0.1651)
		(layer "B.Cu")
		(net "PCIE_COMP_B_TO_SCC_B_CLK_0_DP")
	)
	(segment
		(start 283.028644 -145.740374)
		(end 273.536156 -145.740374)
		(width 0.1651)
		(layer "B.Cu")
		(net "PCIE_COMP_B_TO_SCC_B_CLK_0_DP")
	)
	(segment
		(start 230.886254 -118.032022)
		(end 225.807016 -114.72799)
		(width 0.1651)
		(layer "B.Cu")
		(net "PCIE_COMP_B_TO_SCC_B_CLK_0_DP")
	)
	(segment
		(start 284.236668 -144.694402)
		(end 283.874464 -144.694402)
		(width 0.1651)
		(layer "B.Cu")
		(net "PCIE_COMP_B_TO_SCC_B_CLK_0_DP")
	)
	(arc
		(start 283.874464 -144.694402)
		(mid 283.738862 -144.75057)
		(end 283.682694 -144.886172)
		(width 0.1651)
		(layer "B.Cu")
		(net "PCIE_COMP_B_TO_SCC_B_CLK_0_DP")
	)
	(arc
		(start 209.811874 -74.553826)
		(mid 209.944961 -74.498699)
		(end 210.000088 -74.365612)
		(width 0.1651)
		(layer "B.Cu")
		(net "PCIE_COMP_B_TO_SCC_B_CLK_0_DP")
	)
	(arc
		(start 208.954116 -75.182984)
		(mid 209.138392 -74.738102)
		(end 209.583274 -74.553826)
		(width 0.1651)
		(layer "B.Cu")
		(net "PCIE_COMP_B_TO_SCC_B_CLK_0_DP")
	)
	(arc
		(start 283.682694 -145.086324)
		(mid 283.491127 -145.548807)
		(end 283.028644 -145.740374)
		(width 0.1651)
		(layer "B.Cu")
		(net "PCIE_COMP_B_TO_SCC_B_CLK_0_DP")
	)
	(segment
		(start 247.093994 -128.220216)
		(end 247.057418 -128.048004)
		(width 0.1651)
		(layer "B.Cu")
		(net "PCIE_COMP_B_TO_SCC_B_CLK_0_DN")
	)
	(segment
		(start 247.509284 -128.489964)
		(end 247.093994 -128.220216)
		(width 0.1651)
		(layer "B.Cu")
		(net "PCIE_COMP_B_TO_SCC_B_CLK_0_DN")
	)
	(segment
		(start 209.583274 -74.845926)
		(end 209.811874 -74.845926)
		(width 0.1651)
		(layer "B.Cu")
		(net "PCIE_COMP_B_TO_SCC_B_CLK_0_DN")
	)
	(segment
		(start 271.087342 -143.801592)
		(end 271.050766 -143.62938)
		(width 0.1651)
		(layer "B.Cu")
		(net "PCIE_COMP_B_TO_SCC_B_CLK_0_DN")
	)
	(segment
		(start 231.615234 -118.020084)
		(end 231.19969 -117.750336)
		(width 0.1651)
		(layer "B.Cu")
		(net "PCIE_COMP_B_TO_SCC_B_CLK_0_DN")
	)
	(segment
		(start 250.212606 -130.245612)
		(end 250.17603 -130.0734)
		(width 0.1651)
		(layer "B.Cu")
		(net "PCIE_COMP_B_TO_SCC_B_CLK_0_DN")
	)
	(segment
		(start 246.469662 -127.814832)
		(end 234.770422 -120.217438)
		(width 0.1651)
		(layer "B.Cu")
		(net "PCIE_COMP_B_TO_SCC_B_CLK_0_DN")
	)
	(segment
		(start 232.654602 -118.695216)
		(end 232.239312 -118.425468)
		(width 0.1651)
		(layer "B.Cu")
		(net "PCIE_COMP_B_TO_SCC_B_CLK_0_DN")
	)
	(segment
		(start 213.961218 -95.733362)
		(end 213.798912 -95.698818)
		(width 0.1651)
		(layer "B.Cu")
		(net "PCIE_COMP_B_TO_SCC_B_CLK_0_DN")
	)
	(segment
		(start 209.246216 -84.610448)
		(end 209.246216 -75.182984)
		(width 0.1651)
		(layer "B.Cu")
		(net "PCIE_COMP_B_TO_SCC_B_CLK_0_DN")
	)
	(segment
		(start 233.278934 -119.100346)
		(end 233.106722 -119.137176)
		(width 0.1651)
		(layer "B.Cu")
		(net "PCIE_COMP_B_TO_SCC_B_CLK_0_DN")
	)
	(segment
		(start 246.641874 -127.778256)
		(end 246.469662 -127.814832)
		(width 0.1651)
		(layer "B.Cu")
		(net "PCIE_COMP_B_TO_SCC_B_CLK_0_DN")
	)
	(segment
		(start 214.204296 -96.323404)
		(end 214.204296 -96.322896)
		(width 0.1651)
		(layer "B.Cu")
		(net "PCIE_COMP_B_TO_SCC_B_CLK_0_DN")
	)
	(segment
		(start 272.714466 -144.709896)
		(end 272.542254 -144.746472)
		(width 0.1651)
		(layer "B.Cu")
		(net "PCIE_COMP_B_TO_SCC_B_CLK_0_DN")
	)
	(segment
		(start 283.028644 -145.448274)
		(end 273.671792 -145.448274)
		(width 0.1651)
		(layer "B.Cu")
		(net "PCIE_COMP_B_TO_SCC_B_CLK_0_DN")
	)
	(segment
		(start 247.681496 -128.453388)
		(end 247.509284 -128.489964)
		(width 0.1651)
		(layer "B.Cu")
		(net "PCIE_COMP_B_TO_SCC_B_CLK_0_DN")
	)
	(segment
		(start 248.096786 -128.723136)
		(end 247.681496 -128.453388)
		(width 0.1651)
		(layer "B.Cu")
		(net "PCIE_COMP_B_TO_SCC_B_CLK_0_DN")
	)
	(segment
		(start 271.050766 -143.62938)
		(end 270.635476 -143.359632)
		(width 0.1651)
		(layer "B.Cu")
		(net "PCIE_COMP_B_TO_SCC_B_CLK_0_DN")
	)
	(segment
		(start 232.0671 -118.462044)
		(end 231.65181 -118.192296)
		(width 0.1651)
		(layer "B.Cu")
		(net "PCIE_COMP_B_TO_SCC_B_CLK_0_DN")
	)
	(segment
		(start 226.018344 -114.516662)
		(end 214.204296 -96.323404)
		(width 0.1651)
		(layer "B.Cu")
		(net "PCIE_COMP_B_TO_SCC_B_CLK_0_DN")
	)
	(segment
		(start 282.83662 -144.694402)
		(end 283.198824 -144.694402)
		(width 0.1651)
		(layer "B.Cu")
		(net "PCIE_COMP_B_TO_SCC_B_CLK_0_DN")
	)
	(segment
		(start 273.13001 -144.979644)
		(end 272.714466 -144.709896)
		(width 0.1651)
		(layer "B.Cu")
		(net "PCIE_COMP_B_TO_SCC_B_CLK_0_DN")
	)
	(segment
		(start 210.534758 -90.671904)
		(end 209.246216 -84.610448)
		(width 0.1651)
		(layer "B.Cu")
		(net "PCIE_COMP_B_TO_SCC_B_CLK_0_DN")
	)
	(segment
		(start 249.588528 -129.840228)
		(end 249.172984 -129.57048)
		(width 0.1651)
		(layer "B.Cu")
		(net "PCIE_COMP_B_TO_SCC_B_CLK_0_DN")
	)
	(segment
		(start 234.318302 -119.775478)
		(end 234.146344 -119.812054)
		(width 0.1651)
		(layer "B.Cu")
		(net "PCIE_COMP_B_TO_SCC_B_CLK_0_DN")
	)
	(segment
		(start 271.502886 -144.07134)
		(end 271.087342 -143.801592)
		(width 0.1651)
		(layer "B.Cu")
		(net "PCIE_COMP_B_TO_SCC_B_CLK_0_DN")
	)
	(segment
		(start 232.239312 -118.425468)
		(end 232.0671 -118.462044)
		(width 0.1651)
		(layer "B.Cu")
		(net "PCIE_COMP_B_TO_SCC_B_CLK_0_DN")
	)
	(segment
		(start 234.733846 -120.045226)
		(end 234.318302 -119.775478)
		(width 0.1651)
		(layer "B.Cu")
		(net "PCIE_COMP_B_TO_SCC_B_CLK_0_DN")
	)
	(segment
		(start 231.04094 -117.783864)
		(end 226.018344 -114.516662)
		(width 0.1651)
		(layer "B.Cu")
		(net "PCIE_COMP_B_TO_SCC_B_CLK_0_DN")
	)
	(segment
		(start 273.581876 -145.421604)
		(end 273.166586 -145.151856)
		(width 0.1651)
		(layer "B.Cu")
		(net "PCIE_COMP_B_TO_SCC_B_CLK_0_DN")
	)
	(segment
		(start 233.694224 -119.370348)
		(end 233.278934 -119.100346)
		(width 0.1651)
		(layer "B.Cu")
		(net "PCIE_COMP_B_TO_SCC_B_CLK_0_DN")
	)
	(segment
		(start 213.798912 -95.698818)
		(end 213.529164 -95.283274)
		(width 0.1651)
		(layer "B.Cu")
		(net "PCIE_COMP_B_TO_SCC_B_CLK_0_DN")
	)
	(segment
		(start 248.133362 -128.895348)
		(end 248.096786 -128.723136)
		(width 0.1651)
		(layer "B.Cu")
		(net "PCIE_COMP_B_TO_SCC_B_CLK_0_DN")
	)
	(segment
		(start 210.000088 -75.03414)
		(end 210.000088 -75.3999)
		(width 0.1651)
		(layer "B.Cu")
		(net "PCIE_COMP_B_TO_SCC_B_CLK_0_DN")
	)
	(segment
		(start 250.17603 -130.0734)
		(end 249.760486 -129.803652)
		(width 0.1651)
		(layer "B.Cu")
		(net "PCIE_COMP_B_TO_SCC_B_CLK_0_DN")
	)
	(segment
		(start 247.057418 -128.048004)
		(end 246.641874 -127.778256)
		(width 0.1651)
		(layer "B.Cu")
		(net "PCIE_COMP_B_TO_SCC_B_CLK_0_DN")
	)
	(segment
		(start 232.691432 -118.867428)
		(end 232.654602 -118.695216)
		(width 0.1651)
		(layer "B.Cu")
		(net "PCIE_COMP_B_TO_SCC_B_CLK_0_DN")
	)
	(segment
		(start 249.136408 -129.398268)
		(end 248.721118 -129.12852)
		(width 0.1651)
		(layer "B.Cu")
		(net "PCIE_COMP_B_TO_SCC_B_CLK_0_DN")
	)
	(segment
		(start 270.011144 -142.954502)
		(end 269.595854 -142.684754)
		(width 0.1651)
		(layer "B.Cu")
		(net "PCIE_COMP_B_TO_SCC_B_CLK_0_DN")
	)
	(segment
		(start 233.106722 -119.137176)
		(end 232.691432 -118.867428)
		(width 0.1651)
		(layer "B.Cu")
		(net "PCIE_COMP_B_TO_SCC_B_CLK_0_DN")
	)
	(segment
		(start 234.770422 -120.217438)
		(end 234.733846 -120.045226)
		(width 0.1651)
		(layer "B.Cu")
		(net "PCIE_COMP_B_TO_SCC_B_CLK_0_DN")
	)
	(segment
		(start 213.12378 -94.659196)
		(end 210.534758 -90.671904)
		(width 0.1651)
		(layer "B.Cu")
		(net "PCIE_COMP_B_TO_SCC_B_CLK_0_DN")
	)
	(segment
		(start 249.760486 -129.803652)
		(end 249.588528 -129.840228)
		(width 0.1651)
		(layer "B.Cu")
		(net "PCIE_COMP_B_TO_SCC_B_CLK_0_DN")
	)
	(segment
		(start 249.172984 -129.57048)
		(end 249.136408 -129.398268)
		(width 0.1651)
		(layer "B.Cu")
		(net "PCIE_COMP_B_TO_SCC_B_CLK_0_DN")
	)
	(segment
		(start 234.146344 -119.812054)
		(end 233.7308 -119.542306)
		(width 0.1651)
		(layer "B.Cu")
		(net "PCIE_COMP_B_TO_SCC_B_CLK_0_DN")
	)
	(segment
		(start 270.04772 -143.12646)
		(end 270.011144 -142.954502)
		(width 0.1651)
		(layer "B.Cu")
		(net "PCIE_COMP_B_TO_SCC_B_CLK_0_DN")
	)
	(segment
		(start 269.595854 -142.684754)
		(end 269.423642 -142.72133)
		(width 0.1651)
		(layer "B.Cu")
		(net "PCIE_COMP_B_TO_SCC_B_CLK_0_DN")
	)
	(segment
		(start 272.542254 -144.746472)
		(end 272.126964 -144.476724)
		(width 0.1651)
		(layer "B.Cu")
		(net "PCIE_COMP_B_TO_SCC_B_CLK_0_DN")
	)
	(segment
		(start 272.126964 -144.476724)
		(end 272.090388 -144.304512)
		(width 0.1651)
		(layer "B.Cu")
		(net "PCIE_COMP_B_TO_SCC_B_CLK_0_DN")
	)
	(segment
		(start 273.166586 -145.151856)
		(end 273.13001 -144.979644)
		(width 0.1651)
		(layer "B.Cu")
		(net "PCIE_COMP_B_TO_SCC_B_CLK_0_DN")
	)
	(segment
		(start 213.529164 -95.283274)
		(end 213.5632 -95.123762)
		(width 0.1651)
		(layer "B.Cu")
		(net "PCIE_COMP_B_TO_SCC_B_CLK_0_DN")
	)
	(segment
		(start 231.19969 -117.750336)
		(end 231.04094 -117.783864)
		(width 0.1651)
		(layer "B.Cu")
		(net "PCIE_COMP_B_TO_SCC_B_CLK_0_DN")
	)
	(segment
		(start 283.390594 -144.886172)
		(end 283.390594 -145.086324)
		(width 0.1651)
		(layer "B.Cu")
		(net "PCIE_COMP_B_TO_SCC_B_CLK_0_DN")
	)
	(segment
		(start 231.65181 -118.192296)
		(end 231.615234 -118.020084)
		(width 0.1651)
		(layer "B.Cu")
		(net "PCIE_COMP_B_TO_SCC_B_CLK_0_DN")
	)
	(segment
		(start 214.204296 -96.322896)
		(end 214.23884 -96.16059)
		(width 0.1651)
		(layer "B.Cu")
		(net "PCIE_COMP_B_TO_SCC_B_CLK_0_DN")
	)
	(segment
		(start 248.548906 -129.165096)
		(end 248.133362 -128.895348)
		(width 0.1651)
		(layer "B.Cu")
		(net "PCIE_COMP_B_TO_SCC_B_CLK_0_DN")
	)
	(segment
		(start 248.721118 -129.12852)
		(end 248.548906 -129.165096)
		(width 0.1651)
		(layer "B.Cu")
		(net "PCIE_COMP_B_TO_SCC_B_CLK_0_DN")
	)
	(segment
		(start 213.5632 -95.123762)
		(end 213.283546 -94.693232)
		(width 0.1651)
		(layer "B.Cu")
		(net "PCIE_COMP_B_TO_SCC_B_CLK_0_DN")
	)
	(segment
		(start 270.463264 -143.396208)
		(end 270.04772 -143.12646)
		(width 0.1651)
		(layer "B.Cu")
		(net "PCIE_COMP_B_TO_SCC_B_CLK_0_DN")
	)
	(segment
		(start 213.283546 -94.693232)
		(end 213.12378 -94.659196)
		(width 0.1651)
		(layer "B.Cu")
		(net "PCIE_COMP_B_TO_SCC_B_CLK_0_DN")
	)
	(segment
		(start 214.23884 -96.16059)
		(end 213.961218 -95.733362)
		(width 0.1651)
		(layer "B.Cu")
		(net "PCIE_COMP_B_TO_SCC_B_CLK_0_DN")
	)
	(segment
		(start 272.090388 -144.304512)
		(end 271.674844 -144.034764)
		(width 0.1651)
		(layer "B.Cu")
		(net "PCIE_COMP_B_TO_SCC_B_CLK_0_DN")
	)
	(segment
		(start 233.7308 -119.542306)
		(end 233.694224 -119.370348)
		(width 0.1651)
		(layer "B.Cu")
		(net "PCIE_COMP_B_TO_SCC_B_CLK_0_DN")
	)
	(segment
		(start 270.635476 -143.359632)
		(end 270.463264 -143.396208)
		(width 0.1651)
		(layer "B.Cu")
		(net "PCIE_COMP_B_TO_SCC_B_CLK_0_DN")
	)
	(segment
		(start 269.423642 -142.72133)
		(end 250.212606 -130.245612)
		(width 0.1651)
		(layer "B.Cu")
		(net "PCIE_COMP_B_TO_SCC_B_CLK_0_DN")
	)
	(segment
		(start 271.674844 -144.034764)
		(end 271.502886 -144.07134)
		(width 0.1651)
		(layer "B.Cu")
		(net "PCIE_COMP_B_TO_SCC_B_CLK_0_DN")
	)
	(arc
		(start 273.671792 -145.448274)
		(mid 273.624899 -145.441464)
		(end 273.581876 -145.421604)
		(width 0.1651)
		(layer "B.Cu")
		(net "PCIE_COMP_B_TO_SCC_B_CLK_0_DN")
	)
	(arc
		(start 283.390594 -145.086324)
		(mid 283.284581 -145.342261)
		(end 283.028644 -145.448274)
		(width 0.1651)
		(layer "B.Cu")
		(net "PCIE_COMP_B_TO_SCC_B_CLK_0_DN")
	)
	(arc
		(start 209.246216 -75.182984)
		(mid 209.344938 -74.944648)
		(end 209.583274 -74.845926)
		(width 0.1651)
		(layer "B.Cu")
		(net "PCIE_COMP_B_TO_SCC_B_CLK_0_DN")
	)
	(arc
		(start 209.811874 -74.845926)
		(mid 209.944961 -74.901053)
		(end 210.000088 -75.03414)
		(width 0.1651)
		(layer "B.Cu")
		(net "PCIE_COMP_B_TO_SCC_B_CLK_0_DN")
	)
	(arc
		(start 283.198824 -144.694402)
		(mid 283.334426 -144.75057)
		(end 283.390594 -144.886172)
		(width 0.1651)
		(layer "B.Cu")
		(net "PCIE_COMP_B_TO_SCC_B_CLK_0_DN")
	)
	(segment
		(start 286.282638 -130.819398)
		(end 285.581852 -130.119374)
		(width 0.1397)
		(layer "In5.Cu")
		(net "PCIE_COMP_B_TO_SCC_B_7_DP")
	)
	(segment
		(start 222.972376 -66.153792)
		(end 222.784924 -66.153792)
		(width 0.1397)
		(layer "In5.Cu")
		(net "PCIE_COMP_B_TO_SCC_B_7_DP")
	)
	(segment
		(start 231.137206 -94.73819)
		(end 225.68281 -86.33714)
		(width 0.1397)
		(layer "In5.Cu")
		(net "PCIE_COMP_B_TO_SCC_B_7_DP")
	)
	(segment
		(start 225.68281 -86.33714)
		(end 223.645984 -76.69784)
		(width 0.1397)
		(layer "In5.Cu")
		(net "PCIE_COMP_B_TO_SCC_B_7_DP")
	)
	(segment
		(start 286.836612 -132.094478)
		(end 286.50184 -132.094478)
		(width 0.1397)
		(layer "In5.Cu")
		(net "PCIE_COMP_B_TO_SCC_B_7_DP")
	)
	(segment
		(start 222.600012 -65.96888)
		(end 222.600012 -65.600072)
		(width 0.1397)
		(layer "In5.Cu")
		(net "PCIE_COMP_B_TO_SCC_B_7_DP")
	)
	(segment
		(start 286.282638 -131.875276)
		(end 286.282638 -130.819398)
		(width 0.1397)
		(layer "In5.Cu")
		(net "PCIE_COMP_B_TO_SCC_B_7_DP")
	)
	(segment
		(start 223.645984 -76.69784)
		(end 223.645984 -66.8274)
		(width 0.1397)
		(layer "In5.Cu")
		(net "PCIE_COMP_B_TO_SCC_B_7_DP")
	)
	(segment
		(start 285.581852 -130.119374)
		(end 231.137206 -94.73819)
		(width 0.1397)
		(layer "In5.Cu")
		(net "PCIE_COMP_B_TO_SCC_B_7_DP")
	)
	(arc
		(start 286.50184 -132.094478)
		(mid 286.346841 -132.030275)
		(end 286.282638 -131.875276)
		(width 0.1397)
		(layer "In5.Cu")
		(net "PCIE_COMP_B_TO_SCC_B_7_DP")
	)
	(arc
		(start 223.645984 -66.8274)
		(mid 223.448689 -66.351087)
		(end 222.972376 -66.153792)
		(width 0.1397)
		(layer "In5.Cu")
		(net "PCIE_COMP_B_TO_SCC_B_7_DP")
	)
	(arc
		(start 222.784924 -66.153792)
		(mid 222.654171 -66.099633)
		(end 222.600012 -65.96888)
		(width 0.1397)
		(layer "In5.Cu")
		(net "PCIE_COMP_B_TO_SCC_B_7_DP")
	)
	(segment
		(start 231.873298 -95.565214)
		(end 230.925878 -94.949518)
		(width 0.1397)
		(layer "In5.Cu")
		(net "PCIE_COMP_B_TO_SCC_B_7_DN")
	)
	(segment
		(start 234.776772 -97.618804)
		(end 234.735624 -97.425256)
		(width 0.1397)
		(layer "In5.Cu")
		(net "PCIE_COMP_B_TO_SCC_B_7_DN")
	)
	(segment
		(start 230.925878 -94.949518)
		(end 229.044754 -92.05214)
		(width 0.1397)
		(layer "In5.Cu")
		(net "PCIE_COMP_B_TO_SCC_B_7_DN")
	)
	(segment
		(start 222.972376 -66.445892)
		(end 222.784924 -66.445892)
		(width 0.1397)
		(layer "In5.Cu")
		(net "PCIE_COMP_B_TO_SCC_B_7_DN")
	)
	(segment
		(start 233.7816 -96.805242)
		(end 233.430064 -96.576896)
		(width 0.1397)
		(layer "In5.Cu")
		(net "PCIE_COMP_B_TO_SCC_B_7_DN")
	)
	(segment
		(start 225.408236 -86.450678)
		(end 223.353884 -76.728574)
		(width 0.1397)
		(layer "In5.Cu")
		(net "PCIE_COMP_B_TO_SCC_B_7_DN")
	)
	(segment
		(start 232.47604 -95.956882)
		(end 232.268522 -96.000824)
		(width 0.1397)
		(layer "In5.Cu")
		(net "PCIE_COMP_B_TO_SCC_B_7_DN")
	)
	(segment
		(start 235.319824 -97.80524)
		(end 235.319824 -97.80651)
		(width 0.1397)
		(layer "In5.Cu")
		(net "PCIE_COMP_B_TO_SCC_B_7_DN")
	)
	(segment
		(start 232.827322 -96.185228)
		(end 232.47604 -95.956882)
		(width 0.1397)
		(layer "In5.Cu")
		(net "PCIE_COMP_B_TO_SCC_B_7_DN")
	)
	(segment
		(start 235.319824 -97.80651)
		(end 235.128054 -97.84715)
		(width 0.1397)
		(layer "In5.Cu")
		(net "PCIE_COMP_B_TO_SCC_B_7_DN")
	)
	(segment
		(start 232.871264 -96.392492)
		(end 232.827322 -96.185228)
		(width 0.1397)
		(layer "In5.Cu")
		(net "PCIE_COMP_B_TO_SCC_B_7_DN")
	)
	(segment
		(start 234.735624 -97.425256)
		(end 234.384342 -97.19691)
		(width 0.1397)
		(layer "In5.Cu")
		(net "PCIE_COMP_B_TO_SCC_B_7_DN")
	)
	(segment
		(start 235.128054 -97.84715)
		(end 234.776772 -97.618804)
		(width 0.1397)
		(layer "In5.Cu")
		(net "PCIE_COMP_B_TO_SCC_B_7_DN")
	)
	(segment
		(start 232.268522 -96.000824)
		(end 231.91724 -95.772478)
		(width 0.1397)
		(layer "In5.Cu")
		(net "PCIE_COMP_B_TO_SCC_B_7_DN")
	)
	(segment
		(start 285.39694 -130.347974)
		(end 236.502956 -98.573844)
		(width 0.1397)
		(layer "In5.Cu")
		(net "PCIE_COMP_B_TO_SCC_B_7_DN")
	)
	(segment
		(start 236.502956 -98.573844)
		(end 235.319824 -97.80524)
		(width 0.1397)
		(layer "In5.Cu")
		(net "PCIE_COMP_B_TO_SCC_B_7_DN")
	)
	(segment
		(start 228.164898 -90.696796)
		(end 225.408236 -86.450678)
		(width 0.1397)
		(layer "In5.Cu")
		(net "PCIE_COMP_B_TO_SCC_B_7_DN")
	)
	(segment
		(start 233.825542 -97.012506)
		(end 233.7816 -96.805242)
		(width 0.1397)
		(layer "In5.Cu")
		(net "PCIE_COMP_B_TO_SCC_B_7_DN")
	)
	(segment
		(start 285.436564 -132.094478)
		(end 285.771336 -132.094478)
		(width 0.1397)
		(layer "In5.Cu")
		(net "PCIE_COMP_B_TO_SCC_B_7_DN")
	)
	(segment
		(start 234.384342 -97.19691)
		(end 234.176824 -97.240852)
		(width 0.1397)
		(layer "In5.Cu")
		(net "PCIE_COMP_B_TO_SCC_B_7_DN")
	)
	(segment
		(start 234.176824 -97.240852)
		(end 233.825542 -97.012506)
		(width 0.1397)
		(layer "In5.Cu")
		(net "PCIE_COMP_B_TO_SCC_B_7_DN")
	)
	(segment
		(start 222.600012 -66.630804)
		(end 222.600012 -66.999866)
		(width 0.1397)
		(layer "In5.Cu")
		(net "PCIE_COMP_B_TO_SCC_B_7_DN")
	)
	(segment
		(start 223.353884 -76.728574)
		(end 223.353884 -66.8274)
		(width 0.1397)
		(layer "In5.Cu")
		(net "PCIE_COMP_B_TO_SCC_B_7_DN")
	)
	(segment
		(start 233.2228 -96.620838)
		(end 232.871264 -96.392492)
		(width 0.1397)
		(layer "In5.Cu")
		(net "PCIE_COMP_B_TO_SCC_B_7_DN")
	)
	(segment
		(start 233.430064 -96.576896)
		(end 233.2228 -96.620838)
		(width 0.1397)
		(layer "In5.Cu")
		(net "PCIE_COMP_B_TO_SCC_B_7_DN")
	)
	(segment
		(start 285.990538 -130.940556)
		(end 285.39694 -130.347974)
		(width 0.1397)
		(layer "In5.Cu")
		(net "PCIE_COMP_B_TO_SCC_B_7_DN")
	)
	(segment
		(start 285.990538 -131.875276)
		(end 285.990538 -130.940556)
		(width 0.1397)
		(layer "In5.Cu")
		(net "PCIE_COMP_B_TO_SCC_B_7_DN")
	)
	(segment
		(start 229.044754 -92.05214)
		(end 228.164898 -90.696796)
		(width 0.1397)
		(layer "In5.Cu")
		(net "PCIE_COMP_B_TO_SCC_B_7_DN")
	)
	(segment
		(start 231.91724 -95.772478)
		(end 231.873298 -95.565214)
		(width 0.1397)
		(layer "In5.Cu")
		(net "PCIE_COMP_B_TO_SCC_B_7_DN")
	)
	(arc
		(start 285.771336 -132.094478)
		(mid 285.926335 -132.030275)
		(end 285.990538 -131.875276)
		(width 0.1397)
		(layer "In5.Cu")
		(net "PCIE_COMP_B_TO_SCC_B_7_DN")
	)
	(arc
		(start 222.784924 -66.445892)
		(mid 222.654171 -66.500051)
		(end 222.600012 -66.630804)
		(width 0.1397)
		(layer "In5.Cu")
		(net "PCIE_COMP_B_TO_SCC_B_7_DN")
	)
	(arc
		(start 223.353884 -66.8274)
		(mid 223.242143 -66.557633)
		(end 222.972376 -66.445892)
		(width 0.1397)
		(layer "In5.Cu")
		(net "PCIE_COMP_B_TO_SCC_B_7_DN")
	)
	(segment
		(start 220.800168 -70.768972)
		(end 220.800168 -70.39991)
		(width 0.1397)
		(layer "In5.Cu")
		(net "PCIE_COMP_B_TO_SCC_B_6_DP")
	)
	(segment
		(start 223.034606 -84.23148)
		(end 221.84614 -78.116684)
		(width 0.1397)
		(layer "In5.Cu")
		(net "PCIE_COMP_B_TO_SCC_B_6_DP")
	)
	(segment
		(start 238.137192 -107.47756)
		(end 223.034606 -84.23148)
		(width 0.1397)
		(layer "In5.Cu")
		(net "PCIE_COMP_B_TO_SCC_B_6_DP")
	)
	(segment
		(start 221.172532 -70.953884)
		(end 220.98508 -70.953884)
		(width 0.1397)
		(layer "In5.Cu")
		(net "PCIE_COMP_B_TO_SCC_B_6_DP")
	)
	(segment
		(start 221.84614 -78.116684)
		(end 221.84614 -71.627492)
		(width 0.1397)
		(layer "In5.Cu")
		(net "PCIE_COMP_B_TO_SCC_B_6_DP")
	)
	(segment
		(start 286.633666 -132.84835)
		(end 277.204678 -132.84835)
		(width 0.1397)
		(layer "In5.Cu")
		(net "PCIE_COMP_B_TO_SCC_B_6_DP")
	)
	(segment
		(start 277.204678 -132.84835)
		(end 238.137192 -107.47756)
		(width 0.1397)
		(layer "In5.Cu")
		(net "PCIE_COMP_B_TO_SCC_B_6_DP")
	)
	(segment
		(start 287.83661 -133.894322)
		(end 287.501838 -133.894322)
		(width 0.1397)
		(layer "In5.Cu")
		(net "PCIE_COMP_B_TO_SCC_B_6_DP")
	)
	(segment
		(start 287.282636 -133.67512)
		(end 287.282636 -133.49732)
		(width 0.1397)
		(layer "In5.Cu")
		(net "PCIE_COMP_B_TO_SCC_B_6_DP")
	)
	(arc
		(start 220.98508 -70.953884)
		(mid 220.854327 -70.899725)
		(end 220.800168 -70.768972)
		(width 0.1397)
		(layer "In5.Cu")
		(net "PCIE_COMP_B_TO_SCC_B_6_DP")
	)
	(arc
		(start 287.282636 -133.49732)
		(mid 287.092557 -133.038429)
		(end 286.633666 -132.84835)
		(width 0.1397)
		(layer "In5.Cu")
		(net "PCIE_COMP_B_TO_SCC_B_6_DP")
	)
	(arc
		(start 221.84614 -71.627492)
		(mid 221.648845 -71.151179)
		(end 221.172532 -70.953884)
		(width 0.1397)
		(layer "In5.Cu")
		(net "PCIE_COMP_B_TO_SCC_B_6_DP")
	)
	(arc
		(start 287.501838 -133.894322)
		(mid 287.346839 -133.830119)
		(end 287.282636 -133.67512)
		(width 0.1397)
		(layer "In5.Cu")
		(net "PCIE_COMP_B_TO_SCC_B_6_DP")
	)
	(segment
		(start 221.798134 -80.06842)
		(end 221.898718 -79.919576)
		(width 0.1397)
		(layer "In5.Cu")
		(net "PCIE_COMP_B_TO_SCC_B_6_DN")
	)
	(segment
		(start 222.068644 -81.578958)
		(end 221.988888 -81.167732)
		(width 0.1397)
		(layer "In5.Cu")
		(net "PCIE_COMP_B_TO_SCC_B_6_DN")
	)
	(segment
		(start 237.925864 -107.688888)
		(end 222.758508 -84.342986)
		(width 0.1397)
		(layer "In5.Cu")
		(net "PCIE_COMP_B_TO_SCC_B_6_DN")
	)
	(segment
		(start 221.898718 -79.919576)
		(end 221.744286 -79.124048)
		(width 0.1397)
		(layer "In5.Cu")
		(net "PCIE_COMP_B_TO_SCC_B_6_DN")
	)
	(segment
		(start 222.107252 -80.991964)
		(end 222.027242 -80.580484)
		(width 0.1397)
		(layer "In5.Cu")
		(net "PCIE_COMP_B_TO_SCC_B_6_DN")
	)
	(segment
		(start 222.518732 -83.789266)
		(end 222.438976 -83.37804)
		(width 0.1397)
		(layer "In5.Cu")
		(net "PCIE_COMP_B_TO_SCC_B_6_DN")
	)
	(segment
		(start 221.55404 -78.144878)
		(end 221.55404 -71.627492)
		(width 0.1397)
		(layer "In5.Cu")
		(net "PCIE_COMP_B_TO_SCC_B_6_DN")
	)
	(segment
		(start 220.800168 -71.430896)
		(end 220.800168 -71.799958)
		(width 0.1397)
		(layer "In5.Cu")
		(net "PCIE_COMP_B_TO_SCC_B_6_DN")
	)
	(segment
		(start 286.633666 -133.14045)
		(end 277.118064 -133.14045)
		(width 0.1397)
		(layer "In5.Cu")
		(net "PCIE_COMP_B_TO_SCC_B_6_DN")
	)
	(segment
		(start 221.988888 -81.167732)
		(end 222.107252 -80.991964)
		(width 0.1397)
		(layer "In5.Cu")
		(net "PCIE_COMP_B_TO_SCC_B_6_DN")
	)
	(segment
		(start 222.027242 -80.580484)
		(end 221.878144 -80.4799)
		(width 0.1397)
		(layer "In5.Cu")
		(net "PCIE_COMP_B_TO_SCC_B_6_DN")
	)
	(segment
		(start 222.324422 -82.109056)
		(end 222.244412 -81.697576)
		(width 0.1397)
		(layer "In5.Cu")
		(net "PCIE_COMP_B_TO_SCC_B_6_DN")
	)
	(segment
		(start 277.118064 -133.14045)
		(end 237.925864 -107.688888)
		(width 0.1397)
		(layer "In5.Cu")
		(net "PCIE_COMP_B_TO_SCC_B_6_DN")
	)
	(segment
		(start 222.244412 -81.697576)
		(end 222.068644 -81.578958)
		(width 0.1397)
		(layer "In5.Cu")
		(net "PCIE_COMP_B_TO_SCC_B_6_DN")
	)
	(segment
		(start 286.436562 -133.894322)
		(end 286.771334 -133.894322)
		(width 0.1397)
		(layer "In5.Cu")
		(net "PCIE_COMP_B_TO_SCC_B_6_DN")
	)
	(segment
		(start 221.744286 -79.124048)
		(end 221.55404 -78.144878)
		(width 0.1397)
		(layer "In5.Cu")
		(net "PCIE_COMP_B_TO_SCC_B_6_DN")
	)
	(segment
		(start 222.285814 -82.69605)
		(end 222.205804 -82.28457)
		(width 0.1397)
		(layer "In5.Cu")
		(net "PCIE_COMP_B_TO_SCC_B_6_DN")
	)
	(segment
		(start 286.990536 -133.67512)
		(end 286.990536 -133.49732)
		(width 0.1397)
		(layer "In5.Cu")
		(net "PCIE_COMP_B_TO_SCC_B_6_DN")
	)
	(segment
		(start 222.438976 -83.37804)
		(end 222.541338 -83.225894)
		(width 0.1397)
		(layer "In5.Cu")
		(net "PCIE_COMP_B_TO_SCC_B_6_DN")
	)
	(segment
		(start 222.758508 -84.342986)
		(end 222.670624 -83.891882)
		(width 0.1397)
		(layer "In5.Cu")
		(net "PCIE_COMP_B_TO_SCC_B_6_DN")
	)
	(segment
		(start 222.541338 -83.225894)
		(end 222.461582 -82.814668)
		(width 0.1397)
		(layer "In5.Cu")
		(net "PCIE_COMP_B_TO_SCC_B_6_DN")
	)
	(segment
		(start 222.205804 -82.28457)
		(end 222.324422 -82.109056)
		(width 0.1397)
		(layer "In5.Cu")
		(net "PCIE_COMP_B_TO_SCC_B_6_DN")
	)
	(segment
		(start 221.878144 -80.4799)
		(end 221.798134 -80.06842)
		(width 0.1397)
		(layer "In5.Cu")
		(net "PCIE_COMP_B_TO_SCC_B_6_DN")
	)
	(segment
		(start 222.461582 -82.814668)
		(end 222.285814 -82.69605)
		(width 0.1397)
		(layer "In5.Cu")
		(net "PCIE_COMP_B_TO_SCC_B_6_DN")
	)
	(segment
		(start 222.670624 -83.891882)
		(end 222.518732 -83.789266)
		(width 0.1397)
		(layer "In5.Cu")
		(net "PCIE_COMP_B_TO_SCC_B_6_DN")
	)
	(segment
		(start 221.172532 -71.245984)
		(end 220.98508 -71.245984)
		(width 0.1397)
		(layer "In5.Cu")
		(net "PCIE_COMP_B_TO_SCC_B_6_DN")
	)
	(arc
		(start 286.990536 -133.49732)
		(mid 286.886011 -133.244975)
		(end 286.633666 -133.14045)
		(width 0.1397)
		(layer "In5.Cu")
		(net "PCIE_COMP_B_TO_SCC_B_6_DN")
	)
	(arc
		(start 220.98508 -71.245984)
		(mid 220.854327 -71.300143)
		(end 220.800168 -71.430896)
		(width 0.1397)
		(layer "In5.Cu")
		(net "PCIE_COMP_B_TO_SCC_B_6_DN")
	)
	(arc
		(start 221.55404 -71.627492)
		(mid 221.442299 -71.357725)
		(end 221.172532 -71.245984)
		(width 0.1397)
		(layer "In5.Cu")
		(net "PCIE_COMP_B_TO_SCC_B_6_DN")
	)
	(arc
		(start 286.771334 -133.894322)
		(mid 286.926333 -133.830119)
		(end 286.990536 -133.67512)
		(width 0.1397)
		(layer "In5.Cu")
		(net "PCIE_COMP_B_TO_SCC_B_6_DN")
	)
	(segment
		(start 277.543514 -134.648448)
		(end 237.186978 -108.440474)
		(width 0.1397)
		(layer "In5.Cu")
		(net "PCIE_COMP_B_TO_SCC_B_5_DP")
	)
	(segment
		(start 220.046042 -79.518002)
		(end 220.046042 -66.8274)
		(width 0.1397)
		(layer "In5.Cu")
		(net "PCIE_COMP_B_TO_SCC_B_5_DP")
	)
	(segment
		(start 219.372434 -66.153792)
		(end 219.184982 -66.153792)
		(width 0.1397)
		(layer "In5.Cu")
		(net "PCIE_COMP_B_TO_SCC_B_5_DP")
	)
	(segment
		(start 237.186978 -108.440474)
		(end 220.847158 -83.289394)
		(width 0.1397)
		(layer "In5.Cu")
		(net "PCIE_COMP_B_TO_SCC_B_5_DP")
	)
	(segment
		(start 286.836612 -135.69442)
		(end 286.50184 -135.69442)
		(width 0.1397)
		(layer "In5.Cu")
		(net "PCIE_COMP_B_TO_SCC_B_5_DP")
	)
	(segment
		(start 285.633668 -134.648448)
		(end 277.543514 -134.648448)
		(width 0.1397)
		(layer "In5.Cu")
		(net "PCIE_COMP_B_TO_SCC_B_5_DP")
	)
	(segment
		(start 219.00007 -65.96888)
		(end 219.00007 -65.600072)
		(width 0.1397)
		(layer "In5.Cu")
		(net "PCIE_COMP_B_TO_SCC_B_5_DP")
	)
	(segment
		(start 220.847158 -83.289394)
		(end 220.046042 -79.518002)
		(width 0.1397)
		(layer "In5.Cu")
		(net "PCIE_COMP_B_TO_SCC_B_5_DP")
	)
	(segment
		(start 286.282638 -135.475218)
		(end 286.282638 -135.297418)
		(width 0.1397)
		(layer "In5.Cu")
		(net "PCIE_COMP_B_TO_SCC_B_5_DP")
	)
	(arc
		(start 286.282638 -135.297418)
		(mid 286.092559 -134.838527)
		(end 285.633668 -134.648448)
		(width 0.1397)
		(layer "In5.Cu")
		(net "PCIE_COMP_B_TO_SCC_B_5_DP")
	)
	(arc
		(start 219.184982 -66.153792)
		(mid 219.054229 -66.099633)
		(end 219.00007 -65.96888)
		(width 0.1397)
		(layer "In5.Cu")
		(net "PCIE_COMP_B_TO_SCC_B_5_DP")
	)
	(arc
		(start 286.50184 -135.69442)
		(mid 286.346841 -135.630217)
		(end 286.282638 -135.475218)
		(width 0.1397)
		(layer "In5.Cu")
		(net "PCIE_COMP_B_TO_SCC_B_5_DP")
	)
	(arc
		(start 220.046042 -66.8274)
		(mid 219.848747 -66.351087)
		(end 219.372434 -66.153792)
		(width 0.1397)
		(layer "In5.Cu")
		(net "PCIE_COMP_B_TO_SCC_B_5_DP")
	)
	(segment
		(start 224.362264 -89.236804)
		(end 224.16897 -89.195656)
		(width 0.1397)
		(layer "In5.Cu")
		(net "PCIE_COMP_B_TO_SCC_B_5_DN")
	)
	(segment
		(start 223.331786 -87.90686)
		(end 223.372934 -87.71382)
		(width 0.1397)
		(layer "In5.Cu")
		(net "PCIE_COMP_B_TO_SCC_B_5_DN")
	)
	(segment
		(start 223.940624 -88.84412)
		(end 223.981772 -88.65108)
		(width 0.1397)
		(layer "In5.Cu")
		(net "PCIE_COMP_B_TO_SCC_B_5_DN")
	)
	(segment
		(start 223.560132 -88.258396)
		(end 223.331786 -87.90686)
		(width 0.1397)
		(layer "In5.Cu")
		(net "PCIE_COMP_B_TO_SCC_B_5_DN")
	)
	(segment
		(start 222.155258 -85.8393)
		(end 220.572584 -83.403186)
		(width 0.1397)
		(layer "In5.Cu")
		(net "PCIE_COMP_B_TO_SCC_B_5_DN")
	)
	(segment
		(start 222.764096 -86.77656)
		(end 222.53575 -86.425024)
		(width 0.1397)
		(layer "In5.Cu")
		(net "PCIE_COMP_B_TO_SCC_B_5_DN")
	)
	(segment
		(start 222.722948 -86.9696)
		(end 222.764096 -86.77656)
		(width 0.1397)
		(layer "In5.Cu")
		(net "PCIE_COMP_B_TO_SCC_B_5_DN")
	)
	(segment
		(start 219.372434 -66.445892)
		(end 219.184982 -66.445892)
		(width 0.1397)
		(layer "In5.Cu")
		(net "PCIE_COMP_B_TO_SCC_B_5_DN")
	)
	(segment
		(start 223.144588 -87.362284)
		(end 222.951294 -87.321136)
		(width 0.1397)
		(layer "In5.Cu")
		(net "PCIE_COMP_B_TO_SCC_B_5_DN")
	)
	(segment
		(start 223.753426 -88.299544)
		(end 223.560132 -88.258396)
		(width 0.1397)
		(layer "In5.Cu")
		(net "PCIE_COMP_B_TO_SCC_B_5_DN")
	)
	(segment
		(start 285.436564 -135.69442)
		(end 285.771336 -135.69442)
		(width 0.1397)
		(layer "In5.Cu")
		(net "PCIE_COMP_B_TO_SCC_B_5_DN")
	)
	(segment
		(start 222.53575 -86.425024)
		(end 222.342456 -86.383876)
		(width 0.1397)
		(layer "In5.Cu")
		(net "PCIE_COMP_B_TO_SCC_B_5_DN")
	)
	(segment
		(start 277.4569 -134.940548)
		(end 236.97565 -108.651802)
		(width 0.1397)
		(layer "In5.Cu")
		(net "PCIE_COMP_B_TO_SCC_B_5_DN")
	)
	(segment
		(start 223.372934 -87.71382)
		(end 223.144588 -87.362284)
		(width 0.1397)
		(layer "In5.Cu")
		(net "PCIE_COMP_B_TO_SCC_B_5_DN")
	)
	(segment
		(start 224.16897 -89.195656)
		(end 223.940624 -88.84412)
		(width 0.1397)
		(layer "In5.Cu")
		(net "PCIE_COMP_B_TO_SCC_B_5_DN")
	)
	(segment
		(start 285.633668 -134.940548)
		(end 277.4569 -134.940548)
		(width 0.1397)
		(layer "In5.Cu")
		(net "PCIE_COMP_B_TO_SCC_B_5_DN")
	)
	(segment
		(start 219.753942 -79.548736)
		(end 219.753942 -66.8274)
		(width 0.1397)
		(layer "In5.Cu")
		(net "PCIE_COMP_B_TO_SCC_B_5_DN")
	)
	(segment
		(start 222.11411 -86.032594)
		(end 222.155258 -85.8393)
		(width 0.1397)
		(layer "In5.Cu")
		(net "PCIE_COMP_B_TO_SCC_B_5_DN")
	)
	(segment
		(start 220.572584 -83.403186)
		(end 219.753942 -79.548736)
		(width 0.1397)
		(layer "In5.Cu")
		(net "PCIE_COMP_B_TO_SCC_B_5_DN")
	)
	(segment
		(start 285.990538 -135.475218)
		(end 285.990538 -135.297418)
		(width 0.1397)
		(layer "In5.Cu")
		(net "PCIE_COMP_B_TO_SCC_B_5_DN")
	)
	(segment
		(start 222.951294 -87.321136)
		(end 222.722948 -86.9696)
		(width 0.1397)
		(layer "In5.Cu")
		(net "PCIE_COMP_B_TO_SCC_B_5_DN")
	)
	(segment
		(start 219.00007 -66.630804)
		(end 219.00007 -66.999866)
		(width 0.1397)
		(layer "In5.Cu")
		(net "PCIE_COMP_B_TO_SCC_B_5_DN")
	)
	(segment
		(start 223.981772 -88.65108)
		(end 223.753426 -88.299544)
		(width 0.1397)
		(layer "In5.Cu")
		(net "PCIE_COMP_B_TO_SCC_B_5_DN")
	)
	(segment
		(start 222.342456 -86.383876)
		(end 222.11411 -86.032594)
		(width 0.1397)
		(layer "In5.Cu")
		(net "PCIE_COMP_B_TO_SCC_B_5_DN")
	)
	(segment
		(start 236.97565 -108.651802)
		(end 224.362264 -89.236804)
		(width 0.1397)
		(layer "In5.Cu")
		(net "PCIE_COMP_B_TO_SCC_B_5_DN")
	)
	(arc
		(start 219.184982 -66.445892)
		(mid 219.054229 -66.500051)
		(end 219.00007 -66.630804)
		(width 0.1397)
		(layer "In5.Cu")
		(net "PCIE_COMP_B_TO_SCC_B_5_DN")
	)
	(arc
		(start 219.753942 -66.8274)
		(mid 219.642201 -66.557633)
		(end 219.372434 -66.445892)
		(width 0.1397)
		(layer "In5.Cu")
		(net "PCIE_COMP_B_TO_SCC_B_5_DN")
	)
	(arc
		(start 285.771336 -135.69442)
		(mid 285.926335 -135.630217)
		(end 285.990538 -135.475218)
		(width 0.1397)
		(layer "In5.Cu")
		(net "PCIE_COMP_B_TO_SCC_B_5_DN")
	)
	(arc
		(start 285.990538 -135.297418)
		(mid 285.886013 -135.045073)
		(end 285.633668 -134.940548)
		(width 0.1397)
		(layer "In5.Cu")
		(net "PCIE_COMP_B_TO_SCC_B_5_DN")
	)
	(segment
		(start 286.633666 -136.448546)
		(end 277.110698 -136.448546)
		(width 0.1397)
		(layer "In5.Cu")
		(net "PCIE_COMP_B_TO_SCC_B_4_DP")
	)
	(segment
		(start 217.572336 -70.953884)
		(end 217.384884 -70.953884)
		(width 0.1397)
		(layer "In5.Cu")
		(net "PCIE_COMP_B_TO_SCC_B_4_DP")
	)
	(segment
		(start 236.64545 -110.168944)
		(end 218.245944 -81.834482)
		(width 0.1397)
		(layer "In5.Cu")
		(net "PCIE_COMP_B_TO_SCC_B_4_DP")
	)
	(segment
		(start 217.199972 -70.768972)
		(end 217.199972 -70.39991)
		(width 0.1397)
		(layer "In5.Cu")
		(net "PCIE_COMP_B_TO_SCC_B_4_DP")
	)
	(segment
		(start 287.83661 -137.494518)
		(end 287.501838 -137.494518)
		(width 0.1397)
		(layer "In5.Cu")
		(net "PCIE_COMP_B_TO_SCC_B_4_DP")
	)
	(segment
		(start 218.245944 -81.834482)
		(end 218.245944 -71.627492)
		(width 0.1397)
		(layer "In5.Cu")
		(net "PCIE_COMP_B_TO_SCC_B_4_DP")
	)
	(segment
		(start 277.110698 -136.448546)
		(end 236.64545 -110.168944)
		(width 0.1397)
		(layer "In5.Cu")
		(net "PCIE_COMP_B_TO_SCC_B_4_DP")
	)
	(segment
		(start 287.282636 -137.275316)
		(end 287.282636 -137.097516)
		(width 0.1397)
		(layer "In5.Cu")
		(net "PCIE_COMP_B_TO_SCC_B_4_DP")
	)
	(arc
		(start 218.245944 -71.627492)
		(mid 218.048649 -71.151179)
		(end 217.572336 -70.953884)
		(width 0.1397)
		(layer "In5.Cu")
		(net "PCIE_COMP_B_TO_SCC_B_4_DP")
	)
	(arc
		(start 287.282636 -137.097516)
		(mid 287.092557 -136.638625)
		(end 286.633666 -136.448546)
		(width 0.1397)
		(layer "In5.Cu")
		(net "PCIE_COMP_B_TO_SCC_B_4_DP")
	)
	(arc
		(start 217.384884 -70.953884)
		(mid 217.254131 -70.899725)
		(end 217.199972 -70.768972)
		(width 0.1397)
		(layer "In5.Cu")
		(net "PCIE_COMP_B_TO_SCC_B_4_DP")
	)
	(arc
		(start 287.501838 -137.494518)
		(mid 287.346839 -137.430315)
		(end 287.282636 -137.275316)
		(width 0.1397)
		(layer "In5.Cu")
		(net "PCIE_COMP_B_TO_SCC_B_4_DP")
	)
	(segment
		(start 223.00565 -89.700608)
		(end 222.777304 -89.349326)
		(width 0.1397)
		(layer "In5.Cu")
		(net "PCIE_COMP_B_TO_SCC_B_4_DN")
	)
	(segment
		(start 217.199972 -71.430896)
		(end 217.199972 -71.799958)
		(width 0.1397)
		(layer "In5.Cu")
		(net "PCIE_COMP_B_TO_SCC_B_4_DN")
	)
	(segment
		(start 286.436562 -137.494518)
		(end 286.771334 -137.494518)
		(width 0.1397)
		(layer "In5.Cu")
		(net "PCIE_COMP_B_TO_SCC_B_4_DN")
	)
	(segment
		(start 221.74708 -88.019382)
		(end 221.788228 -87.826088)
		(width 0.1397)
		(layer "In5.Cu")
		(net "PCIE_COMP_B_TO_SCC_B_4_DN")
	)
	(segment
		(start 221.975426 -88.370918)
		(end 221.74708 -88.019382)
		(width 0.1397)
		(layer "In5.Cu")
		(net "PCIE_COMP_B_TO_SCC_B_4_DN")
	)
	(segment
		(start 223.385888 -90.286586)
		(end 223.192848 -90.245438)
		(width 0.1397)
		(layer "In5.Cu")
		(net "PCIE_COMP_B_TO_SCC_B_4_DN")
	)
	(segment
		(start 277.024084 -136.740646)
		(end 236.434122 -110.380272)
		(width 0.1397)
		(layer "In5.Cu")
		(net "PCIE_COMP_B_TO_SCC_B_4_DN")
	)
	(segment
		(start 223.192848 -90.245438)
		(end 222.964502 -89.893902)
		(width 0.1397)
		(layer "In5.Cu")
		(net "PCIE_COMP_B_TO_SCC_B_4_DN")
	)
	(segment
		(start 222.964502 -89.893902)
		(end 223.00565 -89.700608)
		(width 0.1397)
		(layer "In5.Cu")
		(net "PCIE_COMP_B_TO_SCC_B_4_DN")
	)
	(segment
		(start 222.396812 -88.763348)
		(end 222.16872 -88.411812)
		(width 0.1397)
		(layer "In5.Cu")
		(net "PCIE_COMP_B_TO_SCC_B_4_DN")
	)
	(segment
		(start 222.58401 -89.308178)
		(end 222.355918 -88.956642)
		(width 0.1397)
		(layer "In5.Cu")
		(net "PCIE_COMP_B_TO_SCC_B_4_DN")
	)
	(segment
		(start 222.16872 -88.411812)
		(end 221.975426 -88.370918)
		(width 0.1397)
		(layer "In5.Cu")
		(net "PCIE_COMP_B_TO_SCC_B_4_DN")
	)
	(segment
		(start 222.777304 -89.349326)
		(end 222.58401 -89.308178)
		(width 0.1397)
		(layer "In5.Cu")
		(net "PCIE_COMP_B_TO_SCC_B_4_DN")
	)
	(segment
		(start 222.355918 -88.956642)
		(end 222.396812 -88.763348)
		(width 0.1397)
		(layer "In5.Cu")
		(net "PCIE_COMP_B_TO_SCC_B_4_DN")
	)
	(segment
		(start 236.434122 -110.380272)
		(end 223.994726 -91.223846)
		(width 0.1397)
		(layer "In5.Cu")
		(net "PCIE_COMP_B_TO_SCC_B_4_DN")
	)
	(segment
		(start 223.614234 -90.638122)
		(end 223.385888 -90.286586)
		(width 0.1397)
		(layer "In5.Cu")
		(net "PCIE_COMP_B_TO_SCC_B_4_DN")
	)
	(segment
		(start 286.990536 -137.275316)
		(end 286.990536 -137.097516)
		(width 0.1397)
		(layer "In5.Cu")
		(net "PCIE_COMP_B_TO_SCC_B_4_DN")
	)
	(segment
		(start 217.953844 -81.921096)
		(end 217.953844 -71.627492)
		(width 0.1397)
		(layer "In5.Cu")
		(net "PCIE_COMP_B_TO_SCC_B_4_DN")
	)
	(segment
		(start 221.788228 -87.826088)
		(end 217.953844 -81.921096)
		(width 0.1397)
		(layer "In5.Cu")
		(net "PCIE_COMP_B_TO_SCC_B_4_DN")
	)
	(segment
		(start 217.572336 -71.245984)
		(end 217.384884 -71.245984)
		(width 0.1397)
		(layer "In5.Cu")
		(net "PCIE_COMP_B_TO_SCC_B_4_DN")
	)
	(segment
		(start 223.573086 -90.831162)
		(end 223.614234 -90.638122)
		(width 0.1397)
		(layer "In5.Cu")
		(net "PCIE_COMP_B_TO_SCC_B_4_DN")
	)
	(segment
		(start 223.801432 -91.182698)
		(end 223.573086 -90.831162)
		(width 0.1397)
		(layer "In5.Cu")
		(net "PCIE_COMP_B_TO_SCC_B_4_DN")
	)
	(segment
		(start 286.633666 -136.740646)
		(end 277.024084 -136.740646)
		(width 0.1397)
		(layer "In5.Cu")
		(net "PCIE_COMP_B_TO_SCC_B_4_DN")
	)
	(segment
		(start 223.994726 -91.223846)
		(end 223.801432 -91.182698)
		(width 0.1397)
		(layer "In5.Cu")
		(net "PCIE_COMP_B_TO_SCC_B_4_DN")
	)
	(arc
		(start 217.953844 -71.627492)
		(mid 217.842103 -71.357725)
		(end 217.572336 -71.245984)
		(width 0.1397)
		(layer "In5.Cu")
		(net "PCIE_COMP_B_TO_SCC_B_4_DN")
	)
	(arc
		(start 286.990536 -137.097516)
		(mid 286.886011 -136.845171)
		(end 286.633666 -136.740646)
		(width 0.1397)
		(layer "In5.Cu")
		(net "PCIE_COMP_B_TO_SCC_B_4_DN")
	)
	(arc
		(start 217.384884 -71.245984)
		(mid 217.254131 -71.300143)
		(end 217.199972 -71.430896)
		(width 0.1397)
		(layer "In5.Cu")
		(net "PCIE_COMP_B_TO_SCC_B_4_DN")
	)
	(arc
		(start 286.771334 -137.494518)
		(mid 286.926333 -137.430315)
		(end 286.990536 -137.275316)
		(width 0.1397)
		(layer "In5.Cu")
		(net "PCIE_COMP_B_TO_SCC_B_4_DN")
	)
	(segment
		(start 215.400128 -65.96888)
		(end 215.400128 -65.600072)
		(width 0.1397)
		(layer "In5.Cu")
		(net "PCIE_COMP_B_TO_SCC_B_3_DP")
	)
	(segment
		(start 285.633668 -138.24839)
		(end 277.345902 -138.24839)
		(width 0.1397)
		(layer "In5.Cu")
		(net "PCIE_COMP_B_TO_SCC_B_3_DP")
	)
	(segment
		(start 216.4461 -81.775554)
		(end 216.4461 -66.8274)
		(width 0.1397)
		(layer "In5.Cu")
		(net "PCIE_COMP_B_TO_SCC_B_3_DP")
	)
	(segment
		(start 286.282638 -139.07516)
		(end 286.282638 -138.89736)
		(width 0.1397)
		(layer "In5.Cu")
		(net "PCIE_COMP_B_TO_SCC_B_3_DP")
	)
	(segment
		(start 286.836612 -139.294362)
		(end 286.50184 -139.294362)
		(width 0.1397)
		(layer "In5.Cu")
		(net "PCIE_COMP_B_TO_SCC_B_3_DP")
	)
	(segment
		(start 277.345902 -138.24839)
		(end 235.441998 -111.035846)
		(width 0.1397)
		(layer "In5.Cu")
		(net "PCIE_COMP_B_TO_SCC_B_3_DP")
	)
	(segment
		(start 235.441998 -111.035846)
		(end 216.4461 -81.775554)
		(width 0.1397)
		(layer "In5.Cu")
		(net "PCIE_COMP_B_TO_SCC_B_3_DP")
	)
	(segment
		(start 215.772492 -66.153792)
		(end 215.58504 -66.153792)
		(width 0.1397)
		(layer "In5.Cu")
		(net "PCIE_COMP_B_TO_SCC_B_3_DP")
	)
	(arc
		(start 286.282638 -138.89736)
		(mid 286.092559 -138.438469)
		(end 285.633668 -138.24839)
		(width 0.1397)
		(layer "In5.Cu")
		(net "PCIE_COMP_B_TO_SCC_B_3_DP")
	)
	(arc
		(start 286.50184 -139.294362)
		(mid 286.346841 -139.230159)
		(end 286.282638 -139.07516)
		(width 0.1397)
		(layer "In5.Cu")
		(net "PCIE_COMP_B_TO_SCC_B_3_DP")
	)
	(arc
		(start 216.4461 -66.8274)
		(mid 216.248805 -66.351087)
		(end 215.772492 -66.153792)
		(width 0.1397)
		(layer "In5.Cu")
		(net "PCIE_COMP_B_TO_SCC_B_3_DP")
	)
	(arc
		(start 215.58504 -66.153792)
		(mid 215.454287 -66.099633)
		(end 215.400128 -65.96888)
		(width 0.1397)
		(layer "In5.Cu")
		(net "PCIE_COMP_B_TO_SCC_B_3_DP")
	)
	(segment
		(start 230.032306 -103.240078)
		(end 229.804214 -102.888542)
		(width 0.1397)
		(layer "In5.Cu")
		(net "PCIE_COMP_B_TO_SCC_B_3_DN")
	)
	(segment
		(start 285.436564 -139.294362)
		(end 285.771336 -139.294362)
		(width 0.1397)
		(layer "In5.Cu")
		(net "PCIE_COMP_B_TO_SCC_B_3_DN")
	)
	(segment
		(start 216.154 -81.862168)
		(end 216.154 -66.8274)
		(width 0.1397)
		(layer "In5.Cu")
		(net "PCIE_COMP_B_TO_SCC_B_3_DN")
	)
	(segment
		(start 231.629712 -105.700576)
		(end 231.436672 -105.659428)
		(width 0.1397)
		(layer "In5.Cu")
		(net "PCIE_COMP_B_TO_SCC_B_3_DN")
	)
	(segment
		(start 231.208326 -105.307892)
		(end 231.249474 -105.114852)
		(width 0.1397)
		(layer "In5.Cu")
		(net "PCIE_COMP_B_TO_SCC_B_3_DN")
	)
	(segment
		(start 231.249474 -105.114852)
		(end 231.021128 -104.763316)
		(width 0.1397)
		(layer "In5.Cu")
		(net "PCIE_COMP_B_TO_SCC_B_3_DN")
	)
	(segment
		(start 229.804214 -102.888542)
		(end 229.61092 -102.847394)
		(width 0.1397)
		(layer "In5.Cu")
		(net "PCIE_COMP_B_TO_SCC_B_3_DN")
	)
	(segment
		(start 231.021128 -104.763316)
		(end 230.828088 -104.722168)
		(width 0.1397)
		(layer "In5.Cu")
		(net "PCIE_COMP_B_TO_SCC_B_3_DN")
	)
	(segment
		(start 230.219504 -103.784654)
		(end 229.991158 -103.433118)
		(width 0.1397)
		(layer "In5.Cu")
		(net "PCIE_COMP_B_TO_SCC_B_3_DN")
	)
	(segment
		(start 229.423722 -102.302564)
		(end 216.154 -81.862168)
		(width 0.1397)
		(layer "In5.Cu")
		(net "PCIE_COMP_B_TO_SCC_B_3_DN")
	)
	(segment
		(start 229.382574 -102.495858)
		(end 229.423722 -102.302564)
		(width 0.1397)
		(layer "In5.Cu")
		(net "PCIE_COMP_B_TO_SCC_B_3_DN")
	)
	(segment
		(start 277.259288 -138.54049)
		(end 235.23067 -111.247174)
		(width 0.1397)
		(layer "In5.Cu")
		(net "PCIE_COMP_B_TO_SCC_B_3_DN")
	)
	(segment
		(start 230.599742 -104.370632)
		(end 230.64089 -104.177338)
		(width 0.1397)
		(layer "In5.Cu")
		(net "PCIE_COMP_B_TO_SCC_B_3_DN")
	)
	(segment
		(start 215.772492 -66.445892)
		(end 215.58504 -66.445892)
		(width 0.1397)
		(layer "In5.Cu")
		(net "PCIE_COMP_B_TO_SCC_B_3_DN")
	)
	(segment
		(start 229.61092 -102.847394)
		(end 229.382574 -102.495858)
		(width 0.1397)
		(layer "In5.Cu")
		(net "PCIE_COMP_B_TO_SCC_B_3_DN")
	)
	(segment
		(start 231.436672 -105.659428)
		(end 231.208326 -105.307892)
		(width 0.1397)
		(layer "In5.Cu")
		(net "PCIE_COMP_B_TO_SCC_B_3_DN")
	)
	(segment
		(start 215.400128 -66.630804)
		(end 215.400128 -66.999866)
		(width 0.1397)
		(layer "In5.Cu")
		(net "PCIE_COMP_B_TO_SCC_B_3_DN")
	)
	(segment
		(start 229.991158 -103.433118)
		(end 230.032306 -103.240078)
		(width 0.1397)
		(layer "In5.Cu")
		(net "PCIE_COMP_B_TO_SCC_B_3_DN")
	)
	(segment
		(start 285.633668 -138.54049)
		(end 277.259288 -138.54049)
		(width 0.1397)
		(layer "In5.Cu")
		(net "PCIE_COMP_B_TO_SCC_B_3_DN")
	)
	(segment
		(start 230.64089 -104.177338)
		(end 230.412798 -103.825802)
		(width 0.1397)
		(layer "In5.Cu")
		(net "PCIE_COMP_B_TO_SCC_B_3_DN")
	)
	(segment
		(start 285.990538 -139.07516)
		(end 285.990538 -138.89736)
		(width 0.1397)
		(layer "In5.Cu")
		(net "PCIE_COMP_B_TO_SCC_B_3_DN")
	)
	(segment
		(start 230.412798 -103.825802)
		(end 230.219504 -103.784654)
		(width 0.1397)
		(layer "In5.Cu")
		(net "PCIE_COMP_B_TO_SCC_B_3_DN")
	)
	(segment
		(start 235.23067 -111.247174)
		(end 231.629712 -105.700576)
		(width 0.1397)
		(layer "In5.Cu")
		(net "PCIE_COMP_B_TO_SCC_B_3_DN")
	)
	(segment
		(start 230.828088 -104.722168)
		(end 230.599742 -104.370632)
		(width 0.1397)
		(layer "In5.Cu")
		(net "PCIE_COMP_B_TO_SCC_B_3_DN")
	)
	(arc
		(start 285.990538 -138.89736)
		(mid 285.886013 -138.645015)
		(end 285.633668 -138.54049)
		(width 0.1397)
		(layer "In5.Cu")
		(net "PCIE_COMP_B_TO_SCC_B_3_DN")
	)
	(arc
		(start 216.154 -66.8274)
		(mid 216.042259 -66.557633)
		(end 215.772492 -66.445892)
		(width 0.1397)
		(layer "In5.Cu")
		(net "PCIE_COMP_B_TO_SCC_B_3_DN")
	)
	(arc
		(start 285.771336 -139.294362)
		(mid 285.926335 -139.230159)
		(end 285.990538 -139.07516)
		(width 0.1397)
		(layer "In5.Cu")
		(net "PCIE_COMP_B_TO_SCC_B_3_DN")
	)
	(arc
		(start 215.58504 -66.445892)
		(mid 215.454287 -66.500051)
		(end 215.400128 -66.630804)
		(width 0.1397)
		(layer "In5.Cu")
		(net "PCIE_COMP_B_TO_SCC_B_3_DN")
	)
	(segment
		(start 287.83661 -141.09446)
		(end 287.501838 -141.09446)
		(width 0.1397)
		(layer "In5.Cu")
		(net "PCIE_COMP_B_TO_SCC_B_2_DP")
	)
	(segment
		(start 286.633666 -140.048488)
		(end 276.578568 -140.048488)
		(width 0.1397)
		(layer "In5.Cu")
		(net "PCIE_COMP_B_TO_SCC_B_2_DP")
	)
	(segment
		(start 234.983782 -113.03508)
		(end 214.646002 -81.708498)
		(width 0.1397)
		(layer "In5.Cu")
		(net "PCIE_COMP_B_TO_SCC_B_2_DP")
	)
	(segment
		(start 213.972394 -70.953884)
		(end 213.784942 -70.953884)
		(width 0.1397)
		(layer "In5.Cu")
		(net "PCIE_COMP_B_TO_SCC_B_2_DP")
	)
	(segment
		(start 214.646002 -81.708498)
		(end 214.646002 -71.627492)
		(width 0.1397)
		(layer "In5.Cu")
		(net "PCIE_COMP_B_TO_SCC_B_2_DP")
	)
	(segment
		(start 213.60003 -70.768972)
		(end 213.60003 -70.39991)
		(width 0.1397)
		(layer "In5.Cu")
		(net "PCIE_COMP_B_TO_SCC_B_2_DP")
	)
	(segment
		(start 276.578568 -140.048488)
		(end 234.983782 -113.03508)
		(width 0.1397)
		(layer "In5.Cu")
		(net "PCIE_COMP_B_TO_SCC_B_2_DP")
	)
	(segment
		(start 287.282636 -140.875258)
		(end 287.282636 -140.697458)
		(width 0.1397)
		(layer "In5.Cu")
		(net "PCIE_COMP_B_TO_SCC_B_2_DP")
	)
	(arc
		(start 287.282636 -140.697458)
		(mid 287.092557 -140.238567)
		(end 286.633666 -140.048488)
		(width 0.1397)
		(layer "In5.Cu")
		(net "PCIE_COMP_B_TO_SCC_B_2_DP")
	)
	(arc
		(start 287.501838 -141.09446)
		(mid 287.346839 -141.030257)
		(end 287.282636 -140.875258)
		(width 0.1397)
		(layer "In5.Cu")
		(net "PCIE_COMP_B_TO_SCC_B_2_DP")
	)
	(arc
		(start 214.646002 -71.627492)
		(mid 214.448707 -71.151179)
		(end 213.972394 -70.953884)
		(width 0.1397)
		(layer "In5.Cu")
		(net "PCIE_COMP_B_TO_SCC_B_2_DP")
	)
	(arc
		(start 213.784942 -70.953884)
		(mid 213.654189 -70.899725)
		(end 213.60003 -70.768972)
		(width 0.1397)
		(layer "In5.Cu")
		(net "PCIE_COMP_B_TO_SCC_B_2_DP")
	)
	(segment
		(start 225.872548 -99.537266)
		(end 225.679254 -99.496372)
		(width 0.1397)
		(layer "In5.Cu")
		(net "PCIE_COMP_B_TO_SCC_B_2_DN")
	)
	(segment
		(start 225.263964 -98.600006)
		(end 225.07067 -98.558858)
		(width 0.1397)
		(layer "In5.Cu")
		(net "PCIE_COMP_B_TO_SCC_B_2_DN")
	)
	(segment
		(start 286.436562 -141.09446)
		(end 286.771334 -141.09446)
		(width 0.1397)
		(layer "In5.Cu")
		(net "PCIE_COMP_B_TO_SCC_B_2_DN")
	)
	(segment
		(start 225.492056 -98.951542)
		(end 225.263964 -98.600006)
		(width 0.1397)
		(layer "In5.Cu")
		(net "PCIE_COMP_B_TO_SCC_B_2_DN")
	)
	(segment
		(start 213.60003 -71.430896)
		(end 213.60003 -71.799958)
		(width 0.1397)
		(layer "In5.Cu")
		(net "PCIE_COMP_B_TO_SCC_B_2_DN")
	)
	(segment
		(start 226.709224 -100.826316)
		(end 226.480878 -100.47478)
		(width 0.1397)
		(layer "In5.Cu")
		(net "PCIE_COMP_B_TO_SCC_B_2_DN")
	)
	(segment
		(start 226.896422 -101.371146)
		(end 226.668076 -101.01961)
		(width 0.1397)
		(layer "In5.Cu")
		(net "PCIE_COMP_B_TO_SCC_B_2_DN")
	)
	(segment
		(start 226.10064 -99.888802)
		(end 225.872548 -99.537266)
		(width 0.1397)
		(layer "In5.Cu")
		(net "PCIE_COMP_B_TO_SCC_B_2_DN")
	)
	(segment
		(start 214.353902 -81.795112)
		(end 214.353902 -71.627492)
		(width 0.1397)
		(layer "In5.Cu")
		(net "PCIE_COMP_B_TO_SCC_B_2_DN")
	)
	(segment
		(start 227.089462 -101.41204)
		(end 226.896422 -101.371146)
		(width 0.1397)
		(layer "In5.Cu")
		(net "PCIE_COMP_B_TO_SCC_B_2_DN")
	)
	(segment
		(start 286.990536 -140.875258)
		(end 286.990536 -140.697458)
		(width 0.1397)
		(layer "In5.Cu")
		(net "PCIE_COMP_B_TO_SCC_B_2_DN")
	)
	(segment
		(start 213.972394 -71.245984)
		(end 213.784942 -71.245984)
		(width 0.1397)
		(layer "In5.Cu")
		(net "PCIE_COMP_B_TO_SCC_B_2_DN")
	)
	(segment
		(start 286.633666 -140.340588)
		(end 276.491954 -140.340588)
		(width 0.1397)
		(layer "In5.Cu")
		(net "PCIE_COMP_B_TO_SCC_B_2_DN")
	)
	(segment
		(start 225.679254 -99.496372)
		(end 225.450908 -99.144836)
		(width 0.1397)
		(layer "In5.Cu")
		(net "PCIE_COMP_B_TO_SCC_B_2_DN")
	)
	(segment
		(start 226.480878 -100.47478)
		(end 226.287838 -100.433632)
		(width 0.1397)
		(layer "In5.Cu")
		(net "PCIE_COMP_B_TO_SCC_B_2_DN")
	)
	(segment
		(start 226.287838 -100.433632)
		(end 226.059492 -100.082096)
		(width 0.1397)
		(layer "In5.Cu")
		(net "PCIE_COMP_B_TO_SCC_B_2_DN")
	)
	(segment
		(start 276.491954 -140.340588)
		(end 234.772454 -113.246408)
		(width 0.1397)
		(layer "In5.Cu")
		(net "PCIE_COMP_B_TO_SCC_B_2_DN")
	)
	(segment
		(start 226.059492 -100.082096)
		(end 226.10064 -99.888802)
		(width 0.1397)
		(layer "In5.Cu")
		(net "PCIE_COMP_B_TO_SCC_B_2_DN")
	)
	(segment
		(start 226.668076 -101.01961)
		(end 226.709224 -100.826316)
		(width 0.1397)
		(layer "In5.Cu")
		(net "PCIE_COMP_B_TO_SCC_B_2_DN")
	)
	(segment
		(start 234.772454 -113.246408)
		(end 227.089462 -101.41204)
		(width 0.1397)
		(layer "In5.Cu")
		(net "PCIE_COMP_B_TO_SCC_B_2_DN")
	)
	(segment
		(start 225.07067 -98.558858)
		(end 224.842324 -98.207322)
		(width 0.1397)
		(layer "In5.Cu")
		(net "PCIE_COMP_B_TO_SCC_B_2_DN")
	)
	(segment
		(start 224.842324 -98.207322)
		(end 224.883472 -98.014028)
		(width 0.1397)
		(layer "In5.Cu")
		(net "PCIE_COMP_B_TO_SCC_B_2_DN")
	)
	(segment
		(start 224.883472 -98.014028)
		(end 214.353902 -81.795112)
		(width 0.1397)
		(layer "In5.Cu")
		(net "PCIE_COMP_B_TO_SCC_B_2_DN")
	)
	(segment
		(start 225.450908 -99.144836)
		(end 225.492056 -98.951542)
		(width 0.1397)
		(layer "In5.Cu")
		(net "PCIE_COMP_B_TO_SCC_B_2_DN")
	)
	(arc
		(start 213.784942 -71.245984)
		(mid 213.654189 -71.300143)
		(end 213.60003 -71.430896)
		(width 0.1397)
		(layer "In5.Cu")
		(net "PCIE_COMP_B_TO_SCC_B_2_DN")
	)
	(arc
		(start 286.990536 -140.697458)
		(mid 286.886011 -140.445113)
		(end 286.633666 -140.340588)
		(width 0.1397)
		(layer "In5.Cu")
		(net "PCIE_COMP_B_TO_SCC_B_2_DN")
	)
	(arc
		(start 214.353902 -71.627492)
		(mid 214.242161 -71.357725)
		(end 213.972394 -71.245984)
		(width 0.1397)
		(layer "In5.Cu")
		(net "PCIE_COMP_B_TO_SCC_B_2_DN")
	)
	(arc
		(start 286.771334 -141.09446)
		(mid 286.926333 -141.030257)
		(end 286.990536 -140.875258)
		(width 0.1397)
		(layer "In5.Cu")
		(net "PCIE_COMP_B_TO_SCC_B_2_DN")
	)
	(segment
		(start 212.17255 -66.153792)
		(end 211.985098 -66.153792)
		(width 0.1397)
		(layer "In5.Cu")
		(net "PCIE_COMP_B_TO_SCC_B_1_DP")
	)
	(segment
		(start 285.633668 -141.848332)
		(end 276.875748 -141.848332)
		(width 0.1397)
		(layer "In5.Cu")
		(net "PCIE_COMP_B_TO_SCC_B_1_DP")
	)
	(segment
		(start 212.846158 -82.305652)
		(end 212.846158 -66.8274)
		(width 0.1397)
		(layer "In5.Cu")
		(net "PCIE_COMP_B_TO_SCC_B_1_DP")
	)
	(segment
		(start 286.282638 -142.675102)
		(end 286.282638 -142.497302)
		(width 0.1397)
		(layer "In5.Cu")
		(net "PCIE_COMP_B_TO_SCC_B_1_DP")
	)
	(segment
		(start 286.836612 -142.894304)
		(end 286.50184 -142.894304)
		(width 0.1397)
		(layer "In5.Cu")
		(net "PCIE_COMP_B_TO_SCC_B_1_DP")
	)
	(segment
		(start 276.875748 -141.848332)
		(end 233.01452 -113.365788)
		(width 0.1397)
		(layer "In5.Cu")
		(net "PCIE_COMP_B_TO_SCC_B_1_DP")
	)
	(segment
		(start 211.800186 -65.96888)
		(end 211.800186 -65.600072)
		(width 0.1397)
		(layer "In5.Cu")
		(net "PCIE_COMP_B_TO_SCC_B_1_DP")
	)
	(segment
		(start 233.01452 -113.365788)
		(end 212.846158 -82.305652)
		(width 0.1397)
		(layer "In5.Cu")
		(net "PCIE_COMP_B_TO_SCC_B_1_DP")
	)
	(arc
		(start 211.985098 -66.153792)
		(mid 211.854345 -66.099633)
		(end 211.800186 -65.96888)
		(width 0.1397)
		(layer "In5.Cu")
		(net "PCIE_COMP_B_TO_SCC_B_1_DP")
	)
	(arc
		(start 286.282638 -142.497302)
		(mid 286.092559 -142.038411)
		(end 285.633668 -141.848332)
		(width 0.1397)
		(layer "In5.Cu")
		(net "PCIE_COMP_B_TO_SCC_B_1_DP")
	)
	(arc
		(start 286.50184 -142.894304)
		(mid 286.346841 -142.830101)
		(end 286.282638 -142.675102)
		(width 0.1397)
		(layer "In5.Cu")
		(net "PCIE_COMP_B_TO_SCC_B_1_DP")
	)
	(arc
		(start 212.846158 -66.8274)
		(mid 212.648863 -66.351087)
		(end 212.17255 -66.153792)
		(width 0.1397)
		(layer "In5.Cu")
		(net "PCIE_COMP_B_TO_SCC_B_1_DP")
	)
	(segment
		(start 221.890082 -97.026984)
		(end 221.66199 -96.675448)
		(width 0.1397)
		(layer "In5.Cu")
		(net "PCIE_COMP_B_TO_SCC_B_1_DN")
	)
	(segment
		(start 222.920306 -98.356928)
		(end 222.69196 -98.005392)
		(width 0.1397)
		(layer "In5.Cu")
		(net "PCIE_COMP_B_TO_SCC_B_1_DN")
	)
	(segment
		(start 285.633668 -142.140432)
		(end 276.789134 -142.140432)
		(width 0.1397)
		(layer "In5.Cu")
		(net "PCIE_COMP_B_TO_SCC_B_1_DN")
	)
	(segment
		(start 222.498666 -97.964244)
		(end 222.270574 -97.612962)
		(width 0.1397)
		(layer "In5.Cu")
		(net "PCIE_COMP_B_TO_SCC_B_1_DN")
	)
	(segment
		(start 222.270574 -97.612962)
		(end 222.311722 -97.419668)
		(width 0.1397)
		(layer "In5.Cu")
		(net "PCIE_COMP_B_TO_SCC_B_1_DN")
	)
	(segment
		(start 212.17255 -66.445892)
		(end 211.985098 -66.445892)
		(width 0.1397)
		(layer "In5.Cu")
		(net "PCIE_COMP_B_TO_SCC_B_1_DN")
	)
	(segment
		(start 223.107504 -98.901758)
		(end 222.879158 -98.550222)
		(width 0.1397)
		(layer "In5.Cu")
		(net "PCIE_COMP_B_TO_SCC_B_1_DN")
	)
	(segment
		(start 221.474792 -96.130872)
		(end 221.281498 -96.089724)
		(width 0.1397)
		(layer "In5.Cu")
		(net "PCIE_COMP_B_TO_SCC_B_1_DN")
	)
	(segment
		(start 221.281498 -96.089724)
		(end 221.053152 -95.738188)
		(width 0.1397)
		(layer "In5.Cu")
		(net "PCIE_COMP_B_TO_SCC_B_1_DN")
	)
	(segment
		(start 232.803192 -113.577116)
		(end 223.300544 -98.942906)
		(width 0.1397)
		(layer "In5.Cu")
		(net "PCIE_COMP_B_TO_SCC_B_1_DN")
	)
	(segment
		(start 222.311722 -97.419668)
		(end 222.083376 -97.068132)
		(width 0.1397)
		(layer "In5.Cu")
		(net "PCIE_COMP_B_TO_SCC_B_1_DN")
	)
	(segment
		(start 222.69196 -98.005392)
		(end 222.498666 -97.964244)
		(width 0.1397)
		(layer "In5.Cu")
		(net "PCIE_COMP_B_TO_SCC_B_1_DN")
	)
	(segment
		(start 222.083376 -97.068132)
		(end 221.890082 -97.026984)
		(width 0.1397)
		(layer "In5.Cu")
		(net "PCIE_COMP_B_TO_SCC_B_1_DN")
	)
	(segment
		(start 221.66199 -96.675448)
		(end 221.702884 -96.482408)
		(width 0.1397)
		(layer "In5.Cu")
		(net "PCIE_COMP_B_TO_SCC_B_1_DN")
	)
	(segment
		(start 221.053152 -95.738188)
		(end 221.0943 -95.544894)
		(width 0.1397)
		(layer "In5.Cu")
		(net "PCIE_COMP_B_TO_SCC_B_1_DN")
	)
	(segment
		(start 222.879158 -98.550222)
		(end 222.920306 -98.356928)
		(width 0.1397)
		(layer "In5.Cu")
		(net "PCIE_COMP_B_TO_SCC_B_1_DN")
	)
	(segment
		(start 212.554058 -82.392266)
		(end 212.554058 -66.8274)
		(width 0.1397)
		(layer "In5.Cu")
		(net "PCIE_COMP_B_TO_SCC_B_1_DN")
	)
	(segment
		(start 211.800186 -66.630804)
		(end 211.800186 -66.999866)
		(width 0.1397)
		(layer "In5.Cu")
		(net "PCIE_COMP_B_TO_SCC_B_1_DN")
	)
	(segment
		(start 221.702884 -96.482408)
		(end 221.474792 -96.130872)
		(width 0.1397)
		(layer "In5.Cu")
		(net "PCIE_COMP_B_TO_SCC_B_1_DN")
	)
	(segment
		(start 285.990538 -142.675102)
		(end 285.990538 -142.497302)
		(width 0.1397)
		(layer "In5.Cu")
		(net "PCIE_COMP_B_TO_SCC_B_1_DN")
	)
	(segment
		(start 276.789134 -142.140432)
		(end 232.803192 -113.577116)
		(width 0.1397)
		(layer "In5.Cu")
		(net "PCIE_COMP_B_TO_SCC_B_1_DN")
	)
	(segment
		(start 223.300544 -98.942906)
		(end 223.107504 -98.901758)
		(width 0.1397)
		(layer "In5.Cu")
		(net "PCIE_COMP_B_TO_SCC_B_1_DN")
	)
	(segment
		(start 285.436564 -142.894304)
		(end 285.771336 -142.894304)
		(width 0.1397)
		(layer "In5.Cu")
		(net "PCIE_COMP_B_TO_SCC_B_1_DN")
	)
	(segment
		(start 221.0943 -95.544894)
		(end 212.554058 -82.392266)
		(width 0.1397)
		(layer "In5.Cu")
		(net "PCIE_COMP_B_TO_SCC_B_1_DN")
	)
	(arc
		(start 211.985098 -66.445892)
		(mid 211.854345 -66.500051)
		(end 211.800186 -66.630804)
		(width 0.1397)
		(layer "In5.Cu")
		(net "PCIE_COMP_B_TO_SCC_B_1_DN")
	)
	(arc
		(start 285.990538 -142.497302)
		(mid 285.886013 -142.244957)
		(end 285.633668 -142.140432)
		(width 0.1397)
		(layer "In5.Cu")
		(net "PCIE_COMP_B_TO_SCC_B_1_DN")
	)
	(arc
		(start 212.554058 -66.8274)
		(mid 212.442317 -66.557633)
		(end 212.17255 -66.445892)
		(width 0.1397)
		(layer "In5.Cu")
		(net "PCIE_COMP_B_TO_SCC_B_1_DN")
	)
	(arc
		(start 285.771336 -142.894304)
		(mid 285.926335 -142.830101)
		(end 285.990538 -142.675102)
		(width 0.1397)
		(layer "In5.Cu")
		(net "PCIE_COMP_B_TO_SCC_B_1_DN")
	)
	(segment
		(start 265.203432 -136.417304)
		(end 254.070104 -129.186686)
		(width 0.1397)
		(layer "In5.Cu")
		(net "PCIE_COMP_B_TO_SCC_B_0_DP")
	)
	(segment
		(start 210.000088 -70.768972)
		(end 210.000088 -70.39991)
		(width 0.1397)
		(layer "In5.Cu")
		(net "PCIE_COMP_B_TO_SCC_B_0_DP")
	)
	(segment
		(start 231.804464 -114.725196)
		(end 211.759546 -83.855306)
		(width 0.1397)
		(layer "In5.Cu")
		(net "PCIE_COMP_B_TO_SCC_B_0_DP")
	)
	(segment
		(start 287.282636 -144.4752)
		(end 287.282636 -144.2974)
		(width 0.1397)
		(layer "In5.Cu")
		(net "PCIE_COMP_B_TO_SCC_B_0_DP")
	)
	(segment
		(start 211.04606 -82.756756)
		(end 211.04606 -71.408544)
		(width 0.1397)
		(layer "In5.Cu")
		(net "PCIE_COMP_B_TO_SCC_B_0_DP")
	)
	(segment
		(start 210.5914 -70.953884)
		(end 210.185 -70.953884)
		(width 0.1397)
		(layer "In5.Cu")
		(net "PCIE_COMP_B_TO_SCC_B_0_DP")
	)
	(segment
		(start 287.83661 -144.694402)
		(end 287.501838 -144.694402)
		(width 0.1397)
		(layer "In5.Cu")
		(net "PCIE_COMP_B_TO_SCC_B_0_DP")
	)
	(segment
		(start 276.33676 -143.64843)
		(end 265.203432 -136.417304)
		(width 0.1397)
		(layer "In5.Cu")
		(net "PCIE_COMP_B_TO_SCC_B_0_DP")
	)
	(segment
		(start 286.633666 -143.64843)
		(end 276.33676 -143.64843)
		(width 0.1397)
		(layer "In5.Cu")
		(net "PCIE_COMP_B_TO_SCC_B_0_DP")
	)
	(segment
		(start 211.759546 -83.855306)
		(end 211.04606 -82.756756)
		(width 0.1397)
		(layer "In5.Cu")
		(net "PCIE_COMP_B_TO_SCC_B_0_DP")
	)
	(segment
		(start 254.070104 -129.186686)
		(end 231.804464 -114.725196)
		(width 0.1397)
		(layer "In5.Cu")
		(net "PCIE_COMP_B_TO_SCC_B_0_DP")
	)
	(arc
		(start 211.04606 -71.408544)
		(mid 210.912893 -71.087051)
		(end 210.5914 -70.953884)
		(width 0.1397)
		(layer "In5.Cu")
		(net "PCIE_COMP_B_TO_SCC_B_0_DP")
	)
	(arc
		(start 287.501838 -144.694402)
		(mid 287.346839 -144.630199)
		(end 287.282636 -144.4752)
		(width 0.1397)
		(layer "In5.Cu")
		(net "PCIE_COMP_B_TO_SCC_B_0_DP")
	)
	(arc
		(start 287.282636 -144.2974)
		(mid 287.092557 -143.838509)
		(end 286.633666 -143.64843)
		(width 0.1397)
		(layer "In5.Cu")
		(net "PCIE_COMP_B_TO_SCC_B_0_DP")
	)
	(arc
		(start 210.185 -70.953884)
		(mid 210.054247 -70.899725)
		(end 210.000088 -70.768972)
		(width 0.1397)
		(layer "In5.Cu")
		(net "PCIE_COMP_B_TO_SCC_B_0_DP")
	)
	(segment
		(start 214.263986 -88.505284)
		(end 214.30488 -88.31199)
		(width 0.1397)
		(layer "In5.Cu")
		(net "PCIE_COMP_B_TO_SCC_B_0_DN")
	)
	(segment
		(start 213.883494 -87.91956)
		(end 213.655148 -87.568024)
		(width 0.1397)
		(layer "In5.Cu")
		(net "PCIE_COMP_B_TO_SCC_B_0_DN")
	)
	(segment
		(start 286.990536 -144.4752)
		(end 286.990536 -144.2974)
		(width 0.1397)
		(layer "In5.Cu")
		(net "PCIE_COMP_B_TO_SCC_B_0_DN")
	)
	(segment
		(start 214.913718 -89.249504)
		(end 214.685372 -88.897968)
		(width 0.1397)
		(layer "In5.Cu")
		(net "PCIE_COMP_B_TO_SCC_B_0_DN")
	)
	(segment
		(start 276.250146 -143.94053)
		(end 253.910846 -129.431796)
		(width 0.1397)
		(layer "In5.Cu")
		(net "PCIE_COMP_B_TO_SCC_B_0_DN")
	)
	(segment
		(start 215.90254 -90.772488)
		(end 215.7095 -90.731594)
		(width 0.1397)
		(layer "In5.Cu")
		(net "PCIE_COMP_B_TO_SCC_B_0_DN")
	)
	(segment
		(start 215.293956 -89.835228)
		(end 215.100662 -89.79408)
		(width 0.1397)
		(layer "In5.Cu")
		(net "PCIE_COMP_B_TO_SCC_B_0_DN")
	)
	(segment
		(start 210.75396 -82.84337)
		(end 210.75396 -71.408544)
		(width 0.1397)
		(layer "In5.Cu")
		(net "PCIE_COMP_B_TO_SCC_B_0_DN")
	)
	(segment
		(start 214.685372 -88.897968)
		(end 214.492078 -88.85682)
		(width 0.1397)
		(layer "In5.Cu")
		(net "PCIE_COMP_B_TO_SCC_B_0_DN")
	)
	(segment
		(start 215.100662 -89.79408)
		(end 214.87257 -89.442798)
		(width 0.1397)
		(layer "In5.Cu")
		(net "PCIE_COMP_B_TO_SCC_B_0_DN")
	)
	(segment
		(start 214.076788 -87.960708)
		(end 213.883494 -87.91956)
		(width 0.1397)
		(layer "In5.Cu")
		(net "PCIE_COMP_B_TO_SCC_B_0_DN")
	)
	(segment
		(start 253.910846 -129.431796)
		(end 231.593136 -114.936524)
		(width 0.1397)
		(layer "In5.Cu")
		(net "PCIE_COMP_B_TO_SCC_B_0_DN")
	)
	(segment
		(start 215.481154 -90.380058)
		(end 215.522302 -90.186764)
		(width 0.1397)
		(layer "In5.Cu")
		(net "PCIE_COMP_B_TO_SCC_B_0_DN")
	)
	(segment
		(start 210.5914 -71.245984)
		(end 210.185 -71.245984)
		(width 0.1397)
		(layer "In5.Cu")
		(net "PCIE_COMP_B_TO_SCC_B_0_DN")
	)
	(segment
		(start 213.696296 -87.37473)
		(end 210.75396 -82.84337)
		(width 0.1397)
		(layer "In5.Cu")
		(net "PCIE_COMP_B_TO_SCC_B_0_DN")
	)
	(segment
		(start 214.492078 -88.85682)
		(end 214.263986 -88.505284)
		(width 0.1397)
		(layer "In5.Cu")
		(net "PCIE_COMP_B_TO_SCC_B_0_DN")
	)
	(segment
		(start 214.30488 -88.31199)
		(end 214.076788 -87.960708)
		(width 0.1397)
		(layer "In5.Cu")
		(net "PCIE_COMP_B_TO_SCC_B_0_DN")
	)
	(segment
		(start 286.436562 -144.694402)
		(end 286.771334 -144.694402)
		(width 0.1397)
		(layer "In5.Cu")
		(net "PCIE_COMP_B_TO_SCC_B_0_DN")
	)
	(segment
		(start 215.522302 -90.186764)
		(end 215.293956 -89.835228)
		(width 0.1397)
		(layer "In5.Cu")
		(net "PCIE_COMP_B_TO_SCC_B_0_DN")
	)
	(segment
		(start 215.7095 -90.731594)
		(end 215.481154 -90.380058)
		(width 0.1397)
		(layer "In5.Cu")
		(net "PCIE_COMP_B_TO_SCC_B_0_DN")
	)
	(segment
		(start 286.633666 -143.94053)
		(end 276.250146 -143.94053)
		(width 0.1397)
		(layer "In5.Cu")
		(net "PCIE_COMP_B_TO_SCC_B_0_DN")
	)
	(segment
		(start 231.593136 -114.936524)
		(end 215.90254 -90.772488)
		(width 0.1397)
		(layer "In5.Cu")
		(net "PCIE_COMP_B_TO_SCC_B_0_DN")
	)
	(segment
		(start 213.655148 -87.568024)
		(end 213.696296 -87.37473)
		(width 0.1397)
		(layer "In5.Cu")
		(net "PCIE_COMP_B_TO_SCC_B_0_DN")
	)
	(segment
		(start 210.000088 -71.430896)
		(end 210.000088 -71.799958)
		(width 0.1397)
		(layer "In5.Cu")
		(net "PCIE_COMP_B_TO_SCC_B_0_DN")
	)
	(segment
		(start 214.87257 -89.442798)
		(end 214.913718 -89.249504)
		(width 0.1397)
		(layer "In5.Cu")
		(net "PCIE_COMP_B_TO_SCC_B_0_DN")
	)
	(arc
		(start 286.990536 -144.2974)
		(mid 286.886011 -144.045055)
		(end 286.633666 -143.94053)
		(width 0.1397)
		(layer "In5.Cu")
		(net "PCIE_COMP_B_TO_SCC_B_0_DN")
	)
	(arc
		(start 286.771334 -144.694402)
		(mid 286.926333 -144.630199)
		(end 286.990536 -144.4752)
		(width 0.1397)
		(layer "In5.Cu")
		(net "PCIE_COMP_B_TO_SCC_B_0_DN")
	)
	(arc
		(start 210.75396 -71.408544)
		(mid 210.706347 -71.293597)
		(end 210.5914 -71.245984)
		(width 0.1397)
		(layer "In5.Cu")
		(net "PCIE_COMP_B_TO_SCC_B_0_DN")
	)
	(arc
		(start 210.185 -71.245984)
		(mid 210.054247 -71.300143)
		(end 210.000088 -71.430896)
		(width 0.1397)
		(layer "In5.Cu")
		(net "PCIE_COMP_B_TO_SCC_B_0_DN")
	)
	(via
		(at 21.971 -263.779)
		(size 0.6604)
		(drill 0.3302)
		(layers "F.Cu" "B.Cu")
		(net "P5V_HDD0")
	)
	(segment
		(start 434.494686 -116.257578)
		(end 434.494686 -115.256818)
		(width 0.254)
		(layer "F.Cu")
		(net "P5V_B_4_VREG")
	)
	(segment
		(start 434.494686 -115.256818)
		(end 434.644546 -115.106958)
		(width 0.254)
		(layer "F.Cu")
		(net "P5V_B_4_VREG")
	)
	(via
		(at 434.644546 -115.106958)
		(size 0.6604)
		(drill 0.3048)
		(layers "F.Cu" "B.Cu")
		(net "P5V_B_4_VREG")
	)
	(segment
		(start 433.422806 -115.106958)
		(end 434.644546 -115.106958)
		(width 0.254)
		(layer "B.Cu")
		(net "P5V_B_4_VREG")
	)
	(segment
		(start 433.415186 -115.114578)
		(end 433.422806 -115.106958)
		(width 0.254)
		(layer "B.Cu")
		(net "P5V_B_4_VREG")
	)
	(segment
		(start 434.65115 -115.100354)
		(end 434.644546 -115.106958)
		(width 0.254)
		(layer "B.Cu")
		(net "P5V_B_4_VREG")
	)
	(segment
		(start 435.852062 -115.100354)
		(end 434.65115 -115.100354)
		(width 0.254)
		(layer "B.Cu")
		(net "P5V_B_4_VREG")
	)
	(via
		(at 442.940186 -120.702578)
		(size 0.6096)
		(drill 0.3048)
		(layers "F.Cu" "B.Cu")
		(net "P5V_B_4_VFB_R")
	)
	(segment
		(start 443.133988 -119.309642)
		(end 443.133988 -120.508776)
		(width 0.254)
		(layer "B.Cu")
		(net "P5V_B_4_VFB_R")
	)
	(segment
		(start 443.133988 -119.309642)
		(end 442.45657 -119.309642)
		(width 0.254)
		(layer "B.Cu")
		(net "P5V_B_4_VFB_R")
	)
	(segment
		(start 441.987686 -120.702578)
		(end 442.940186 -120.702578)
		(width 0.254)
		(layer "B.Cu")
		(net "P5V_B_4_VFB_R")
	)
	(segment
		(start 441.606686 -120.321578)
		(end 441.987686 -120.702578)
		(width 0.254)
		(layer "B.Cu")
		(net "P5V_B_4_VFB_R")
	)
	(segment
		(start 443.133988 -120.508776)
		(end 442.940186 -120.702578)
		(width 0.254)
		(layer "B.Cu")
		(net "P5V_B_4_VFB_R")
	)
	(segment
		(start 442.45657 -119.309642)
		(end 442.390784 -119.375428)
		(width 0.254)
		(layer "B.Cu")
		(net "P5V_B_4_VFB_R")
	)
	(segment
		(start 442.390784 -119.375428)
		(end 441.616084 -119.375428)
		(width 0.254)
		(layer "B.Cu")
		(net "P5V_B_4_VFB_R")
	)
	(via
		(at 445.64935 -121.492264)
		(size 0.6096)
		(drill 0.3048)
		(layers "F.Cu" "B.Cu")
		(net "P5V_B_4_VFB")
	)
	(segment
		(start 446.676526 -121.492264)
		(end 445.64935 -121.492264)
		(width 0.254)
		(layer "B.Cu")
		(net "P5V_B_4_VFB")
	)
	(segment
		(start 440.727084 -119.375428)
		(end 440.727084 -120.31218)
		(width 0.254)
		(layer "B.Cu")
		(net "P5V_B_4_VFB")
	)
	(segment
		(start 440.134248 -118.782592)
		(end 440.727084 -119.375428)
		(width 0.254)
		(layer "B.Cu")
		(net "P5V_B_4_VFB")
	)
	(segment
		(start 440.750706 -119.351806)
		(end 440.727084 -119.375428)
		(width 0.254)
		(layer "B.Cu")
		(net "P5V_B_4_VFB")
	)
	(segment
		(start 445.64935 -121.492264)
		(end 441.697872 -121.492264)
		(width 0.254)
		(layer "B.Cu")
		(net "P5V_B_4_VFB")
	)
	(segment
		(start 439.302398 -118.782592)
		(end 440.134248 -118.782592)
		(width 0.254)
		(layer "B.Cu")
		(net "P5V_B_4_VFB")
	)
	(segment
		(start 440.717686 -120.512078)
		(end 440.717686 -120.321578)
		(width 0.254)
		(layer "B.Cu")
		(net "P5V_B_4_VFB")
	)
	(segment
		(start 447.573908 -120.594882)
		(end 446.676526 -121.492264)
		(width 0.254)
		(layer "B.Cu")
		(net "P5V_B_4_VFB")
	)
	(segment
		(start 440.750706 -117.10035)
		(end 440.750706 -119.351806)
		(width 0.254)
		(layer "B.Cu")
		(net "P5V_B_4_VFB")
	)
	(segment
		(start 440.727084 -120.31218)
		(end 440.717686 -120.321578)
		(width 0.254)
		(layer "B.Cu")
		(net "P5V_B_4_VFB")
	)
	(segment
		(start 441.697872 -121.492264)
		(end 440.717686 -120.512078)
		(width 0.254)
		(layer "B.Cu")
		(net "P5V_B_4_VFB")
	)
	(segment
		(start 440.908186 -113.234978)
		(end 442.965586 -113.234978)
		(width 0.508)
		(layer "F.Cu")
		(net "P5V_B_4_VBST_RC")
	)
	(segment
		(start 444.068708 -112.710976)
		(end 443.544706 -113.234978)
		(width 0.508)
		(layer "F.Cu")
		(net "P5V_B_4_VBST_RC")
	)
	(segment
		(start 443.544706 -113.234978)
		(end 442.965586 -113.234978)
		(width 0.508)
		(layer "F.Cu")
		(net "P5V_B_4_VBST_RC")
	)
	(via
		(at 442.965586 -113.234978)
		(size 0.6604)
		(drill 0.3302)
		(layers "F.Cu" "B.Cu")
		(net "P5V_B_4_VBST_RC")
	)
	(segment
		(start 441.943236 -115.794028)
		(end 442.615574 -115.794028)
		(width 0.508)
		(layer "F.Cu")
		(net "P5V_B_4_VBST")
	)
	(segment
		(start 442.615574 -115.794028)
		(end 442.660532 -115.838986)
		(width 0.508)
		(layer "F.Cu")
		(net "P5V_B_4_VBST")
	)
	(segment
		(start 440.908186 -114.758978)
		(end 441.943236 -115.794028)
		(width 0.508)
		(layer "F.Cu")
		(net "P5V_B_4_VBST")
	)
	(via
		(at 442.660532 -115.838986)
		(size 0.6604)
		(drill 0.3048)
		(layers "F.Cu" "B.Cu")
		(net "P5V_B_4_VBST")
	)
	(segment
		(start 440.750706 -115.600226)
		(end 442.3664 -115.600226)
		(width 0.3048)
		(layer "B.Cu")
		(net "P5V_B_4_VBST")
	)
	(segment
		(start 442.3664 -115.600226)
		(end 442.60516 -115.838986)
		(width 0.3048)
		(layer "B.Cu")
		(net "P5V_B_4_VBST")
	)
	(segment
		(start 442.60516 -115.838986)
		(end 442.660532 -115.838986)
		(width 0.3048)
		(layer "B.Cu")
		(net "P5V_B_4_VBST")
	)
	(segment
		(start 434.824886 -119.432578)
		(end 434.824886 -118.924578)
		(width 0.254)
		(layer "F.Cu")
		(net "P5V_B_4_TRIP")
	)
	(segment
		(start 435.362604 -118.38686)
		(end 435.362604 -117.904514)
		(width 0.254)
		(layer "F.Cu")
		(net "P5V_B_4_TRIP")
	)
	(segment
		(start 434.824886 -119.432578)
		(end 434.824886 -120.651778)
		(width 0.254)
		(layer "F.Cu")
		(net "P5V_B_4_TRIP")
	)
	(segment
		(start 434.824886 -118.924578)
		(end 435.362604 -118.38686)
		(width 0.254)
		(layer "F.Cu")
		(net "P5V_B_4_TRIP")
	)
	(via
		(at 434.824886 -119.432578)
		(size 0.6604)
		(drill 0.3302)
		(layers "F.Cu" "B.Cu")
		(net "P5V_B_4_TRIP")
	)
	(via
		(at 435.362604 -117.904514)
		(size 0.5588)
		(drill 0.3048)
		(layers "F.Cu" "B.Cu")
		(net "P5V_B_4_TRIP")
	)
	(segment
		(start 435.015386 -117.557296)
		(end 435.362604 -117.904514)
		(width 0.254)
		(layer "B.Cu")
		(net "P5V_B_4_TRIP")
	)
	(segment
		(start 435.243478 -116.600224)
		(end 435.015386 -116.828316)
		(width 0.254)
		(layer "B.Cu")
		(net "P5V_B_4_TRIP")
	)
	(segment
		(start 435.852062 -116.600224)
		(end 435.243478 -116.600224)
		(width 0.254)
		(layer "B.Cu")
		(net "P5V_B_4_TRIP")
	)
	(segment
		(start 435.015386 -116.828316)
		(end 435.015386 -117.557296)
		(width 0.254)
		(layer "B.Cu")
		(net "P5V_B_4_TRIP")
	)
	(segment
		(start 442.813186 -111.266478)
		(end 440.78906 -111.266478)
		(width 0.508)
		(layer "F.Cu")
		(net "P5V_B_4_SNB")
	)
	(segment
		(start 444.061596 -111.434118)
		(end 443.893956 -111.266478)
		(width 0.508)
		(layer "F.Cu")
		(net "P5V_B_4_SNB")
	)
	(segment
		(start 443.893956 -111.266478)
		(end 442.813186 -111.266478)
		(width 0.508)
		(layer "F.Cu")
		(net "P5V_B_4_SNB")
	)
	(via
		(at 442.813186 -111.266478)
		(size 0.6604)
		(drill 0.3302)
		(layers "F.Cu" "B.Cu")
		(net "P5V_B_4_SNB")
	)
	(segment
		(start 437.463184 -118.400576)
		(end 437.920384 -117.943376)
		(width 0.254)
		(layer "F.Cu")
		(net "P5V_B_4_ROVP")
	)
	(segment
		(start 437.463184 -118.748048)
		(end 437.463184 -118.400576)
		(width 0.254)
		(layer "F.Cu")
		(net "P5V_B_4_ROVP")
	)
	(via
		(at 443.727586 -116.613178)
		(size 0.6604)
		(drill 0.3048)
		(layers "F.Cu" "B.Cu")
		(net "P5V_B_4_ROVP")
	)
	(via
		(at 437.920384 -117.943376)
		(size 0.5588)
		(drill 0.3048)
		(layers "F.Cu" "B.Cu")
		(net "P5V_B_4_ROVP")
	)
	(segment
		(start 442.7093 -114.803428)
		(end 443.727586 -115.821714)
		(width 0.254)
		(layer "B.Cu")
		(net "P5V_B_4_ROVP")
	)
	(segment
		(start 441.433458 -115.100354)
		(end 441.730384 -114.803428)
		(width 0.254)
		(layer "B.Cu")
		(net "P5V_B_4_ROVP")
	)
	(segment
		(start 441.730384 -114.803428)
		(end 442.7093 -114.803428)
		(width 0.254)
		(layer "B.Cu")
		(net "P5V_B_4_ROVP")
	)
	(segment
		(start 440.750706 -115.100354)
		(end 441.433458 -115.100354)
		(width 0.254)
		(layer "B.Cu")
		(net "P5V_B_4_ROVP")
	)
	(segment
		(start 443.727586 -115.821714)
		(end 443.727586 -116.613178)
		(width 0.254)
		(layer "B.Cu")
		(net "P5V_B_4_ROVP")
	)
	(segment
		(start 441.228988 -117.943376)
		(end 442.559186 -116.613178)
		(width 0.254)
		(layer "In2.Cu")
		(net "P5V_B_4_ROVP")
	)
	(segment
		(start 437.920384 -117.943376)
		(end 441.228988 -117.943376)
		(width 0.254)
		(layer "In2.Cu")
		(net "P5V_B_4_ROVP")
	)
	(segment
		(start 442.559186 -116.613178)
		(end 443.727586 -116.613178)
		(width 0.254)
		(layer "In2.Cu")
		(net "P5V_B_4_ROVP")
	)
	(segment
		(start 436.412386 -118.734078)
		(end 436.412386 -117.908578)
		(width 0.254)
		(layer "F.Cu")
		(net "P5V_B_4_RF")
	)
	(segment
		(start 436.336186 -116.867178)
		(end 436.336186 -117.832378)
		(width 0.254)
		(layer "F.Cu")
		(net "P5V_B_4_RF")
	)
	(segment
		(start 436.412386 -117.908578)
		(end 436.336186 -117.832378)
		(width 0.254)
		(layer "F.Cu")
		(net "P5V_B_4_RF")
	)
	(segment
		(start 435.383686 -116.257578)
		(end 435.726586 -116.257578)
		(width 0.254)
		(layer "F.Cu")
		(net "P5V_B_4_RF")
	)
	(segment
		(start 435.726586 -116.257578)
		(end 436.336186 -116.867178)
		(width 0.254)
		(layer "F.Cu")
		(net "P5V_B_4_RF")
	)
	(via
		(at 436.336186 -116.867178)
		(size 0.6604)
		(drill 0.3302)
		(layers "F.Cu" "B.Cu")
		(net "P5V_B_4_RF")
	)
	(via
		(at 436.336186 -117.832378)
		(size 0.5588)
		(drill 0.3048)
		(layers "F.Cu" "B.Cu")
		(net "P5V_B_4_RF")
	)
	(segment
		(start 435.852062 -117.10035)
		(end 435.852062 -117.348254)
		(width 0.254)
		(layer "B.Cu")
		(net "P5V_B_4_RF")
	)
	(segment
		(start 435.852062 -117.348254)
		(end 436.336186 -117.832378)
		(width 0.254)
		(layer "B.Cu")
		(net "P5V_B_4_RF")
	)
	(segment
		(start 442.863986 -117.451378)
		(end 443.702186 -118.289578)
		(width 0.254)
		(layer "F.Cu")
		(net "P5V_B_4_PGOOD")
	)
	(segment
		(start 439.826908 -117.379496)
		(end 440.72048 -117.379496)
		(width 0.254)
		(layer "F.Cu")
		(net "P5V_B_4_PGOOD")
	)
	(segment
		(start 445.226186 -120.194578)
		(end 444.108586 -120.194578)
		(width 0.254)
		(layer "F.Cu")
		(net "P5V_B_4_PGOOD")
	)
	(segment
		(start 443.704472 -119.790464)
		(end 443.704472 -119.184928)
		(width 0.254)
		(layer "F.Cu")
		(net "P5V_B_4_PGOOD")
	)
	(segment
		(start 443.704472 -118.291864)
		(end 443.704472 -119.184928)
		(width 0.254)
		(layer "F.Cu")
		(net "P5V_B_4_PGOOD")
	)
	(segment
		(start 446.242186 -121.210578)
		(end 445.226186 -120.194578)
		(width 0.254)
		(layer "F.Cu")
		(net "P5V_B_4_PGOOD")
	)
	(segment
		(start 441.959746 -117.451378)
		(end 442.863986 -117.451378)
		(width 0.254)
		(layer "F.Cu")
		(net "P5V_B_4_PGOOD")
	)
	(segment
		(start 443.702186 -118.289578)
		(end 443.704472 -118.291864)
		(width 0.254)
		(layer "F.Cu")
		(net "P5V_B_4_PGOOD")
	)
	(segment
		(start 444.108586 -120.194578)
		(end 443.704472 -119.790464)
		(width 0.254)
		(layer "F.Cu")
		(net "P5V_B_4_PGOOD")
	)
	(segment
		(start 438.592722 -118.613682)
		(end 439.826908 -117.379496)
		(width 0.254)
		(layer "F.Cu")
		(net "P5V_B_4_PGOOD")
	)
	(segment
		(start 440.72048 -117.379496)
		(end 441.376054 -118.03507)
		(width 0.254)
		(layer "F.Cu")
		(net "P5V_B_4_PGOOD")
	)
	(segment
		(start 441.376054 -118.03507)
		(end 441.959746 -117.451378)
		(width 0.254)
		(layer "F.Cu")
		(net "P5V_B_4_PGOOD")
	)
	(via
		(at 443.702186 -118.289578)
		(size 0.5588)
		(drill 0.3048)
		(layers "F.Cu" "B.Cu")
		(net "P5V_B_4_PGOOD")
	)
	(segment
		(start 440.750706 -116.100352)
		(end 441.554108 -116.100352)
		(width 0.254)
		(layer "B.Cu")
		(net "P5V_B_4_PGOOD")
	)
	(segment
		(start 443.702186 -118.24843)
		(end 443.702186 -118.289578)
		(width 0.254)
		(layer "B.Cu")
		(net "P5V_B_4_PGOOD")
	)
	(segment
		(start 441.554108 -116.100352)
		(end 443.702186 -118.24843)
		(width 0.254)
		(layer "B.Cu")
		(net "P5V_B_4_PGOOD")
	)
	(segment
		(start 438.368186 -121.845578)
		(end 434.659786 -121.845578)
		(width 0.254)
		(layer "F.Cu")
		(net "P5V_B_4_MODE")
	)
	(segment
		(start 433.897786 -118.013226)
		(end 434.211984 -117.699028)
		(width 0.254)
		(layer "F.Cu")
		(net "P5V_B_4_MODE")
	)
	(segment
		(start 439.481722 -119.645938)
		(end 439.481722 -118.613682)
		(width 0.254)
		(layer "F.Cu")
		(net "P5V_B_4_MODE")
	)
	(segment
		(start 439.481214 -119.646446)
		(end 439.481722 -119.645938)
		(width 0.254)
		(layer "F.Cu")
		(net "P5V_B_4_MODE")
	)
	(segment
		(start 434.659786 -121.845578)
		(end 433.897786 -121.083578)
		(width 0.254)
		(layer "F.Cu")
		(net "P5V_B_4_MODE")
	)
	(segment
		(start 438.96534 -121.248424)
		(end 438.96534 -120.401588)
		(width 0.254)
		(layer "F.Cu")
		(net "P5V_B_4_MODE")
	)
	(segment
		(start 439.481214 -119.885714)
		(end 439.481214 -119.646446)
		(width 0.254)
		(layer "F.Cu")
		(net "P5V_B_4_MODE")
	)
	(segment
		(start 438.622186 -121.591578)
		(end 438.368186 -121.845578)
		(width 0.254)
		(layer "F.Cu")
		(net "P5V_B_4_MODE")
	)
	(segment
		(start 438.96534 -120.401588)
		(end 439.481214 -119.885714)
		(width 0.254)
		(layer "F.Cu")
		(net "P5V_B_4_MODE")
	)
	(segment
		(start 438.622186 -121.591578)
		(end 438.96534 -121.248424)
		(width 0.254)
		(layer "F.Cu")
		(net "P5V_B_4_MODE")
	)
	(segment
		(start 433.897786 -121.083578)
		(end 433.897786 -118.013226)
		(width 0.254)
		(layer "F.Cu")
		(net "P5V_B_4_MODE")
	)
	(via
		(at 438.622186 -121.591578)
		(size 0.6604)
		(drill 0.3302)
		(layers "F.Cu" "B.Cu")
		(net "P5V_B_4_MODE")
	)
	(via
		(at 434.211984 -117.699028)
		(size 0.5588)
		(drill 0.3048)
		(layers "F.Cu" "B.Cu")
		(net "P5V_B_4_MODE")
	)
	(segment
		(start 434.211984 -116.95938)
		(end 434.211984 -117.699028)
		(width 0.254)
		(layer "B.Cu")
		(net "P5V_B_4_MODE")
	)
	(segment
		(start 435.852062 -116.100352)
		(end 435.071012 -116.100352)
		(width 0.254)
		(layer "B.Cu")
		(net "P5V_B_4_MODE")
	)
	(segment
		(start 435.071012 -116.100352)
		(end 434.211984 -116.95938)
		(width 0.254)
		(layer "B.Cu")
		(net "P5V_B_4_MODE")
	)
	(via
		(at 448.782186 -121.845578)
		(size 0.6096)
		(drill 0.3048)
		(layers "F.Cu" "B.Cu")
		(net "P5V_B_4_LL_R")
	)
	(segment
		(start 444.950596 -109.34954)
		(end 444.950596 -110.401608)
		(width 0.508)
		(layer "F.Cu")
		(net "P5V_B_4_LL")
	)
	(segment
		(start 444.957708 -112.710976)
		(end 444.957708 -113.9063)
		(width 0.6096)
		(layer "F.Cu")
		(net "P5V_B_4_LL")
	)
	(segment
		(start 444.957708 -113.9063)
		(end 445.505586 -114.454178)
		(width 0.6096)
		(layer "F.Cu")
		(net "P5V_B_4_LL")
	)
	(segment
		(start 444.950596 -110.401608)
		(end 444.950596 -111.434118)
		(width 0.508)
		(layer "F.Cu")
		(net "P5V_B_4_LL")
	)
	(via
		(at 444.950596 -109.34954)
		(size 0.7112)
		(drill 0.4064)
		(layers "F.Cu" "B.Cu")
		(net "P5V_B_4_LL")
	)
	(via
		(at 444.950596 -110.401608)
		(size 0.6604)
		(drill 0.3302)
		(layers "F.Cu" "B.Cu")
		(net "P5V_B_4_LL")
	)
	(via
		(at 445.505586 -114.454178)
		(size 0.7112)
		(drill 0.4064)
		(layers "F.Cu" "B.Cu")
		(net "P5V_B_4_LL")
	)
	(segment
		(start 446.845436 -111.780828)
		(end 447.632328 -112.56772)
		(width 0.508)
		(layer "B.Cu")
		(net "P5V_B_4_LL")
	)
	(segment
		(start 444.26759 -111.780828)
		(end 446.845436 -111.780828)
		(width 0.508)
		(layer "B.Cu")
		(net "P5V_B_4_LL")
	)
	(segment
		(start 447.632328 -112.56772)
		(end 447.632328 -118.340124)
		(width 0.508)
		(layer "B.Cu")
		(net "P5V_B_4_LL")
	)
	(segment
		(start 442.190124 -118.170706)
		(end 442.178186 -118.182644)
		(width 0.254)
		(layer "F.Cu")
		(net "P5V_B_4_EN_R")
	)
	(segment
		(start 442.495686 -121.591578)
		(end 441.416186 -121.591578)
		(width 0.254)
		(layer "F.Cu")
		(net "P5V_B_4_EN_R")
	)
	(segment
		(start 442.686186 -121.401078)
		(end 442.495686 -121.591578)
		(width 0.254)
		(layer "F.Cu")
		(net "P5V_B_4_EN_R")
	)
	(segment
		(start 441.606686 -120.321578)
		(end 441.606686 -120.702578)
		(width 0.254)
		(layer "F.Cu")
		(net "P5V_B_4_EN_R")
	)
	(segment
		(start 442.178186 -119.178578)
		(end 441.606686 -119.750078)
		(width 0.254)
		(layer "F.Cu")
		(net "P5V_B_4_EN_R")
	)
	(segment
		(start 441.416186 -120.893078)
		(end 441.416186 -121.591578)
		(width 0.254)
		(layer "F.Cu")
		(net "P5V_B_4_EN_R")
	)
	(segment
		(start 443.625986 -121.401078)
		(end 442.686186 -121.401078)
		(width 0.254)
		(layer "F.Cu")
		(net "P5V_B_4_EN_R")
	)
	(segment
		(start 441.606686 -119.750078)
		(end 441.606686 -120.321578)
		(width 0.254)
		(layer "F.Cu")
		(net "P5V_B_4_EN_R")
	)
	(segment
		(start 442.178186 -118.182644)
		(end 442.178186 -119.178578)
		(width 0.254)
		(layer "F.Cu")
		(net "P5V_B_4_EN_R")
	)
	(segment
		(start 441.606686 -120.702578)
		(end 441.416186 -120.893078)
		(width 0.254)
		(layer "F.Cu")
		(net "P5V_B_4_EN_R")
	)
	(segment
		(start 443.714886 -121.312178)
		(end 443.625986 -121.401078)
		(width 0.254)
		(layer "F.Cu")
		(net "P5V_B_4_EN_R")
	)
	(via
		(at 442.190124 -118.170706)
		(size 0.5588)
		(drill 0.3048)
		(layers "F.Cu" "B.Cu")
		(net "P5V_B_4_EN_R")
	)
	(via
		(at 441.416186 -121.591578)
		(size 0.6604)
		(drill 0.3302)
		(layers "F.Cu" "B.Cu")
		(net "P5V_B_4_EN_R")
	)
	(segment
		(start 441.730384 -116.987828)
		(end 441.730384 -117.710966)
		(width 0.254)
		(layer "B.Cu")
		(net "P5V_B_4_EN_R")
	)
	(segment
		(start 440.750706 -116.600224)
		(end 441.34278 -116.600224)
		(width 0.254)
		(layer "B.Cu")
		(net "P5V_B_4_EN_R")
	)
	(segment
		(start 441.730384 -117.710966)
		(end 442.190124 -118.170706)
		(width 0.254)
		(layer "B.Cu")
		(net "P5V_B_4_EN_R")
	)
	(segment
		(start 441.34278 -116.600224)
		(end 441.730384 -116.987828)
		(width 0.254)
		(layer "B.Cu")
		(net "P5V_B_4_EN_R")
	)
	(via
		(at 445.810386 -119.309642)
		(size 0.6604)
		(drill 0.3048)
		(layers "F.Cu" "B.Cu")
		(net "P5V_B_4_CC")
	)
	(via
		(at 466.464904 -118.626636)
		(size 0.5588)
		(drill 0.3048)
		(layers "F.Cu" "B.Cu")
		(net "P5V_B_4_CC")
	)
	(segment
		(start 466.505798 -118.585742)
		(end 466.464904 -118.626636)
		(width 0.254)
		(layer "B.Cu")
		(net "P5V_B_4_CC")
	)
	(segment
		(start 444.657988 -119.309642)
		(end 445.810386 -119.309642)
		(width 0.254)
		(layer "B.Cu")
		(net "P5V_B_4_CC")
	)
	(segment
		(start 466.505798 -118.002558)
		(end 466.505798 -118.585742)
		(width 0.254)
		(layer "B.Cu")
		(net "P5V_B_4_CC")
	)
	(segment
		(start 445.810386 -119.309642)
		(end 465.781898 -119.309642)
		(width 0.254)
		(layer "In5.Cu")
		(net "P5V_B_4_CC")
	)
	(segment
		(start 465.781898 -119.309642)
		(end 466.464904 -118.626636)
		(width 0.254)
		(layer "In5.Cu")
		(net "P5V_B_4_CC")
	)
	(segment
		(start 441.96 -100.859844)
		(end 441.963556 -100.8634)
		(width 0.508)
		(layer "F.Cu")
		(net "P5V_B_4")
	)
	(segment
		(start 262.46201 -228.097588)
		(end 262.46201 -227.160074)
		(width 0.508)
		(layer "F.Cu")
		(net "P5V_B_4")
	)
	(segment
		(start 265.753088 -240.011712)
		(end 265.753088 -231.388666)
		(width 0.508)
		(layer "F.Cu")
		(net "P5V_B_4")
	)
	(segment
		(start 440.69 -99.949)
		(end 440.69 -100.859844)
		(width 0.508)
		(layer "F.Cu")
		(net "P5V_B_4")
	)
	(segment
		(start 448.377564 -114.7572)
		(end 457.0984 -114.7572)
		(width 0.508)
		(layer "F.Cu")
		(net "P5V_B_4")
	)
	(segment
		(start 444.593472 -118.541292)
		(end 447.893186 -115.241578)
		(width 0.508)
		(layer "F.Cu")
		(net "P5V_B_4")
	)
	(segment
		(start 265.753088 -231.388666)
		(end 262.46201 -228.097588)
		(width 0.508)
		(layer "F.Cu")
		(net "P5V_B_4")
	)
	(segment
		(start 410.464 -100.859844)
		(end 410.467556 -100.8634)
		(width 0.508)
		(layer "F.Cu")
		(net "P5V_B_4")
	)
	(segment
		(start 409.194 -100.859844)
		(end 409.197556 -100.8634)
		(width 0.508)
		(layer "F.Cu")
		(net "P5V_B_4")
	)
	(segment
		(start 444.593472 -119.184928)
		(end 444.593472 -118.541292)
		(width 0.508)
		(layer "F.Cu")
		(net "P5V_B_4")
	)
	(segment
		(start 409.194 -99.949)
		(end 409.194 -100.859844)
		(width 0.508)
		(layer "F.Cu")
		(net "P5V_B_4")
	)
	(segment
		(start 440.69 -100.859844)
		(end 440.693556 -100.8634)
		(width 0.508)
		(layer "F.Cu")
		(net "P5V_B_4")
	)
	(segment
		(start 465.3534 -101.063044)
		(end 465.356956 -101.0666)
		(width 0.508)
		(layer "F.Cu")
		(net "P5V_B_4")
	)
	(segment
		(start 441.96 -99.949)
		(end 441.96 -100.859844)
		(width 0.508)
		(layer "F.Cu")
		(net "P5V_B_4")
	)
	(segment
		(start 410.464 -99.949)
		(end 410.464 -100.859844)
		(width 0.508)
		(layer "F.Cu")
		(net "P5V_B_4")
	)
	(segment
		(start 465.3534 -100.1522)
		(end 465.3534 -101.063044)
		(width 0.508)
		(layer "F.Cu")
		(net "P5V_B_4")
	)
	(segment
		(start 464.0834 -101.063044)
		(end 464.086956 -101.0666)
		(width 0.508)
		(layer "F.Cu")
		(net "P5V_B_4")
	)
	(segment
		(start 447.893186 -115.241578)
		(end 448.377564 -114.7572)
		(width 0.508)
		(layer "F.Cu")
		(net "P5V_B_4")
	)
	(segment
		(start 464.0834 -100.1522)
		(end 464.0834 -101.063044)
		(width 0.508)
		(layer "F.Cu")
		(net "P5V_B_4")
	)
	(via
		(at 393.446 -19.431)
		(size 0.5588)
		(drill 0.3048)
		(layers "F.Cu" "B.Cu")
		(net "P5V_B_4")
	)
	(via
		(at 464.2104 -246.5578)
		(size 0.5588)
		(drill 0.3048)
		(layers "F.Cu" "B.Cu")
		(net "P5V_B_4")
	)
	(via
		(at 466.969602 -115.50015)
		(size 0.7112)
		(drill 0.4064)
		(layers "F.Cu" "B.Cu")
		(net "P5V_B_4")
	)
	(via
		(at 477.647 -22.098)
		(size 0.5588)
		(drill 0.3048)
		(layers "F.Cu" "B.Cu")
		(net "P5V_B_4")
	)
	(via
		(at 440.693556 -100.8634)
		(size 0.5588)
		(drill 0.3048)
		(layers "F.Cu" "B.Cu")
		(net "P5V_B_4")
	)
	(via
		(at 462.092802 -114.23015)
		(size 0.7112)
		(drill 0.4064)
		(layers "F.Cu" "B.Cu")
		(net "P5V_B_4")
	)
	(via
		(at 457.0984 -114.7572)
		(size 0.7112)
		(drill 0.4064)
		(layers "F.Cu" "B.Cu")
		(net "P5V_B_4")
	)
	(via
		(at 332.613 -19.431)
		(size 0.5588)
		(drill 0.3048)
		(layers "F.Cu" "B.Cu")
		(net "P5V_B_4")
	)
	(via
		(at 459.71841 -113.53419)
		(size 0.7112)
		(drill 0.4064)
		(layers "F.Cu" "B.Cu")
		(net "P5V_B_4")
	)
	(via
		(at 475.107 -137.287)
		(size 0.5588)
		(drill 0.3048)
		(layers "F.Cu" "B.Cu")
		(net "P5V_B_4")
	)
	(via
		(at 429.8188 -21.8948)
		(size 0.5588)
		(drill 0.3048)
		(layers "F.Cu" "B.Cu")
		(net "P5V_B_4")
	)
	(via
		(at 433.56149 -139.232132)
		(size 0.5588)
		(drill 0.3048)
		(layers "F.Cu" "B.Cu")
		(net "P5V_B_4")
	)
	(via
		(at 464.531202 -115.50015)
		(size 0.7112)
		(drill 0.4064)
		(layers "F.Cu" "B.Cu")
		(net "P5V_B_4")
	)
	(via
		(at 460.0702 -21.7424)
		(size 0.5588)
		(drill 0.3048)
		(layers "F.Cu" "B.Cu")
		(net "P5V_B_4")
	)
	(via
		(at 459.71841 -117.29339)
		(size 0.7112)
		(drill 0.4064)
		(layers "F.Cu" "B.Cu")
		(net "P5V_B_4")
	)
	(via
		(at 464.531202 -114.23015)
		(size 0.7112)
		(drill 0.4064)
		(layers "F.Cu" "B.Cu")
		(net "P5V_B_4")
	)
	(via
		(at 459.71841 -112.31499)
		(size 0.7112)
		(drill 0.4064)
		(layers "F.Cu" "B.Cu")
		(net "P5V_B_4")
	)
	(via
		(at 395.986 -19.431)
		(size 0.5588)
		(drill 0.3048)
		(layers "F.Cu" "B.Cu")
		(net "P5V_B_4")
	)
	(via
		(at 465.074 -138.303)
		(size 0.5588)
		(drill 0.3048)
		(layers "F.Cu" "B.Cu")
		(net "P5V_B_4")
	)
	(via
		(at 455.90841 -117.29339)
		(size 0.7112)
		(drill 0.4064)
		(layers "F.Cu" "B.Cu")
		(net "P5V_B_4")
	)
	(via
		(at 409.197556 -100.8634)
		(size 0.5588)
		(drill 0.3048)
		(layers "F.Cu" "B.Cu")
		(net "P5V_B_4")
	)
	(via
		(at 455.90841 -112.31499)
		(size 0.7112)
		(drill 0.4064)
		(layers "F.Cu" "B.Cu")
		(net "P5V_B_4")
	)
	(via
		(at 476.377 -137.287)
		(size 0.5588)
		(drill 0.3048)
		(layers "F.Cu" "B.Cu")
		(net "P5V_B_4")
	)
	(via
		(at 370.459 -25.781)
		(size 0.5588)
		(drill 0.3048)
		(layers "F.Cu" "B.Cu")
		(net "P5V_B_4")
	)
	(via
		(at 333.883 -19.431)
		(size 0.5588)
		(drill 0.3048)
		(layers "F.Cu" "B.Cu")
		(net "P5V_B_4")
	)
	(via
		(at 463.312002 -115.50015)
		(size 0.7112)
		(drill 0.4064)
		(layers "F.Cu" "B.Cu")
		(net "P5V_B_4")
	)
	(via
		(at 394.716 -19.431)
		(size 0.5588)
		(drill 0.3048)
		(layers "F.Cu" "B.Cu")
		(net "P5V_B_4")
	)
	(via
		(at 455.90841 -116.07419)
		(size 0.7112)
		(drill 0.4064)
		(layers "F.Cu" "B.Cu")
		(net "P5V_B_4")
	)
	(via
		(at 475.107 -22.098)
		(size 0.5588)
		(drill 0.3048)
		(layers "F.Cu" "B.Cu")
		(net "P5V_B_4")
	)
	(via
		(at 331.343 -19.431)
		(size 0.5588)
		(drill 0.3048)
		(layers "F.Cu" "B.Cu")
		(net "P5V_B_4")
	)
	(via
		(at 433.599082 -138.03249)
		(size 0.5588)
		(drill 0.3048)
		(layers "F.Cu" "B.Cu")
		(net "P5V_B_4")
	)
	(via
		(at 473.837 -137.287)
		(size 0.5588)
		(drill 0.3048)
		(layers "F.Cu" "B.Cu")
		(net "P5V_B_4")
	)
	(via
		(at 429.8188 -23.1648)
		(size 0.5588)
		(drill 0.3048)
		(layers "F.Cu" "B.Cu")
		(net "P5V_B_4")
	)
	(via
		(at 466.219032 -112.803178)
		(size 0.6096)
		(drill 0.3048)
		(layers "F.Cu" "B.Cu")
		(net "P5V_B_4")
	)
	(via
		(at 465.074 -140.843)
		(size 0.5588)
		(drill 0.3048)
		(layers "F.Cu" "B.Cu")
		(net "P5V_B_4")
	)
	(via
		(at 465.074 -137.033)
		(size 0.5588)
		(drill 0.3048)
		(layers "F.Cu" "B.Cu")
		(net "P5V_B_4")
	)
	(via
		(at 457.5302 -21.7424)
		(size 0.5588)
		(drill 0.3048)
		(layers "F.Cu" "B.Cu")
		(net "P5V_B_4")
	)
	(via
		(at 433.599082 -136.76249)
		(size 0.5588)
		(drill 0.3048)
		(layers "F.Cu" "B.Cu")
		(net "P5V_B_4")
	)
	(via
		(at 477.647 -137.287)
		(size 0.5588)
		(drill 0.3048)
		(layers "F.Cu" "B.Cu")
		(net "P5V_B_4")
	)
	(via
		(at 473.837 -22.098)
		(size 0.5588)
		(drill 0.3048)
		(layers "F.Cu" "B.Cu")
		(net "P5V_B_4")
	)
	(via
		(at 265.753088 -240.011712)
		(size 0.5588)
		(drill 0.3048)
		(layers "F.Cu" "B.Cu")
		(net "P5V_B_4")
	)
	(via
		(at 429.8442 -24.4094)
		(size 0.5588)
		(drill 0.3048)
		(layers "F.Cu" "B.Cu")
		(net "P5V_B_4")
	)
	(via
		(at 466.969602 -114.23015)
		(size 0.7112)
		(drill 0.4064)
		(layers "F.Cu" "B.Cu")
		(net "P5V_B_4")
	)
	(via
		(at 456.2602 -21.7424)
		(size 0.5588)
		(drill 0.3048)
		(layers "F.Cu" "B.Cu")
		(net "P5V_B_4")
	)
	(via
		(at 455.90841 -113.53419)
		(size 0.7112)
		(drill 0.4064)
		(layers "F.Cu" "B.Cu")
		(net "P5V_B_4")
	)
	(via
		(at 433.5272 -141.3002)
		(size 0.5588)
		(drill 0.3048)
		(layers "F.Cu" "B.Cu")
		(net "P5V_B_4")
	)
	(via
		(at 465.356956 -101.0666)
		(size 0.5588)
		(drill 0.3048)
		(layers "F.Cu" "B.Cu")
		(net "P5V_B_4")
	)
	(via
		(at 465.750402 -114.23015)
		(size 0.7112)
		(drill 0.4064)
		(layers "F.Cu" "B.Cu")
		(net "P5V_B_4")
	)
	(via
		(at 465.750402 -115.50015)
		(size 0.7112)
		(drill 0.4064)
		(layers "F.Cu" "B.Cu")
		(net "P5V_B_4")
	)
	(via
		(at 461.643984 -111.069628)
		(size 0.6096)
		(drill 0.3048)
		(layers "F.Cu" "B.Cu")
		(net "P5V_B_4")
	)
	(via
		(at 476.377 -22.098)
		(size 0.5588)
		(drill 0.3048)
		(layers "F.Cu" "B.Cu")
		(net "P5V_B_4")
	)
	(via
		(at 460.873602 -114.23015)
		(size 0.7112)
		(drill 0.4064)
		(layers "F.Cu" "B.Cu")
		(net "P5V_B_4")
	)
	(via
		(at 370.459 -23.241)
		(size 0.5588)
		(drill 0.3048)
		(layers "F.Cu" "B.Cu")
		(net "P5V_B_4")
	)
	(via
		(at 465.074 -139.573)
		(size 0.5588)
		(drill 0.3048)
		(layers "F.Cu" "B.Cu")
		(net "P5V_B_4")
	)
	(via
		(at 460.873602 -115.50015)
		(size 0.7112)
		(drill 0.4064)
		(layers "F.Cu" "B.Cu")
		(net "P5V_B_4")
	)
	(via
		(at 463.777584 -111.907828)
		(size 0.6096)
		(drill 0.3048)
		(layers "F.Cu" "B.Cu")
		(net "P5V_B_4")
	)
	(via
		(at 462.092802 -115.50015)
		(size 0.7112)
		(drill 0.4064)
		(layers "F.Cu" "B.Cu")
		(net "P5V_B_4")
	)
	(via
		(at 463.312002 -114.23015)
		(size 0.7112)
		(drill 0.4064)
		(layers "F.Cu" "B.Cu")
		(net "P5V_B_4")
	)
	(via
		(at 458.4446 -114.7572)
		(size 0.7112)
		(drill 0.4064)
		(layers "F.Cu" "B.Cu")
		(net "P5V_B_4")
	)
	(via
		(at 458.8002 -21.7424)
		(size 0.5588)
		(drill 0.3048)
		(layers "F.Cu" "B.Cu")
		(net "P5V_B_4")
	)
	(via
		(at 433.578 -26.289)
		(size 0.5588)
		(drill 0.3048)
		(layers "F.Cu" "B.Cu")
		(net "P5V_B_4")
	)
	(via
		(at 330.073 -19.431)
		(size 0.5588)
		(drill 0.3048)
		(layers "F.Cu" "B.Cu")
		(net "P5V_B_4")
	)
	(via
		(at 441.963556 -100.8634)
		(size 0.5588)
		(drill 0.3048)
		(layers "F.Cu" "B.Cu")
		(net "P5V_B_4")
	)
	(via
		(at 370.459 -21.971)
		(size 0.5588)
		(drill 0.3048)
		(layers "F.Cu" "B.Cu")
		(net "P5V_B_4")
	)
	(via
		(at 410.467556 -100.8634)
		(size 0.5588)
		(drill 0.3048)
		(layers "F.Cu" "B.Cu")
		(net "P5V_B_4")
	)
	(via
		(at 466.113368 -110.596172)
		(size 0.6096)
		(drill 0.3048)
		(layers "F.Cu" "B.Cu")
		(net "P5V_B_4")
	)
	(via
		(at 370.459 -24.511)
		(size 0.5588)
		(drill 0.3048)
		(layers "F.Cu" "B.Cu")
		(net "P5V_B_4")
	)
	(via
		(at 397.256 -19.431)
		(size 0.5588)
		(drill 0.3048)
		(layers "F.Cu" "B.Cu")
		(net "P5V_B_4")
	)
	(via
		(at 459.71841 -116.07419)
		(size 0.7112)
		(drill 0.4064)
		(layers "F.Cu" "B.Cu")
		(net "P5V_B_4")
	)
	(via
		(at 464.086956 -101.0666)
		(size 0.5588)
		(drill 0.3048)
		(layers "F.Cu" "B.Cu")
		(net "P5V_B_4")
	)
	(segment
		(start 466.505798 -117.875558)
		(end 466.505798 -117.389402)
		(width 0.254)
		(layer "B.Cu")
		(net "P5V_B_4")
	)
	(segment
		(start 449.655184 -111.780828)
		(end 449.005198 -112.430814)
		(width 0.508)
		(layer "B.Cu")
		(net "P5V_B_4")
	)
	(segment
		(start 449.005198 -112.430814)
		(end 449.005198 -118.015004)
		(width 0.508)
		(layer "B.Cu")
		(net "P5V_B_4")
	)
	(segment
		(start 453.061578 -111.780828)
		(end 449.655184 -111.780828)
		(width 0.508)
		(layer "B.Cu")
		(net "P5V_B_4")
	)
	(segment
		(start 477.647 -137.287)
		(end 480.539298 -140.179298)
		(width 0.508)
		(layer "In2.Cu")
		(net "P5V_B_4")
	)
	(segment
		(start 486.8926 -230.3018)
		(end 486.8926 -232.5116)
		(width 0.508)
		(layer "In2.Cu")
		(net "P5V_B_4")
	)
	(segment
		(start 476.4786 -242.9256)
		(end 471.8558 -242.9256)
		(width 0.508)
		(layer "In2.Cu")
		(net "P5V_B_4")
	)
	(segment
		(start 480.539298 -164.24402)
		(end 480.6442 -164.348922)
		(width 0.508)
		(layer "In2.Cu")
		(net "P5V_B_4")
	)
	(segment
		(start 471.8558 -242.9256)
		(end 468.2236 -246.5578)
		(width 0.508)
		(layer "In2.Cu")
		(net "P5V_B_4")
	)
	(segment
		(start 468.2236 -246.5578)
		(end 464.2104 -246.5578)
		(width 0.508)
		(layer "In2.Cu")
		(net "P5V_B_4")
	)
	(segment
		(start 480.6442 -165.862)
		(end 487.1974 -172.4152)
		(width 0.508)
		(layer "In2.Cu")
		(net "P5V_B_4")
	)
	(segment
		(start 486.8926 -232.5116)
		(end 476.4786 -242.9256)
		(width 0.508)
		(layer "In2.Cu")
		(net "P5V_B_4")
	)
	(segment
		(start 487.1974 -172.4152)
		(end 487.1974 -229.997)
		(width 0.508)
		(layer "In2.Cu")
		(net "P5V_B_4")
	)
	(segment
		(start 480.539298 -140.179298)
		(end 480.539298 -164.24402)
		(width 0.508)
		(layer "In2.Cu")
		(net "P5V_B_4")
	)
	(segment
		(start 487.1974 -229.997)
		(end 486.8926 -230.3018)
		(width 0.508)
		(layer "In2.Cu")
		(net "P5V_B_4")
	)
	(segment
		(start 480.6442 -164.348922)
		(end 480.6442 -165.862)
		(width 0.508)
		(layer "In2.Cu")
		(net "P5V_B_4")
	)
	(segment
		(start 350.598486 -257.380486)
		(end 451.863714 -257.380486)
		(width 0.508)
		(layer "In5.Cu")
		(net "P5V_B_4")
	)
	(segment
		(start 337.08975 -251.25045)
		(end 344.46845 -251.25045)
		(width 0.508)
		(layer "In5.Cu")
		(net "P5V_B_4")
	)
	(segment
		(start 462.6864 -246.5578)
		(end 464.2104 -246.5578)
		(width 0.508)
		(layer "In5.Cu")
		(net "P5V_B_4")
	)
	(segment
		(start 322.878958 -254.78232)
		(end 333.55788 -254.78232)
		(width 0.508)
		(layer "In5.Cu")
		(net "P5V_B_4")
	)
	(segment
		(start 265.753088 -240.011712)
		(end 280.778712 -240.011712)
		(width 0.508)
		(layer "In5.Cu")
		(net "P5V_B_4")
	)
	(segment
		(start 451.863714 -257.380486)
		(end 462.6864 -246.5578)
		(width 0.508)
		(layer "In5.Cu")
		(net "P5V_B_4")
	)
	(segment
		(start 296.82059 -257.937)
		(end 319.724278 -257.937)
		(width 0.508)
		(layer "In5.Cu")
		(net "P5V_B_4")
	)
	(segment
		(start 280.778712 -240.011712)
		(end 286.430466 -245.663466)
		(width 0.508)
		(layer "In5.Cu")
		(net "P5V_B_4")
	)
	(segment
		(start 344.46845 -251.25045)
		(end 350.598486 -257.380486)
		(width 0.508)
		(layer "In5.Cu")
		(net "P5V_B_4")
	)
	(segment
		(start 319.724278 -257.937)
		(end 322.878958 -254.78232)
		(width 0.508)
		(layer "In5.Cu")
		(net "P5V_B_4")
	)
	(segment
		(start 333.55788 -254.78232)
		(end 337.08975 -251.25045)
		(width 0.508)
		(layer "In5.Cu")
		(net "P5V_B_4")
	)
	(segment
		(start 286.430466 -245.663466)
		(end 286.430466 -247.546876)
		(width 0.508)
		(layer "In5.Cu")
		(net "P5V_B_4")
	)
	(segment
		(start 286.430466 -247.546876)
		(end 296.82059 -257.937)
		(width 0.508)
		(layer "In5.Cu")
		(net "P5V_B_4")
	)
	(segment
		(start 453.393302 -225.57359)
		(end 453.543162 -225.42373)
		(width 0.254)
		(layer "F.Cu")
		(net "P5V_B_3_VREG")
	)
	(segment
		(start 453.393302 -226.57435)
		(end 453.393302 -225.57359)
		(width 0.254)
		(layer "F.Cu")
		(net "P5V_B_3_VREG")
	)
	(via
		(at 453.543162 -225.42373)
		(size 0.6604)
		(drill 0.3048)
		(layers "F.Cu" "B.Cu")
		(net "P5V_B_3_VREG")
	)
	(segment
		(start 452.313802 -225.43135)
		(end 452.321422 -225.42373)
		(width 0.254)
		(layer "B.Cu")
		(net "P5V_B_3_VREG")
	)
	(segment
		(start 454.750678 -225.417126)
		(end 453.549766 -225.417126)
		(width 0.254)
		(layer "B.Cu")
		(net "P5V_B_3_VREG")
	)
	(segment
		(start 452.321422 -225.42373)
		(end 453.543162 -225.42373)
		(width 0.254)
		(layer "B.Cu")
		(net "P5V_B_3_VREG")
	)
	(segment
		(start 453.549766 -225.417126)
		(end 453.543162 -225.42373)
		(width 0.254)
		(layer "B.Cu")
		(net "P5V_B_3_VREG")
	)
	(via
		(at 461.838802 -231.01935)
		(size 0.6096)
		(drill 0.3048)
		(layers "F.Cu" "B.Cu")
		(net "P5V_B_3_VFB_R")
	)
	(segment
		(start 462.032604 -230.825548)
		(end 461.838802 -231.01935)
		(width 0.254)
		(layer "B.Cu")
		(net "P5V_B_3_VFB_R")
	)
	(segment
		(start 461.1878 -229.6922)
		(end 460.4893 -229.6922)
		(width 0.254)
		(layer "B.Cu")
		(net "P5V_B_3_VFB_R")
	)
	(segment
		(start 460.886302 -231.01935)
		(end 461.838802 -231.01935)
		(width 0.254)
		(layer "B.Cu")
		(net "P5V_B_3_VFB_R")
	)
	(segment
		(start 460.505302 -230.63835)
		(end 460.886302 -231.01935)
		(width 0.254)
		(layer "B.Cu")
		(net "P5V_B_3_VFB_R")
	)
	(segment
		(start 462.032604 -229.626414)
		(end 461.253586 -229.626414)
		(width 0.254)
		(layer "B.Cu")
		(net "P5V_B_3_VFB_R")
	)
	(segment
		(start 461.253586 -229.626414)
		(end 461.1878 -229.6922)
		(width 0.254)
		(layer "B.Cu")
		(net "P5V_B_3_VFB_R")
	)
	(segment
		(start 462.032604 -229.626414)
		(end 462.032604 -230.825548)
		(width 0.254)
		(layer "B.Cu")
		(net "P5V_B_3_VFB_R")
	)
	(via
		(at 464.277202 -231.78135)
		(size 0.6096)
		(drill 0.3048)
		(layers "F.Cu" "B.Cu")
		(net "P5V_B_3_VFB")
	)
	(segment
		(start 459.649322 -229.643178)
		(end 459.6003 -229.6922)
		(width 0.254)
		(layer "B.Cu")
		(net "P5V_B_3_VFB")
	)
	(segment
		(start 458.201014 -229.099364)
		(end 459.007464 -229.099364)
		(width 0.254)
		(layer "B.Cu")
		(net "P5V_B_3_VFB")
	)
	(segment
		(start 459.616302 -230.82885)
		(end 459.616302 -230.63835)
		(width 0.254)
		(layer "B.Cu")
		(net "P5V_B_3_VFB")
	)
	(segment
		(start 465.602828 -231.78135)
		(end 464.277202 -231.78135)
		(width 0.254)
		(layer "B.Cu")
		(net "P5V_B_3_VFB")
	)
	(segment
		(start 464.277202 -231.78135)
		(end 460.568802 -231.78135)
		(width 0.254)
		(layer "B.Cu")
		(net "P5V_B_3_VFB")
	)
	(segment
		(start 459.6003 -229.6922)
		(end 459.6003 -230.622348)
		(width 0.254)
		(layer "B.Cu")
		(net "P5V_B_3_VFB")
	)
	(segment
		(start 459.007464 -229.099364)
		(end 459.6003 -229.6922)
		(width 0.254)
		(layer "B.Cu")
		(net "P5V_B_3_VFB")
	)
	(segment
		(start 459.6003 -230.622348)
		(end 459.616302 -230.63835)
		(width 0.254)
		(layer "B.Cu")
		(net "P5V_B_3_VFB")
	)
	(segment
		(start 459.649322 -227.417122)
		(end 459.649322 -229.643178)
		(width 0.254)
		(layer "B.Cu")
		(net "P5V_B_3_VFB")
	)
	(segment
		(start 466.472524 -230.911654)
		(end 465.602828 -231.78135)
		(width 0.254)
		(layer "B.Cu")
		(net "P5V_B_3_VFB")
	)
	(segment
		(start 460.568802 -231.78135)
		(end 459.616302 -230.82885)
		(width 0.254)
		(layer "B.Cu")
		(net "P5V_B_3_VFB")
	)
	(segment
		(start 461.737202 -223.55175)
		(end 459.806802 -223.55175)
		(width 0.508)
		(layer "F.Cu")
		(net "P5V_B_3_VBST_RC")
	)
	(segment
		(start 462.443322 -223.55175)
		(end 461.737202 -223.55175)
		(width 0.508)
		(layer "F.Cu")
		(net "P5V_B_3_VBST_RC")
	)
	(segment
		(start 462.967324 -223.027748)
		(end 462.443322 -223.55175)
		(width 0.508)
		(layer "F.Cu")
		(net "P5V_B_3_VBST_RC")
	)
	(via
		(at 461.737202 -223.55175)
		(size 0.6604)
		(drill 0.3302)
		(layers "F.Cu" "B.Cu")
		(net "P5V_B_3_VBST_RC")
	)
	(segment
		(start 460.729584 -225.998532)
		(end 461.705706 -225.998532)
		(width 0.508)
		(layer "F.Cu")
		(net "P5V_B_3_VBST")
	)
	(segment
		(start 459.806802 -225.07575)
		(end 460.729584 -225.998532)
		(width 0.508)
		(layer "F.Cu")
		(net "P5V_B_3_VBST")
	)
	(via
		(at 461.705706 -225.998532)
		(size 0.6604)
		(drill 0.3048)
		(layers "F.Cu" "B.Cu")
		(net "P5V_B_3_VBST")
	)
	(segment
		(start 461.624172 -225.916998)
		(end 461.705706 -225.998532)
		(width 0.3048)
		(layer "B.Cu")
		(net "P5V_B_3_VBST")
	)
	(segment
		(start 459.649322 -225.916998)
		(end 461.624172 -225.916998)
		(width 0.3048)
		(layer "B.Cu")
		(net "P5V_B_3_VBST")
	)
	(segment
		(start 454.26122 -228.703632)
		(end 453.723502 -229.24135)
		(width 0.254)
		(layer "F.Cu")
		(net "P5V_B_3_TRIP")
	)
	(segment
		(start 453.723502 -230.96855)
		(end 453.723502 -229.74935)
		(width 0.254)
		(layer "F.Cu")
		(net "P5V_B_3_TRIP")
	)
	(segment
		(start 454.26122 -228.221286)
		(end 454.26122 -228.703632)
		(width 0.254)
		(layer "F.Cu")
		(net "P5V_B_3_TRIP")
	)
	(segment
		(start 453.723502 -229.24135)
		(end 453.723502 -229.74935)
		(width 0.254)
		(layer "F.Cu")
		(net "P5V_B_3_TRIP")
	)
	(via
		(at 454.26122 -228.221286)
		(size 0.5588)
		(drill 0.3048)
		(layers "F.Cu" "B.Cu")
		(net "P5V_B_3_TRIP")
	)
	(via
		(at 453.723502 -229.74935)
		(size 0.6604)
		(drill 0.3302)
		(layers "F.Cu" "B.Cu")
		(net "P5V_B_3_TRIP")
	)
	(segment
		(start 454.750678 -226.916996)
		(end 454.142094 -226.916996)
		(width 0.254)
		(layer "B.Cu")
		(net "P5V_B_3_TRIP")
	)
	(segment
		(start 453.914002 -227.145088)
		(end 453.914002 -227.874068)
		(width 0.254)
		(layer "B.Cu")
		(net "P5V_B_3_TRIP")
	)
	(segment
		(start 454.142094 -226.916996)
		(end 453.914002 -227.145088)
		(width 0.254)
		(layer "B.Cu")
		(net "P5V_B_3_TRIP")
	)
	(segment
		(start 453.914002 -227.874068)
		(end 454.26122 -228.221286)
		(width 0.254)
		(layer "B.Cu")
		(net "P5V_B_3_TRIP")
	)
	(segment
		(start 461.330802 -221.58325)
		(end 459.687676 -221.58325)
		(width 0.508)
		(layer "F.Cu")
		(net "P5V_B_3_SNB")
	)
	(segment
		(start 462.960212 -221.75089)
		(end 462.792572 -221.58325)
		(width 0.508)
		(layer "F.Cu")
		(net "P5V_B_3_SNB")
	)
	(segment
		(start 462.792572 -221.58325)
		(end 461.330802 -221.58325)
		(width 0.508)
		(layer "F.Cu")
		(net "P5V_B_3_SNB")
	)
	(via
		(at 461.330802 -221.58325)
		(size 0.6604)
		(drill 0.3302)
		(layers "F.Cu" "B.Cu")
		(net "P5V_B_3_SNB")
	)
	(segment
		(start 456.3618 -229.06482)
		(end 456.3618 -228.717348)
		(width 0.254)
		(layer "F.Cu")
		(net "P5V_B_3_ROVP")
	)
	(segment
		(start 456.3618 -228.717348)
		(end 456.819 -228.260148)
		(width 0.254)
		(layer "F.Cu")
		(net "P5V_B_3_ROVP")
	)
	(via
		(at 462.626202 -226.92995)
		(size 0.6604)
		(drill 0.3048)
		(layers "F.Cu" "B.Cu")
		(net "P5V_B_3_ROVP")
	)
	(via
		(at 456.819 -228.260148)
		(size 0.5588)
		(drill 0.3048)
		(layers "F.Cu" "B.Cu")
		(net "P5V_B_3_ROVP")
	)
	(segment
		(start 462.626202 -225.695002)
		(end 462.626202 -226.92995)
		(width 0.254)
		(layer "B.Cu")
		(net "P5V_B_3_ROVP")
	)
	(segment
		(start 459.649322 -225.417126)
		(end 460.306674 -225.417126)
		(width 0.254)
		(layer "B.Cu")
		(net "P5V_B_3_ROVP")
	)
	(segment
		(start 461.899 -224.9678)
		(end 462.626202 -225.695002)
		(width 0.254)
		(layer "B.Cu")
		(net "P5V_B_3_ROVP")
	)
	(segment
		(start 460.306674 -225.417126)
		(end 460.756 -224.9678)
		(width 0.254)
		(layer "B.Cu")
		(net "P5V_B_3_ROVP")
	)
	(segment
		(start 460.756 -224.9678)
		(end 461.899 -224.9678)
		(width 0.254)
		(layer "B.Cu")
		(net "P5V_B_3_ROVP")
	)
	(segment
		(start 462.626202 -226.92995)
		(end 461.457802 -226.92995)
		(width 0.254)
		(layer "In2.Cu")
		(net "P5V_B_3_ROVP")
	)
	(segment
		(start 460.127604 -228.260148)
		(end 456.819 -228.260148)
		(width 0.254)
		(layer "In2.Cu")
		(net "P5V_B_3_ROVP")
	)
	(segment
		(start 461.457802 -226.92995)
		(end 460.127604 -228.260148)
		(width 0.254)
		(layer "In2.Cu")
		(net "P5V_B_3_ROVP")
	)
	(segment
		(start 454.282302 -226.57435)
		(end 454.625202 -226.57435)
		(width 0.254)
		(layer "F.Cu")
		(net "P5V_B_3_RF")
	)
	(segment
		(start 454.625202 -226.57435)
		(end 455.234802 -227.18395)
		(width 0.254)
		(layer "F.Cu")
		(net "P5V_B_3_RF")
	)
	(segment
		(start 455.311002 -229.05085)
		(end 455.311002 -228.22535)
		(width 0.254)
		(layer "F.Cu")
		(net "P5V_B_3_RF")
	)
	(segment
		(start 455.234802 -228.14915)
		(end 455.234802 -227.18395)
		(width 0.254)
		(layer "F.Cu")
		(net "P5V_B_3_RF")
	)
	(segment
		(start 455.311002 -228.22535)
		(end 455.234802 -228.14915)
		(width 0.254)
		(layer "F.Cu")
		(net "P5V_B_3_RF")
	)
	(via
		(at 455.234802 -228.14915)
		(size 0.5588)
		(drill 0.3048)
		(layers "F.Cu" "B.Cu")
		(net "P5V_B_3_RF")
	)
	(via
		(at 455.234802 -227.18395)
		(size 0.6604)
		(drill 0.3302)
		(layers "F.Cu" "B.Cu")
		(net "P5V_B_3_RF")
	)
	(segment
		(start 454.750678 -227.665026)
		(end 455.234802 -228.14915)
		(width 0.254)
		(layer "B.Cu")
		(net "P5V_B_3_RF")
	)
	(segment
		(start 454.750678 -227.417122)
		(end 454.750678 -227.665026)
		(width 0.254)
		(layer "B.Cu")
		(net "P5V_B_3_RF")
	)
	(segment
		(start 462.603088 -228.608636)
		(end 462.600802 -228.60635)
		(width 0.254)
		(layer "F.Cu")
		(net "P5V_B_3_PGOOD")
	)
	(segment
		(start 463.007202 -230.51135)
		(end 462.603088 -230.107236)
		(width 0.254)
		(layer "F.Cu")
		(net "P5V_B_3_PGOOD")
	)
	(segment
		(start 461.722216 -227.727764)
		(end 460.898748 -227.727764)
		(width 0.254)
		(layer "F.Cu")
		(net "P5V_B_3_PGOOD")
	)
	(segment
		(start 460.898748 -227.727764)
		(end 460.27467 -228.351842)
		(width 0.254)
		(layer "F.Cu")
		(net "P5V_B_3_PGOOD")
	)
	(segment
		(start 459.619096 -227.696268)
		(end 460.27467 -228.351842)
		(width 0.254)
		(layer "F.Cu")
		(net "P5V_B_3_PGOOD")
	)
	(segment
		(start 465.140802 -231.52735)
		(end 464.124802 -230.51135)
		(width 0.254)
		(layer "F.Cu")
		(net "P5V_B_3_PGOOD")
	)
	(segment
		(start 464.124802 -230.51135)
		(end 463.007202 -230.51135)
		(width 0.254)
		(layer "F.Cu")
		(net "P5V_B_3_PGOOD")
	)
	(segment
		(start 462.603088 -229.5017)
		(end 462.603088 -228.608636)
		(width 0.254)
		(layer "F.Cu")
		(net "P5V_B_3_PGOOD")
	)
	(segment
		(start 462.603088 -230.107236)
		(end 462.603088 -229.5017)
		(width 0.254)
		(layer "F.Cu")
		(net "P5V_B_3_PGOOD")
	)
	(segment
		(start 462.600802 -228.60635)
		(end 461.722216 -227.727764)
		(width 0.254)
		(layer "F.Cu")
		(net "P5V_B_3_PGOOD")
	)
	(segment
		(start 458.725524 -227.696268)
		(end 459.619096 -227.696268)
		(width 0.254)
		(layer "F.Cu")
		(net "P5V_B_3_PGOOD")
	)
	(segment
		(start 457.491338 -228.930454)
		(end 458.725524 -227.696268)
		(width 0.254)
		(layer "F.Cu")
		(net "P5V_B_3_PGOOD")
	)
	(via
		(at 462.600802 -228.60635)
		(size 0.5588)
		(drill 0.3048)
		(layers "F.Cu" "B.Cu")
		(net "P5V_B_3_PGOOD")
	)
	(segment
		(start 459.649322 -226.417124)
		(end 460.427324 -226.417124)
		(width 0.254)
		(layer "B.Cu")
		(net "P5V_B_3_PGOOD")
	)
	(segment
		(start 460.427324 -226.417124)
		(end 460.8068 -226.7966)
		(width 0.254)
		(layer "B.Cu")
		(net "P5V_B_3_PGOOD")
	)
	(segment
		(start 462.600802 -227.981002)
		(end 462.600802 -228.60635)
		(width 0.254)
		(layer "B.Cu")
		(net "P5V_B_3_PGOOD")
	)
	(segment
		(start 460.8068 -226.7966)
		(end 461.4164 -226.7966)
		(width 0.254)
		(layer "B.Cu")
		(net "P5V_B_3_PGOOD")
	)
	(segment
		(start 461.4164 -226.7966)
		(end 462.600802 -227.981002)
		(width 0.254)
		(layer "B.Cu")
		(net "P5V_B_3_PGOOD")
	)
	(segment
		(start 452.796402 -231.40035)
		(end 453.558402 -232.16235)
		(width 0.254)
		(layer "F.Cu")
		(net "P5V_B_3_MODE")
	)
	(segment
		(start 458.380338 -229.96271)
		(end 458.37983 -229.963218)
		(width 0.254)
		(layer "F.Cu")
		(net "P5V_B_3_MODE")
	)
	(segment
		(start 458.37983 -229.963218)
		(end 458.37983 -230.202486)
		(width 0.254)
		(layer "F.Cu")
		(net "P5V_B_3_MODE")
	)
	(segment
		(start 458.37983 -230.202486)
		(end 457.863956 -230.71836)
		(width 0.254)
		(layer "F.Cu")
		(net "P5V_B_3_MODE")
	)
	(segment
		(start 453.1106 -228.0158)
		(end 452.796402 -228.329998)
		(width 0.254)
		(layer "F.Cu")
		(net "P5V_B_3_MODE")
	)
	(segment
		(start 453.558402 -232.16235)
		(end 457.266802 -232.16235)
		(width 0.254)
		(layer "F.Cu")
		(net "P5V_B_3_MODE")
	)
	(segment
		(start 457.266802 -232.16235)
		(end 457.520802 -231.90835)
		(width 0.254)
		(layer "F.Cu")
		(net "P5V_B_3_MODE")
	)
	(segment
		(start 452.796402 -228.329998)
		(end 452.796402 -231.40035)
		(width 0.254)
		(layer "F.Cu")
		(net "P5V_B_3_MODE")
	)
	(segment
		(start 458.380338 -228.930454)
		(end 458.380338 -229.96271)
		(width 0.254)
		(layer "F.Cu")
		(net "P5V_B_3_MODE")
	)
	(segment
		(start 457.863956 -230.71836)
		(end 457.863956 -231.565196)
		(width 0.254)
		(layer "F.Cu")
		(net "P5V_B_3_MODE")
	)
	(segment
		(start 457.863956 -231.565196)
		(end 457.520802 -231.90835)
		(width 0.254)
		(layer "F.Cu")
		(net "P5V_B_3_MODE")
	)
	(via
		(at 457.520802 -231.90835)
		(size 0.6604)
		(drill 0.3302)
		(layers "F.Cu" "B.Cu")
		(net "P5V_B_3_MODE")
	)
	(via
		(at 453.1106 -228.0158)
		(size 0.5588)
		(drill 0.3048)
		(layers "F.Cu" "B.Cu")
		(net "P5V_B_3_MODE")
	)
	(segment
		(start 454.750678 -226.417124)
		(end 453.969628 -226.417124)
		(width 0.254)
		(layer "B.Cu")
		(net "P5V_B_3_MODE")
	)
	(segment
		(start 453.969628 -226.417124)
		(end 453.1106 -227.276152)
		(width 0.254)
		(layer "B.Cu")
		(net "P5V_B_3_MODE")
	)
	(segment
		(start 453.1106 -227.276152)
		(end 453.1106 -228.0158)
		(width 0.254)
		(layer "B.Cu")
		(net "P5V_B_3_MODE")
	)
	(via
		(at 467.680802 -232.16235)
		(size 0.6096)
		(drill 0.3048)
		(layers "F.Cu" "B.Cu")
		(net "P5V_B_3_LL_R")
	)
	(segment
		(start 464.251802 -219.97035)
		(end 464.505802 -219.71635)
		(width 0.508)
		(layer "F.Cu")
		(net "P5V_B_3_LL")
	)
	(segment
		(start 464.251802 -221.3483)
		(end 464.251802 -220.73235)
		(width 0.508)
		(layer "F.Cu")
		(net "P5V_B_3_LL")
	)
	(segment
		(start 463.856324 -223.027748)
		(end 463.856324 -224.223072)
		(width 0.508)
		(layer "F.Cu")
		(net "P5V_B_3_LL")
	)
	(segment
		(start 463.849212 -221.75089)
		(end 464.251802 -221.3483)
		(width 0.508)
		(layer "F.Cu")
		(net "P5V_B_3_LL")
	)
	(segment
		(start 464.251802 -220.73235)
		(end 464.251802 -219.97035)
		(width 0.508)
		(layer "F.Cu")
		(net "P5V_B_3_LL")
	)
	(segment
		(start 463.856324 -224.223072)
		(end 464.404202 -224.77095)
		(width 0.508)
		(layer "F.Cu")
		(net "P5V_B_3_LL")
	)
	(via
		(at 464.404202 -224.77095)
		(size 0.7112)
		(drill 0.4064)
		(layers "F.Cu" "B.Cu")
		(net "P5V_B_3_LL")
	)
	(via
		(at 464.251802 -220.73235)
		(size 0.6604)
		(drill 0.3302)
		(layers "F.Cu" "B.Cu")
		(net "P5V_B_3_LL")
	)
	(via
		(at 464.505802 -219.71635)
		(size 0.5588)
		(drill 0.3048)
		(layers "F.Cu" "B.Cu")
		(net "P5V_B_3_LL")
	)
	(segment
		(start 463.166206 -222.0976)
		(end 465.744052 -222.0976)
		(width 0.508)
		(layer "B.Cu")
		(net "P5V_B_3_LL")
	)
	(segment
		(start 466.537802 -223.647254)
		(end 466.530944 -223.654112)
		(width 0.508)
		(layer "B.Cu")
		(net "P5V_B_3_LL")
	)
	(segment
		(start 465.744052 -222.0976)
		(end 466.537802 -222.89135)
		(width 0.508)
		(layer "B.Cu")
		(net "P5V_B_3_LL")
	)
	(segment
		(start 466.530944 -223.654112)
		(end 466.530944 -228.656896)
		(width 0.508)
		(layer "B.Cu")
		(net "P5V_B_3_LL")
	)
	(segment
		(start 466.537802 -222.89135)
		(end 466.537802 -223.647254)
		(width 0.508)
		(layer "B.Cu")
		(net "P5V_B_3_LL")
	)
	(segment
		(start 460.314802 -231.90835)
		(end 461.394302 -231.90835)
		(width 0.254)
		(layer "F.Cu")
		(net "P5V_B_3_EN_R")
	)
	(segment
		(start 460.505302 -230.06685)
		(end 461.076802 -229.49535)
		(width 0.254)
		(layer "F.Cu")
		(net "P5V_B_3_EN_R")
	)
	(segment
		(start 461.394302 -231.90835)
		(end 461.584802 -231.71785)
		(width 0.254)
		(layer "F.Cu")
		(net "P5V_B_3_EN_R")
	)
	(segment
		(start 460.505302 -231.01935)
		(end 460.505302 -230.63835)
		(width 0.254)
		(layer "F.Cu")
		(net "P5V_B_3_EN_R")
	)
	(segment
		(start 462.613502 -231.62895)
		(end 462.524602 -231.71785)
		(width 0.254)
		(layer "F.Cu")
		(net "P5V_B_3_EN_R")
	)
	(segment
		(start 460.505302 -230.63835)
		(end 460.505302 -230.06685)
		(width 0.254)
		(layer "F.Cu")
		(net "P5V_B_3_EN_R")
	)
	(segment
		(start 461.076802 -228.499416)
		(end 461.08874 -228.487478)
		(width 0.254)
		(layer "F.Cu")
		(net "P5V_B_3_EN_R")
	)
	(segment
		(start 462.524602 -231.71785)
		(end 461.584802 -231.71785)
		(width 0.254)
		(layer "F.Cu")
		(net "P5V_B_3_EN_R")
	)
	(segment
		(start 461.076802 -229.49535)
		(end 461.076802 -228.499416)
		(width 0.254)
		(layer "F.Cu")
		(net "P5V_B_3_EN_R")
	)
	(segment
		(start 460.314802 -231.90835)
		(end 460.314802 -231.20985)
		(width 0.254)
		(layer "F.Cu")
		(net "P5V_B_3_EN_R")
	)
	(segment
		(start 460.314802 -231.20985)
		(end 460.505302 -231.01935)
		(width 0.254)
		(layer "F.Cu")
		(net "P5V_B_3_EN_R")
	)
	(via
		(at 460.314802 -231.90835)
		(size 0.6604)
		(drill 0.3302)
		(layers "F.Cu" "B.Cu")
		(net "P5V_B_3_EN_R")
	)
	(via
		(at 461.08874 -228.487478)
		(size 0.5588)
		(drill 0.3048)
		(layers "F.Cu" "B.Cu")
		(net "P5V_B_3_EN_R")
	)
	(segment
		(start 461.102202 -227.76815)
		(end 461.102202 -228.474016)
		(width 0.254)
		(layer "B.Cu")
		(net "P5V_B_3_EN_R")
	)
	(segment
		(start 460.251048 -226.916996)
		(end 461.102202 -227.76815)
		(width 0.254)
		(layer "B.Cu")
		(net "P5V_B_3_EN_R")
	)
	(segment
		(start 459.649322 -226.916996)
		(end 460.251048 -226.916996)
		(width 0.254)
		(layer "B.Cu")
		(net "P5V_B_3_EN_R")
	)
	(segment
		(start 461.102202 -228.474016)
		(end 461.08874 -228.487478)
		(width 0.254)
		(layer "B.Cu")
		(net "P5V_B_3_EN_R")
	)
	(via
		(at 464.709002 -229.626414)
		(size 0.6604)
		(drill 0.3048)
		(layers "F.Cu" "B.Cu")
		(net "P5V_B_3_CC")
	)
	(via
		(at 486.283 -229.108)
		(size 0.5588)
		(drill 0.3048)
		(layers "F.Cu" "B.Cu")
		(net "P5V_B_3_CC")
	)
	(segment
		(start 486.283 -229.108)
		(end 485.714802 -228.539802)
		(width 0.254)
		(layer "B.Cu")
		(net "P5V_B_3_CC")
	)
	(segment
		(start 485.714802 -228.539802)
		(end 485.714802 -228.28885)
		(width 0.254)
		(layer "B.Cu")
		(net "P5V_B_3_CC")
	)
	(segment
		(start 463.556604 -229.626414)
		(end 464.709002 -229.626414)
		(width 0.254)
		(layer "B.Cu")
		(net "P5V_B_3_CC")
	)
	(segment
		(start 485.764586 -229.626414)
		(end 486.283 -229.108)
		(width 0.254)
		(layer "In2.Cu")
		(net "P5V_B_3_CC")
	)
	(segment
		(start 464.709002 -229.626414)
		(end 485.764586 -229.626414)
		(width 0.254)
		(layer "In2.Cu")
		(net "P5V_B_3_CC")
	)
	(segment
		(start 315.839856 -213.91626)
		(end 315.839348 -213.915752)
		(width 0.508)
		(layer "F.Cu")
		(net "P5V_B_3")
	)
	(segment
		(start 315.839348 -213.915752)
		(end 314.569348 -213.915752)
		(width 0.508)
		(layer "F.Cu")
		(net "P5V_B_3")
	)
	(segment
		(start 441.96 -215.011)
		(end 441.96 -215.9254)
		(width 0.508)
		(layer "F.Cu")
		(net "P5V_B_3")
	)
	(segment
		(start 347.345 -100.859844)
		(end 347.348556 -100.8634)
		(width 0.508)
		(layer "F.Cu")
		(net "P5V_B_3")
	)
	(segment
		(start 346.075 -100.859844)
		(end 346.078556 -100.8634)
		(width 0.508)
		(layer "F.Cu")
		(net "P5V_B_3")
	)
	(segment
		(start 377.698 -100.859844)
		(end 377.701556 -100.8634)
		(width 0.508)
		(layer "F.Cu")
		(net "P5V_B_3")
	)
	(segment
		(start 264.2108 -231.273604)
		(end 261.782306 -228.84511)
		(width 0.508)
		(layer "F.Cu")
		(net "P5V_B_3")
	)
	(segment
		(start 316.887352 -213.91626)
		(end 315.839856 -213.91626)
		(width 0.508)
		(layer "F.Cu")
		(net "P5V_B_3")
	)
	(segment
		(start 378.968 -99.949)
		(end 378.968 -100.859844)
		(width 0.508)
		(layer "F.Cu")
		(net "P5V_B_3")
	)
	(segment
		(start 475.9452 -225.1202)
		(end 475.869 -225.1964)
		(width 0.508)
		(layer "F.Cu")
		(net "P5V_B_3")
	)
	(segment
		(start 377.698 -99.949)
		(end 377.698 -100.859844)
		(width 0.508)
		(layer "F.Cu")
		(net "P5V_B_3")
	)
	(segment
		(start 317.119 -98.933)
		(end 317.119 -99.9744)
		(width 0.508)
		(layer "F.Cu")
		(net "P5V_B_3")
	)
	(segment
		(start 475.869 -225.1964)
		(end 467.153752 -225.1964)
		(width 0.508)
		(layer "F.Cu")
		(net "P5V_B_3")
	)
	(segment
		(start 261.782306 -228.84511)
		(end 259.534406 -228.84511)
		(width 0.508)
		(layer "F.Cu")
		(net "P5V_B_3")
	)
	(segment
		(start 346.075 -215.138)
		(end 346.075 -216.388188)
		(width 0.508)
		(layer "F.Cu")
		(net "P5V_B_3")
	)
	(segment
		(start 473.583 -215.011)
		(end 473.583 -215.9254)
		(width 0.508)
		(layer "F.Cu")
		(net "P5V_B_3")
	)
	(segment
		(start 378.968 -216.3064)
		(end 379.349 -216.6874)
		(width 0.508)
		(layer "F.Cu")
		(net "P5V_B_3")
	)
	(segment
		(start 463.492088 -229.5017)
		(end 463.492088 -228.858064)
		(width 0.508)
		(layer "F.Cu")
		(net "P5V_B_3")
	)
	(segment
		(start 346.075 -99.949)
		(end 346.075 -100.859844)
		(width 0.508)
		(layer "F.Cu")
		(net "P5V_B_3")
	)
	(segment
		(start 410.464 -215.011)
		(end 410.464 -215.9254)
		(width 0.508)
		(layer "F.Cu")
		(net "P5V_B_3")
	)
	(segment
		(start 378.968 -215.011)
		(end 378.968 -216.3064)
		(width 0.508)
		(layer "F.Cu")
		(net "P5V_B_3")
	)
	(segment
		(start 463.492088 -228.858064)
		(end 466.791802 -225.55835)
		(width 0.508)
		(layer "F.Cu")
		(net "P5V_B_3")
	)
	(segment
		(start 347.345 -99.949)
		(end 347.345 -100.859844)
		(width 0.508)
		(layer "F.Cu")
		(net "P5V_B_3")
	)
	(segment
		(start 264.2108 -240.03)
		(end 264.2108 -231.273604)
		(width 0.508)
		(layer "F.Cu")
		(net "P5V_B_3")
	)
	(segment
		(start 467.153752 -225.1964)
		(end 466.791802 -225.55835)
		(width 0.508)
		(layer "F.Cu")
		(net "P5V_B_3")
	)
	(segment
		(start 315.849 -98.933)
		(end 315.849 -99.9744)
		(width 0.508)
		(layer "F.Cu")
		(net "P5V_B_3")
	)
	(segment
		(start 378.968 -100.859844)
		(end 378.971556 -100.8634)
		(width 0.508)
		(layer "F.Cu")
		(net "P5V_B_3")
	)
	(segment
		(start 409.194 -215.011)
		(end 409.194 -215.9254)
		(width 0.508)
		(layer "F.Cu")
		(net "P5V_B_3")
	)
	(segment
		(start 347.345 -215.138)
		(end 347.345 -216.388188)
		(width 0.508)
		(layer "F.Cu")
		(net "P5V_B_3")
	)
	(segment
		(start 472.313 -215.011)
		(end 472.313 -215.9254)
		(width 0.508)
		(layer "F.Cu")
		(net "P5V_B_3")
	)
	(segment
		(start 377.698 -215.011)
		(end 377.698 -216.3064)
		(width 0.508)
		(layer "F.Cu")
		(net "P5V_B_3")
	)
	(segment
		(start 440.69 -215.011)
		(end 440.69 -215.9254)
		(width 0.508)
		(layer "F.Cu")
		(net "P5V_B_3")
	)
	(via
		(at 338.963 -139.573)
		(size 0.5588)
		(drill 0.3048)
		(layers "F.Cu" "B.Cu")
		(net "P5V_B_3")
	)
	(via
		(at 370.459 -251.968)
		(size 0.5588)
		(drill 0.3048)
		(layers "F.Cu" "B.Cu")
		(net "P5V_B_3")
	)
	(via
		(at 402.082 -255.778)
		(size 0.5588)
		(drill 0.3048)
		(layers "F.Cu" "B.Cu")
		(net "P5V_B_3")
	)
	(via
		(at 483.378002 -224.51695)
		(size 0.7112)
		(drill 0.4064)
		(layers "F.Cu" "B.Cu")
		(net "P5V_B_3")
	)
	(via
		(at 402.082 -140.843)
		(size 0.5588)
		(drill 0.3048)
		(layers "F.Cu" "B.Cu")
		(net "P5V_B_3")
	)
	(via
		(at 378.971556 -100.8634)
		(size 0.5588)
		(drill 0.3048)
		(layers "F.Cu" "B.Cu")
		(net "P5V_B_3")
	)
	(via
		(at 474.75521 -226.36099)
		(size 0.7112)
		(drill 0.4064)
		(layers "F.Cu" "B.Cu")
		(net "P5V_B_3")
	)
	(via
		(at 475.9452 -225.1202)
		(size 0.7112)
		(drill 0.4064)
		(layers "F.Cu" "B.Cu")
		(net "P5V_B_3")
	)
	(via
		(at 479.720402 -224.51695)
		(size 0.7112)
		(drill 0.4064)
		(layers "F.Cu" "B.Cu")
		(net "P5V_B_3")
	)
	(via
		(at 465.074 -251.968)
		(size 0.5588)
		(drill 0.3048)
		(layers "F.Cu" "B.Cu")
		(net "P5V_B_3")
	)
	(via
		(at 478.56521 -227.58019)
		(size 0.7112)
		(drill 0.4064)
		(layers "F.Cu" "B.Cu")
		(net "P5V_B_3")
	)
	(via
		(at 370.459 -138.303)
		(size 0.5588)
		(drill 0.3048)
		(layers "F.Cu" "B.Cu")
		(net "P5V_B_3")
	)
	(via
		(at 370.459 -140.843)
		(size 0.5588)
		(drill 0.3048)
		(layers "F.Cu" "B.Cu")
		(net "P5V_B_3")
	)
	(via
		(at 482.158802 -225.78695)
		(size 0.7112)
		(drill 0.4064)
		(layers "F.Cu" "B.Cu")
		(net "P5V_B_3")
	)
	(via
		(at 433.578 -254.508)
		(size 0.5588)
		(drill 0.3048)
		(layers "F.Cu" "B.Cu")
		(net "P5V_B_3")
	)
	(via
		(at 473.583 -215.9254)
		(size 0.5588)
		(drill 0.3048)
		(layers "F.Cu" "B.Cu")
		(net "P5V_B_3")
	)
	(via
		(at 482.158802 -224.51695)
		(size 0.7112)
		(drill 0.4064)
		(layers "F.Cu" "B.Cu")
		(net "P5V_B_3")
	)
	(via
		(at 472.313 -215.9254)
		(size 0.5588)
		(drill 0.3048)
		(layers "F.Cu" "B.Cu")
		(net "P5V_B_3")
	)
	(via
		(at 474.75521 -223.82099)
		(size 0.7112)
		(drill 0.4064)
		(layers "F.Cu" "B.Cu")
		(net "P5V_B_3")
	)
	(via
		(at 338.963 -254.508)
		(size 0.5588)
		(drill 0.3048)
		(layers "F.Cu" "B.Cu")
		(net "P5V_B_3")
	)
	(via
		(at 484.5812 -221.2848)
		(size 0.6096)
		(drill 0.3048)
		(layers "F.Cu" "B.Cu")
		(net "P5V_B_3")
	)
	(via
		(at 402.082 -254.508)
		(size 0.5588)
		(drill 0.3048)
		(layers "F.Cu" "B.Cu")
		(net "P5V_B_3")
	)
	(via
		(at 476.710756 -252.256544)
		(size 0.5588)
		(drill 0.3048)
		(layers "F.Cu" "B.Cu")
		(net "P5V_B_3")
	)
	(via
		(at 370.459 -139.573)
		(size 0.5588)
		(drill 0.3048)
		(layers "F.Cu" "B.Cu")
		(net "P5V_B_3")
	)
	(via
		(at 477.980756 -252.256544)
		(size 0.5588)
		(drill 0.3048)
		(layers "F.Cu" "B.Cu")
		(net "P5V_B_3")
	)
	(via
		(at 478.56521 -222.60179)
		(size 0.7112)
		(drill 0.4064)
		(layers "F.Cu" "B.Cu")
		(net "P5V_B_3")
	)
	(via
		(at 402.082 -139.573)
		(size 0.5588)
		(drill 0.3048)
		(layers "F.Cu" "B.Cu")
		(net "P5V_B_3")
	)
	(via
		(at 478.56521 -226.36099)
		(size 0.7112)
		(drill 0.4064)
		(layers "F.Cu" "B.Cu")
		(net "P5V_B_3")
	)
	(via
		(at 473.837 -252.222)
		(size 0.5588)
		(drill 0.3048)
		(layers "F.Cu" "B.Cu")
		(net "P5V_B_3")
	)
	(via
		(at 346.078556 -100.8634)
		(size 0.5588)
		(drill 0.3048)
		(layers "F.Cu" "B.Cu")
		(net "P5V_B_3")
	)
	(via
		(at 370.459 -137.033)
		(size 0.5588)
		(drill 0.3048)
		(layers "F.Cu" "B.Cu")
		(net "P5V_B_3")
	)
	(via
		(at 347.345 -216.388188)
		(size 0.5588)
		(drill 0.3048)
		(layers "F.Cu" "B.Cu")
		(net "P5V_B_3")
	)
	(via
		(at 370.459 -253.238)
		(size 0.5588)
		(drill 0.3048)
		(layers "F.Cu" "B.Cu")
		(net "P5V_B_3")
	)
	(via
		(at 433.578 -255.778)
		(size 0.5588)
		(drill 0.3048)
		(layers "F.Cu" "B.Cu")
		(net "P5V_B_3")
	)
	(via
		(at 338.963 -140.843)
		(size 0.5588)
		(drill 0.3048)
		(layers "F.Cu" "B.Cu")
		(net "P5V_B_3")
	)
	(via
		(at 338.963 -255.778)
		(size 0.5588)
		(drill 0.3048)
		(layers "F.Cu" "B.Cu")
		(net "P5V_B_3")
	)
	(via
		(at 402.082 -137.033)
		(size 0.5588)
		(drill 0.3048)
		(layers "F.Cu" "B.Cu")
		(net "P5V_B_3")
	)
	(via
		(at 480.939602 -224.51695)
		(size 0.7112)
		(drill 0.4064)
		(layers "F.Cu" "B.Cu")
		(net "P5V_B_3")
	)
	(via
		(at 433.578 -253.238)
		(size 0.5588)
		(drill 0.3048)
		(layers "F.Cu" "B.Cu")
		(net "P5V_B_3")
	)
	(via
		(at 485.816402 -225.78695)
		(size 0.7112)
		(drill 0.4064)
		(layers "F.Cu" "B.Cu")
		(net "P5V_B_3")
	)
	(via
		(at 402.082 -251.968)
		(size 0.5588)
		(drill 0.3048)
		(layers "F.Cu" "B.Cu")
		(net "P5V_B_3")
	)
	(via
		(at 347.348556 -100.8634)
		(size 0.5588)
		(drill 0.3048)
		(layers "F.Cu" "B.Cu")
		(net "P5V_B_3")
	)
	(via
		(at 465.074 -255.778)
		(size 0.5588)
		(drill 0.3048)
		(layers "F.Cu" "B.Cu")
		(net "P5V_B_3")
	)
	(via
		(at 474.75521 -227.58019)
		(size 0.7112)
		(drill 0.4064)
		(layers "F.Cu" "B.Cu")
		(net "P5V_B_3")
	)
	(via
		(at 315.849 -99.9744)
		(size 0.5588)
		(drill 0.3048)
		(layers "F.Cu" "B.Cu")
		(net "P5V_B_3")
	)
	(via
		(at 377.701556 -100.8634)
		(size 0.5588)
		(drill 0.3048)
		(layers "F.Cu" "B.Cu")
		(net "P5V_B_3")
	)
	(via
		(at 346.075 -216.388188)
		(size 0.5588)
		(drill 0.3048)
		(layers "F.Cu" "B.Cu")
		(net "P5V_B_3")
	)
	(via
		(at 402.082 -253.238)
		(size 0.5588)
		(drill 0.3048)
		(layers "F.Cu" "B.Cu")
		(net "P5V_B_3")
	)
	(via
		(at 480.939602 -225.78695)
		(size 0.7112)
		(drill 0.4064)
		(layers "F.Cu" "B.Cu")
		(net "P5V_B_3")
	)
	(via
		(at 484.597202 -225.78695)
		(size 0.7112)
		(drill 0.4064)
		(layers "F.Cu" "B.Cu")
		(net "P5V_B_3")
	)
	(via
		(at 341.68461 -135.534654)
		(size 0.5588)
		(drill 0.3048)
		(layers "F.Cu" "B.Cu")
		(net "P5V_B_3")
	)
	(via
		(at 377.698 -216.3064)
		(size 0.5588)
		(drill 0.3048)
		(layers "F.Cu" "B.Cu")
		(net "P5V_B_3")
	)
	(via
		(at 264.2108 -240.03)
		(size 0.5588)
		(drill 0.3048)
		(layers "F.Cu" "B.Cu")
		(net "P5V_B_3")
	)
	(via
		(at 338.963 -137.033)
		(size 0.5588)
		(drill 0.3048)
		(layers "F.Cu" "B.Cu")
		(net "P5V_B_3")
	)
	(via
		(at 441.96 -215.9254)
		(size 0.5588)
		(drill 0.3048)
		(layers "F.Cu" "B.Cu")
		(net "P5V_B_3")
	)
	(via
		(at 479.720402 -225.78695)
		(size 0.7112)
		(drill 0.4064)
		(layers "F.Cu" "B.Cu")
		(net "P5V_B_3")
	)
	(via
		(at 370.459 -254.508)
		(size 0.5588)
		(drill 0.3048)
		(layers "F.Cu" "B.Cu")
		(net "P5V_B_3")
	)
	(via
		(at 475.440756 -252.256544)
		(size 0.5588)
		(drill 0.3048)
		(layers "F.Cu" "B.Cu")
		(net "P5V_B_3")
	)
	(via
		(at 338.963 -138.303)
		(size 0.5588)
		(drill 0.3048)
		(layers "F.Cu" "B.Cu")
		(net "P5V_B_3")
	)
	(via
		(at 409.194 -215.9254)
		(size 0.5588)
		(drill 0.3048)
		(layers "F.Cu" "B.Cu")
		(net "P5V_B_3")
	)
	(via
		(at 465.074 -253.238)
		(size 0.5588)
		(drill 0.3048)
		(layers "F.Cu" "B.Cu")
		(net "P5V_B_3")
	)
	(via
		(at 465.074 -254.508)
		(size 0.5588)
		(drill 0.3048)
		(layers "F.Cu" "B.Cu")
		(net "P5V_B_3")
	)
	(via
		(at 433.578 -251.968)
		(size 0.5588)
		(drill 0.3048)
		(layers "F.Cu" "B.Cu")
		(net "P5V_B_3")
	)
	(via
		(at 440.69 -215.9254)
		(size 0.5588)
		(drill 0.3048)
		(layers "F.Cu" "B.Cu")
		(net "P5V_B_3")
	)
	(via
		(at 338.963 -253.238)
		(size 0.5588)
		(drill 0.3048)
		(layers "F.Cu" "B.Cu")
		(net "P5V_B_3")
	)
	(via
		(at 483.378002 -225.78695)
		(size 0.7112)
		(drill 0.4064)
		(layers "F.Cu" "B.Cu")
		(net "P5V_B_3")
	)
	(via
		(at 410.464 -215.9254)
		(size 0.5588)
		(drill 0.3048)
		(layers "F.Cu" "B.Cu")
		(net "P5V_B_3")
	)
	(via
		(at 317.119 -99.9744)
		(size 0.5588)
		(drill 0.3048)
		(layers "F.Cu" "B.Cu")
		(net "P5V_B_3")
	)
	(via
		(at 485.816402 -224.51695)
		(size 0.7112)
		(drill 0.4064)
		(layers "F.Cu" "B.Cu")
		(net "P5V_B_3")
	)
	(via
		(at 477.2914 -225.1202)
		(size 0.7112)
		(drill 0.4064)
		(layers "F.Cu" "B.Cu")
		(net "P5V_B_3")
	)
	(via
		(at 478.56521 -223.82099)
		(size 0.7112)
		(drill 0.4064)
		(layers "F.Cu" "B.Cu")
		(net "P5V_B_3")
	)
	(via
		(at 379.349 -216.6874)
		(size 0.5588)
		(drill 0.3048)
		(layers "F.Cu" "B.Cu")
		(net "P5V_B_3")
	)
	(via
		(at 328.834496 -91.135708)
		(size 0.5588)
		(drill 0.3048)
		(layers "F.Cu" "B.Cu")
		(net "P5V_B_3")
	)
	(via
		(at 402.082 -138.303)
		(size 0.5588)
		(drill 0.3048)
		(layers "F.Cu" "B.Cu")
		(net "P5V_B_3")
	)
	(via
		(at 370.459 -255.778)
		(size 0.5588)
		(drill 0.3048)
		(layers "F.Cu" "B.Cu")
		(net "P5V_B_3")
	)
	(via
		(at 338.963 -251.968)
		(size 0.5588)
		(drill 0.3048)
		(layers "F.Cu" "B.Cu")
		(net "P5V_B_3")
	)
	(via
		(at 316.887352 -213.91626)
		(size 0.5588)
		(drill 0.3048)
		(layers "F.Cu" "B.Cu")
		(net "P5V_B_3")
	)
	(via
		(at 474.75521 -222.60179)
		(size 0.7112)
		(drill 0.4064)
		(layers "F.Cu" "B.Cu")
		(net "P5V_B_3")
	)
	(via
		(at 484.597202 -224.51695)
		(size 0.7112)
		(drill 0.4064)
		(layers "F.Cu" "B.Cu")
		(net "P5V_B_3")
	)
	(segment
		(start 315.849 -99.9744)
		(end 317.119 -99.9744)
		(width 0.508)
		(layer "B.Cu")
		(net "P5V_B_3")
	)
	(segment
		(start 377.701556 -100.8634)
		(end 378.971556 -100.8634)
		(width 0.508)
		(layer "B.Cu")
		(net "P5V_B_3")
	)
	(segment
		(start 320.55562 -99.9744)
		(end 317.119 -99.9744)
		(width 0.508)
		(layer "B.Cu")
		(net "P5V_B_3")
	)
	(segment
		(start 375.383552 -100.81133)
		(end 375.435622 -100.8634)
		(width 0.508)
		(layer "B.Cu")
		(net "P5V_B_3")
	)
	(segment
		(start 341.68461 -109.34319)
		(end 347.348556 -103.679244)
		(width 0.508)
		(layer "B.Cu")
		(net "P5V_B_3")
	)
	(segment
		(start 485.714802 -228.16185)
		(end 485.714802 -227.59035)
		(width 0.254)
		(layer "B.Cu")
		(net "P5V_B_3")
	)
	(segment
		(start 347.348556 -100.8634)
		(end 374.76303 -100.8634)
		(width 0.508)
		(layer "B.Cu")
		(net "P5V_B_3")
	)
	(segment
		(start 374.8151 -100.81133)
		(end 375.383552 -100.81133)
		(width 0.508)
		(layer "B.Cu")
		(net "P5V_B_3")
	)
	(segment
		(start 375.435622 -100.8634)
		(end 377.701556 -100.8634)
		(width 0.508)
		(layer "B.Cu")
		(net "P5V_B_3")
	)
	(segment
		(start 468.5538 -222.0976)
		(end 467.903814 -222.747586)
		(width 0.508)
		(layer "B.Cu")
		(net "P5V_B_3")
	)
	(segment
		(start 467.903814 -222.747586)
		(end 467.903814 -228.331776)
		(width 0.508)
		(layer "B.Cu")
		(net "P5V_B_3")
	)
	(segment
		(start 374.76303 -100.8634)
		(end 374.8151 -100.81133)
		(width 0.508)
		(layer "B.Cu")
		(net "P5V_B_3")
	)
	(segment
		(start 346.078556 -100.8634)
		(end 347.348556 -100.8634)
		(width 0.508)
		(layer "B.Cu")
		(net "P5V_B_3")
	)
	(segment
		(start 325.461884 -91.135708)
		(end 322.470272 -94.12732)
		(width 0.508)
		(layer "B.Cu")
		(net "P5V_B_3")
	)
	(segment
		(start 322.470272 -98.059748)
		(end 320.55562 -99.9744)
		(width 0.508)
		(layer "B.Cu")
		(net "P5V_B_3")
	)
	(segment
		(start 328.834496 -91.135708)
		(end 325.461884 -91.135708)
		(width 0.508)
		(layer "B.Cu")
		(net "P5V_B_3")
	)
	(segment
		(start 347.348556 -103.679244)
		(end 347.348556 -100.8634)
		(width 0.508)
		(layer "B.Cu")
		(net "P5V_B_3")
	)
	(segment
		(start 322.470272 -94.12732)
		(end 322.470272 -98.059748)
		(width 0.508)
		(layer "B.Cu")
		(net "P5V_B_3")
	)
	(segment
		(start 471.960194 -222.0976)
		(end 468.5538 -222.0976)
		(width 0.508)
		(layer "B.Cu")
		(net "P5V_B_3")
	)
	(segment
		(start 341.68461 -135.534654)
		(end 341.68461 -109.34319)
		(width 0.508)
		(layer "B.Cu")
		(net "P5V_B_3")
	)
	(segment
		(start 344.596212 -214.9094)
		(end 346.075 -216.388188)
		(width 0.508)
		(layer "In2.Cu")
		(net "P5V_B_3")
	)
	(segment
		(start 317.880492 -214.9094)
		(end 344.596212 -214.9094)
		(width 0.508)
		(layer "In2.Cu")
		(net "P5V_B_3")
	)
	(segment
		(start 328.834496 -91.135708)
		(end 328.836528 -91.13774)
		(width 0.508)
		(layer "In2.Cu")
		(net "P5V_B_3")
	)
	(segment
		(start 316.887352 -213.91626)
		(end 317.880492 -214.9094)
		(width 0.508)
		(layer "In2.Cu")
		(net "P5V_B_3")
	)
	(segment
		(start 345.445588 -100.230432)
		(end 346.078556 -100.8634)
		(width 0.508)
		(layer "In2.Cu")
		(net "P5V_B_3")
	)
	(segment
		(start 328.836528 -91.13774)
		(end 343.755726 -91.13774)
		(width 0.508)
		(layer "In2.Cu")
		(net "P5V_B_3")
	)
	(segment
		(start 345.445588 -92.827602)
		(end 345.445588 -100.230432)
		(width 0.508)
		(layer "In2.Cu")
		(net "P5V_B_3")
	)
	(segment
		(start 343.755726 -91.13774)
		(end 345.445588 -92.827602)
		(width 0.508)
		(layer "In2.Cu")
		(net "P5V_B_3")
	)
	(segment
		(start 285.259018 -246.397018)
		(end 285.259018 -247.725946)
		(width 0.508)
		(layer "In5.Cu")
		(net "P5V_B_3")
	)
	(segment
		(start 280.110438 -241.248438)
		(end 285.259018 -246.397018)
		(width 0.508)
		(layer "In5.Cu")
		(net "P5V_B_3")
	)
	(segment
		(start 323.19468 -255.54432)
		(end 338.72932 -255.54432)
		(width 0.508)
		(layer "In5.Cu")
		(net "P5V_B_3")
	)
	(segment
		(start 320.04 -258.699)
		(end 323.19468 -255.54432)
		(width 0.508)
		(layer "In5.Cu")
		(net "P5V_B_3")
	)
	(segment
		(start 296.232072 -258.699)
		(end 320.04 -258.699)
		(width 0.508)
		(layer "In5.Cu")
		(net "P5V_B_3")
	)
	(segment
		(start 264.2108 -240.03)
		(end 265.429238 -241.248438)
		(width 0.508)
		(layer "In5.Cu")
		(net "P5V_B_3")
	)
	(segment
		(start 265.429238 -241.248438)
		(end 280.110438 -241.248438)
		(width 0.508)
		(layer "In5.Cu")
		(net "P5V_B_3")
	)
	(segment
		(start 285.259018 -247.725946)
		(end 296.232072 -258.699)
		(width 0.508)
		(layer "In5.Cu")
		(net "P5V_B_3")
	)
	(segment
		(start 338.72932 -255.54432)
		(end 338.963 -255.778)
		(width 0.508)
		(layer "In5.Cu")
		(net "P5V_B_3")
	)
	(segment
		(start 42.63136 -114.388646)
		(end 42.78122 -114.238786)
		(width 0.254)
		(layer "F.Cu")
		(net "P5V_B_2_VREG")
	)
	(segment
		(start 42.63136 -115.389406)
		(end 42.63136 -114.388646)
		(width 0.254)
		(layer "F.Cu")
		(net "P5V_B_2_VREG")
	)
	(via
		(at 42.78122 -114.238786)
		(size 0.6604)
		(drill 0.3048)
		(layers "F.Cu" "B.Cu")
		(net "P5V_B_2_VREG")
	)
	(segment
		(start 41.55948 -114.238786)
		(end 42.78122 -114.238786)
		(width 0.254)
		(layer "B.Cu")
		(net "P5V_B_2_VREG")
	)
	(segment
		(start 43.988736 -114.232182)
		(end 42.787824 -114.232182)
		(width 0.254)
		(layer "B.Cu")
		(net "P5V_B_2_VREG")
	)
	(segment
		(start 41.55186 -114.246406)
		(end 41.55948 -114.238786)
		(width 0.254)
		(layer "B.Cu")
		(net "P5V_B_2_VREG")
	)
	(segment
		(start 42.787824 -114.232182)
		(end 42.78122 -114.238786)
		(width 0.254)
		(layer "B.Cu")
		(net "P5V_B_2_VREG")
	)
	(via
		(at 51.023266 -119.568976)
		(size 0.6096)
		(drill 0.3048)
		(layers "F.Cu" "B.Cu")
		(net "P5V_B_2_VFB_R")
	)
	(segment
		(start 49.85893 -119.568976)
		(end 51.023266 -119.568976)
		(width 0.254)
		(layer "B.Cu")
		(net "P5V_B_2_VFB_R")
	)
	(segment
		(start 50.313844 -118.44147)
		(end 51.270662 -118.44147)
		(width 0.254)
		(layer "B.Cu")
		(net "P5V_B_2_VFB_R")
	)
	(segment
		(start 49.752758 -118.507256)
		(end 50.248058 -118.507256)
		(width 0.254)
		(layer "B.Cu")
		(net "P5V_B_2_VFB_R")
	)
	(segment
		(start 50.248058 -118.507256)
		(end 50.313844 -118.44147)
		(width 0.254)
		(layer "B.Cu")
		(net "P5V_B_2_VFB_R")
	)
	(segment
		(start 49.74336 -119.453406)
		(end 49.85893 -119.568976)
		(width 0.254)
		(layer "B.Cu")
		(net "P5V_B_2_VFB_R")
	)
	(segment
		(start 51.270662 -119.32158)
		(end 51.023266 -119.568976)
		(width 0.254)
		(layer "B.Cu")
		(net "P5V_B_2_VFB_R")
	)
	(segment
		(start 51.270662 -118.44147)
		(end 51.270662 -119.32158)
		(width 0.254)
		(layer "B.Cu")
		(net "P5V_B_2_VFB_R")
	)
	(segment
		(start 51.68138 -112.366806)
		(end 51.10226 -112.366806)
		(width 0.508)
		(layer "F.Cu")
		(net "P5V_B_2_VBST_RC")
	)
	(segment
		(start 52.205382 -111.842804)
		(end 51.68138 -112.366806)
		(width 0.508)
		(layer "F.Cu")
		(net "P5V_B_2_VBST_RC")
	)
	(segment
		(start 51.10226 -112.366806)
		(end 49.04486 -112.366806)
		(width 0.508)
		(layer "F.Cu")
		(net "P5V_B_2_VBST_RC")
	)
	(via
		(at 51.10226 -112.366806)
		(size 0.6604)
		(drill 0.3302)
		(layers "F.Cu" "B.Cu")
		(net "P5V_B_2_VBST_RC")
	)
	(segment
		(start 49.12106 -113.890806)
		(end 50.277268 -115.047014)
		(width 0.508)
		(layer "F.Cu")
		(net "P5V_B_2_VBST")
	)
	(segment
		(start 50.277268 -115.047014)
		(end 50.805588 -115.047014)
		(width 0.508)
		(layer "F.Cu")
		(net "P5V_B_2_VBST")
	)
	(segment
		(start 49.04486 -113.890806)
		(end 49.12106 -113.890806)
		(width 0.508)
		(layer "F.Cu")
		(net "P5V_B_2_VBST")
	)
	(via
		(at 50.805588 -115.047014)
		(size 0.6604)
		(drill 0.3048)
		(layers "F.Cu" "B.Cu")
		(net "P5V_B_2_VBST")
	)
	(segment
		(start 50.490628 -114.732054)
		(end 50.805588 -115.047014)
		(width 0.3048)
		(layer "B.Cu")
		(net "P5V_B_2_VBST")
	)
	(segment
		(start 48.88738 -114.732054)
		(end 50.490628 -114.732054)
		(width 0.3048)
		(layer "B.Cu")
		(net "P5V_B_2_VBST")
	)
	(segment
		(start 42.96156 -119.783606)
		(end 42.96156 -118.564406)
		(width 0.254)
		(layer "F.Cu")
		(net "P5V_B_2_TRIP")
	)
	(segment
		(start 42.96156 -118.056406)
		(end 42.96156 -118.564406)
		(width 0.254)
		(layer "F.Cu")
		(net "P5V_B_2_TRIP")
	)
	(segment
		(start 43.499278 -117.518688)
		(end 42.96156 -118.056406)
		(width 0.254)
		(layer "F.Cu")
		(net "P5V_B_2_TRIP")
	)
	(segment
		(start 43.499278 -117.036342)
		(end 43.499278 -117.518688)
		(width 0.254)
		(layer "F.Cu")
		(net "P5V_B_2_TRIP")
	)
	(via
		(at 42.96156 -118.564406)
		(size 0.6604)
		(drill 0.3302)
		(layers "F.Cu" "B.Cu")
		(net "P5V_B_2_TRIP")
	)
	(via
		(at 43.499278 -117.036342)
		(size 0.5588)
		(drill 0.3048)
		(layers "F.Cu" "B.Cu")
		(net "P5V_B_2_TRIP")
	)
	(segment
		(start 43.15206 -116.689124)
		(end 43.499278 -117.036342)
		(width 0.254)
		(layer "B.Cu")
		(net "P5V_B_2_TRIP")
	)
	(segment
		(start 43.988736 -115.732052)
		(end 43.380152 -115.732052)
		(width 0.254)
		(layer "B.Cu")
		(net "P5V_B_2_TRIP")
	)
	(segment
		(start 43.380152 -115.732052)
		(end 43.15206 -115.960144)
		(width 0.254)
		(layer "B.Cu")
		(net "P5V_B_2_TRIP")
	)
	(segment
		(start 43.15206 -115.960144)
		(end 43.15206 -116.689124)
		(width 0.254)
		(layer "B.Cu")
		(net "P5V_B_2_TRIP")
	)
	(segment
		(start 50.69586 -110.398306)
		(end 48.925734 -110.398306)
		(width 0.508)
		(layer "F.Cu")
		(net "P5V_B_2_SNB")
	)
	(segment
		(start 52.19827 -110.565946)
		(end 52.03063 -110.398306)
		(width 0.508)
		(layer "F.Cu")
		(net "P5V_B_2_SNB")
	)
	(segment
		(start 52.03063 -110.398306)
		(end 50.69586 -110.398306)
		(width 0.508)
		(layer "F.Cu")
		(net "P5V_B_2_SNB")
	)
	(via
		(at 50.69586 -110.398306)
		(size 0.6604)
		(drill 0.3302)
		(layers "F.Cu" "B.Cu")
		(net "P5V_B_2_SNB")
	)
	(segment
		(start 45.599858 -117.879876)
		(end 45.599858 -117.532404)
		(width 0.254)
		(layer "F.Cu")
		(net "P5V_B_2_ROVP")
	)
	(segment
		(start 45.599858 -117.532404)
		(end 46.057058 -117.075204)
		(width 0.254)
		(layer "F.Cu")
		(net "P5V_B_2_ROVP")
	)
	(via
		(at 46.057058 -117.075204)
		(size 0.5588)
		(drill 0.3048)
		(layers "F.Cu" "B.Cu")
		(net "P5V_B_2_ROVP")
	)
	(via
		(at 51.86426 -115.745006)
		(size 0.6604)
		(drill 0.3048)
		(layers "F.Cu" "B.Cu")
		(net "P5V_B_2_ROVP")
	)
	(segment
		(start 48.88738 -114.232182)
		(end 49.595532 -114.232182)
		(width 0.254)
		(layer "B.Cu")
		(net "P5V_B_2_ROVP")
	)
	(segment
		(start 49.595532 -114.232182)
		(end 49.892458 -113.935256)
		(width 0.254)
		(layer "B.Cu")
		(net "P5V_B_2_ROVP")
	)
	(segment
		(start 51.86426 -114.969036)
		(end 51.86426 -115.745006)
		(width 0.254)
		(layer "B.Cu")
		(net "P5V_B_2_ROVP")
	)
	(segment
		(start 50.83048 -113.935256)
		(end 51.86426 -114.969036)
		(width 0.254)
		(layer "B.Cu")
		(net "P5V_B_2_ROVP")
	)
	(segment
		(start 49.892458 -113.935256)
		(end 50.83048 -113.935256)
		(width 0.254)
		(layer "B.Cu")
		(net "P5V_B_2_ROVP")
	)
	(segment
		(start 49.365662 -117.075204)
		(end 46.057058 -117.075204)
		(width 0.254)
		(layer "In2.Cu")
		(net "P5V_B_2_ROVP")
	)
	(segment
		(start 51.86426 -115.745006)
		(end 50.69586 -115.745006)
		(width 0.254)
		(layer "In2.Cu")
		(net "P5V_B_2_ROVP")
	)
	(segment
		(start 50.69586 -115.745006)
		(end 49.365662 -117.075204)
		(width 0.254)
		(layer "In2.Cu")
		(net "P5V_B_2_ROVP")
	)
	(segment
		(start 44.47286 -116.964206)
		(end 44.47286 -115.999006)
		(width 0.254)
		(layer "F.Cu")
		(net "P5V_B_2_RF")
	)
	(segment
		(start 44.54906 -117.040406)
		(end 44.47286 -116.964206)
		(width 0.254)
		(layer "F.Cu")
		(net "P5V_B_2_RF")
	)
	(segment
		(start 43.86326 -115.389406)
		(end 44.47286 -115.999006)
		(width 0.254)
		(layer "F.Cu")
		(net "P5V_B_2_RF")
	)
	(segment
		(start 44.54906 -117.865906)
		(end 44.54906 -117.040406)
		(width 0.254)
		(layer "F.Cu")
		(net "P5V_B_2_RF")
	)
	(segment
		(start 43.52036 -115.389406)
		(end 43.86326 -115.389406)
		(width 0.254)
		(layer "F.Cu")
		(net "P5V_B_2_RF")
	)
	(via
		(at 44.47286 -115.999006)
		(size 0.6604)
		(drill 0.3302)
		(layers "F.Cu" "B.Cu")
		(net "P5V_B_2_RF")
	)
	(via
		(at 44.47286 -116.964206)
		(size 0.5588)
		(drill 0.3048)
		(layers "F.Cu" "B.Cu")
		(net "P5V_B_2_RF")
	)
	(segment
		(start 43.988736 -116.232178)
		(end 43.988736 -116.480082)
		(width 0.254)
		(layer "B.Cu")
		(net "P5V_B_2_RF")
	)
	(segment
		(start 43.988736 -116.480082)
		(end 44.47286 -116.964206)
		(width 0.254)
		(layer "B.Cu")
		(net "P5V_B_2_RF")
	)
	(segment
		(start 53.36286 -119.326406)
		(end 52.24526 -119.326406)
		(width 0.254)
		(layer "F.Cu")
		(net "P5V_B_2_PGOOD")
	)
	(segment
		(start 50.101754 -116.449856)
		(end 49.55286 -116.99875)
		(width 0.254)
		(layer "F.Cu")
		(net "P5V_B_2_PGOOD")
	)
	(segment
		(start 48.857154 -116.511324)
		(end 49.512728 -117.166898)
		(width 0.254)
		(layer "F.Cu")
		(net "P5V_B_2_PGOOD")
	)
	(segment
		(start 49.55286 -117.126766)
		(end 49.512728 -117.166898)
		(width 0.254)
		(layer "F.Cu")
		(net "P5V_B_2_PGOOD")
	)
	(segment
		(start 50.86731 -116.449856)
		(end 50.101754 -116.449856)
		(width 0.254)
		(layer "F.Cu")
		(net "P5V_B_2_PGOOD")
	)
	(segment
		(start 52.24526 -119.326406)
		(end 51.841146 -118.922292)
		(width 0.254)
		(layer "F.Cu")
		(net "P5V_B_2_PGOOD")
	)
	(segment
		(start 54.37886 -120.342406)
		(end 53.36286 -119.326406)
		(width 0.254)
		(layer "F.Cu")
		(net "P5V_B_2_PGOOD")
	)
	(segment
		(start 46.729396 -117.74551)
		(end 47.963582 -116.511324)
		(width 0.254)
		(layer "F.Cu")
		(net "P5V_B_2_PGOOD")
	)
	(segment
		(start 49.55286 -116.99875)
		(end 49.55286 -117.126766)
		(width 0.254)
		(layer "F.Cu")
		(net "P5V_B_2_PGOOD")
	)
	(segment
		(start 51.841146 -118.922292)
		(end 51.841146 -118.316756)
		(width 0.254)
		(layer "F.Cu")
		(net "P5V_B_2_PGOOD")
	)
	(segment
		(start 51.83886 -117.421406)
		(end 50.86731 -116.449856)
		(width 0.254)
		(layer "F.Cu")
		(net "P5V_B_2_PGOOD")
	)
	(segment
		(start 51.841146 -118.316756)
		(end 51.841146 -117.423692)
		(width 0.254)
		(layer "F.Cu")
		(net "P5V_B_2_PGOOD")
	)
	(segment
		(start 47.963582 -116.511324)
		(end 48.857154 -116.511324)
		(width 0.254)
		(layer "F.Cu")
		(net "P5V_B_2_PGOOD")
	)
	(segment
		(start 51.841146 -117.423692)
		(end 51.83886 -117.421406)
		(width 0.254)
		(layer "F.Cu")
		(net "P5V_B_2_PGOOD")
	)
	(via
		(at 51.83886 -117.421406)
		(size 0.5588)
		(drill 0.3048)
		(layers "F.Cu" "B.Cu")
		(net "P5V_B_2_PGOOD")
	)
	(segment
		(start 50.480468 -116.094256)
		(end 51.162458 -116.094256)
		(width 0.254)
		(layer "B.Cu")
		(net "P5V_B_2_PGOOD")
	)
	(segment
		(start 48.88738 -115.23218)
		(end 49.618392 -115.23218)
		(width 0.254)
		(layer "B.Cu")
		(net "P5V_B_2_PGOOD")
	)
	(segment
		(start 51.162458 -116.094256)
		(end 51.83886 -116.770658)
		(width 0.254)
		(layer "B.Cu")
		(net "P5V_B_2_PGOOD")
	)
	(segment
		(start 49.618392 -115.23218)
		(end 50.480468 -116.094256)
		(width 0.254)
		(layer "B.Cu")
		(net "P5V_B_2_PGOOD")
	)
	(segment
		(start 51.83886 -116.770658)
		(end 51.83886 -117.421406)
		(width 0.254)
		(layer "B.Cu")
		(net "P5V_B_2_PGOOD")
	)
	(segment
		(start 47.618396 -117.74551)
		(end 47.618396 -118.777766)
		(width 0.254)
		(layer "F.Cu")
		(net "P5V_B_2_MODE")
	)
	(segment
		(start 47.102014 -119.533416)
		(end 47.102014 -120.380252)
		(width 0.254)
		(layer "F.Cu")
		(net "P5V_B_2_MODE")
	)
	(segment
		(start 47.618396 -118.777766)
		(end 47.617888 -118.778274)
		(width 0.254)
		(layer "F.Cu")
		(net "P5V_B_2_MODE")
	)
	(segment
		(start 46.50486 -120.977406)
		(end 46.75886 -120.723406)
		(width 0.254)
		(layer "F.Cu")
		(net "P5V_B_2_MODE")
	)
	(segment
		(start 42.79646 -120.977406)
		(end 46.50486 -120.977406)
		(width 0.254)
		(layer "F.Cu")
		(net "P5V_B_2_MODE")
	)
	(segment
		(start 47.102014 -120.380252)
		(end 46.75886 -120.723406)
		(width 0.254)
		(layer "F.Cu")
		(net "P5V_B_2_MODE")
	)
	(segment
		(start 42.03446 -117.145054)
		(end 42.03446 -120.215406)
		(width 0.254)
		(layer "F.Cu")
		(net "P5V_B_2_MODE")
	)
	(segment
		(start 47.617888 -118.778274)
		(end 47.617888 -119.017542)
		(width 0.254)
		(layer "F.Cu")
		(net "P5V_B_2_MODE")
	)
	(segment
		(start 42.348658 -116.830856)
		(end 42.03446 -117.145054)
		(width 0.254)
		(layer "F.Cu")
		(net "P5V_B_2_MODE")
	)
	(segment
		(start 42.03446 -120.215406)
		(end 42.79646 -120.977406)
		(width 0.254)
		(layer "F.Cu")
		(net "P5V_B_2_MODE")
	)
	(segment
		(start 47.617888 -119.017542)
		(end 47.102014 -119.533416)
		(width 0.254)
		(layer "F.Cu")
		(net "P5V_B_2_MODE")
	)
	(via
		(at 42.348658 -116.830856)
		(size 0.5588)
		(drill 0.3048)
		(layers "F.Cu" "B.Cu")
		(net "P5V_B_2_MODE")
	)
	(via
		(at 46.75886 -120.723406)
		(size 0.6604)
		(drill 0.3302)
		(layers "F.Cu" "B.Cu")
		(net "P5V_B_2_MODE")
	)
	(segment
		(start 43.988736 -115.23218)
		(end 43.207686 -115.23218)
		(width 0.254)
		(layer "B.Cu")
		(net "P5V_B_2_MODE")
	)
	(segment
		(start 43.207686 -115.23218)
		(end 42.348658 -116.091208)
		(width 0.254)
		(layer "B.Cu")
		(net "P5V_B_2_MODE")
	)
	(segment
		(start 42.348658 -116.091208)
		(end 42.348658 -116.830856)
		(width 0.254)
		(layer "B.Cu")
		(net "P5V_B_2_MODE")
	)
	(via
		(at 56.91886 -120.977406)
		(size 0.6096)
		(drill 0.3048)
		(layers "F.Cu" "B.Cu")
		(net "P5V_B_2_LL_R")
	)
	(segment
		(start 53.094382 -111.842804)
		(end 53.094382 -113.038128)
		(width 0.508)
		(layer "F.Cu")
		(net "P5V_B_2_LL")
	)
	(segment
		(start 53.48986 -109.585506)
		(end 53.491384 -109.58703)
		(width 0.508)
		(layer "F.Cu")
		(net "P5V_B_2_LL")
	)
	(segment
		(start 53.48986 -109.588554)
		(end 53.491384 -109.58703)
		(width 0.508)
		(layer "F.Cu")
		(net "P5V_B_2_LL")
	)
	(segment
		(start 53.48986 -110.163356)
		(end 53.48986 -109.588554)
		(width 0.508)
		(layer "F.Cu")
		(net "P5V_B_2_LL")
	)
	(segment
		(start 53.094382 -113.038128)
		(end 53.64226 -113.586006)
		(width 0.508)
		(layer "F.Cu")
		(net "P5V_B_2_LL")
	)
	(segment
		(start 53.48986 -108.785406)
		(end 53.48986 -109.585506)
		(width 0.508)
		(layer "F.Cu")
		(net "P5V_B_2_LL")
	)
	(segment
		(start 53.08727 -110.565946)
		(end 53.48986 -110.163356)
		(width 0.508)
		(layer "F.Cu")
		(net "P5V_B_2_LL")
	)
	(segment
		(start 53.74386 -108.531406)
		(end 53.48986 -108.785406)
		(width 0.508)
		(layer "F.Cu")
		(net "P5V_B_2_LL")
	)
	(via
		(at 53.74386 -108.531406)
		(size 0.7112)
		(drill 0.4064)
		(layers "F.Cu" "B.Cu")
		(net "P5V_B_2_LL")
	)
	(via
		(at 53.64226 -113.586006)
		(size 0.7112)
		(drill 0.4064)
		(layers "F.Cu" "B.Cu")
		(net "P5V_B_2_LL")
	)
	(via
		(at 53.491384 -109.58703)
		(size 0.6604)
		(drill 0.3302)
		(layers "F.Cu" "B.Cu")
		(net "P5V_B_2_LL")
	)
	(segment
		(start 55.475886 -110.912656)
		(end 56.125872 -111.562642)
		(width 0.508)
		(layer "B.Cu")
		(net "P5V_B_2_LL")
	)
	(segment
		(start 55.769002 -116.571776)
		(end 55.769002 -117.471952)
		(width 0.508)
		(layer "B.Cu")
		(net "P5V_B_2_LL")
	)
	(segment
		(start 52.404264 -110.912656)
		(end 55.475886 -110.912656)
		(width 0.508)
		(layer "B.Cu")
		(net "P5V_B_2_LL")
	)
	(segment
		(start 56.125872 -111.562642)
		(end 56.125872 -116.214906)
		(width 0.508)
		(layer "B.Cu")
		(net "P5V_B_2_LL")
	)
	(segment
		(start 56.125872 -116.214906)
		(end 55.769002 -116.571776)
		(width 0.508)
		(layer "B.Cu")
		(net "P5V_B_2_LL")
	)
	(segment
		(start 50.31486 -117.314472)
		(end 50.326798 -117.302534)
		(width 0.254)
		(layer "F.Cu")
		(net "P5V_B_2_EN_R")
	)
	(segment
		(start 49.55286 -120.723406)
		(end 49.55286 -120.024906)
		(width 0.254)
		(layer "F.Cu")
		(net "P5V_B_2_EN_R")
	)
	(segment
		(start 49.74336 -119.453406)
		(end 49.74336 -118.881906)
		(width 0.254)
		(layer "F.Cu")
		(net "P5V_B_2_EN_R")
	)
	(segment
		(start 49.55286 -120.723406)
		(end 50.63236 -120.723406)
		(width 0.254)
		(layer "F.Cu")
		(net "P5V_B_2_EN_R")
	)
	(segment
		(start 49.74336 -119.834406)
		(end 49.74336 -119.453406)
		(width 0.254)
		(layer "F.Cu")
		(net "P5V_B_2_EN_R")
	)
	(segment
		(start 51.76266 -120.532906)
		(end 50.82286 -120.532906)
		(width 0.254)
		(layer "F.Cu")
		(net "P5V_B_2_EN_R")
	)
	(segment
		(start 49.74336 -118.881906)
		(end 50.31486 -118.310406)
		(width 0.254)
		(layer "F.Cu")
		(net "P5V_B_2_EN_R")
	)
	(segment
		(start 50.31486 -118.310406)
		(end 50.31486 -117.314472)
		(width 0.254)
		(layer "F.Cu")
		(net "P5V_B_2_EN_R")
	)
	(segment
		(start 50.63236 -120.723406)
		(end 50.82286 -120.532906)
		(width 0.254)
		(layer "F.Cu")
		(net "P5V_B_2_EN_R")
	)
	(segment
		(start 51.85156 -120.444006)
		(end 51.76266 -120.532906)
		(width 0.254)
		(layer "F.Cu")
		(net "P5V_B_2_EN_R")
	)
	(segment
		(start 49.55286 -120.024906)
		(end 49.74336 -119.834406)
		(width 0.254)
		(layer "F.Cu")
		(net "P5V_B_2_EN_R")
	)
	(via
		(at 49.55286 -120.723406)
		(size 0.6604)
		(drill 0.3302)
		(layers "F.Cu" "B.Cu")
		(net "P5V_B_2_EN_R")
	)
	(via
		(at 50.326798 -117.302534)
		(size 0.5588)
		(drill 0.3048)
		(layers "F.Cu" "B.Cu")
		(net "P5V_B_2_EN_R")
	)
	(segment
		(start 49.489106 -115.732052)
		(end 49.846484 -116.08943)
		(width 0.254)
		(layer "B.Cu")
		(net "P5V_B_2_EN_R")
	)
	(segment
		(start 49.846484 -116.82222)
		(end 50.326798 -117.302534)
		(width 0.254)
		(layer "B.Cu")
		(net "P5V_B_2_EN_R")
	)
	(segment
		(start 48.88738 -115.732052)
		(end 49.489106 -115.732052)
		(width 0.254)
		(layer "B.Cu")
		(net "P5V_B_2_EN_R")
	)
	(segment
		(start 49.846484 -116.08943)
		(end 49.846484 -116.82222)
		(width 0.254)
		(layer "B.Cu")
		(net "P5V_B_2_EN_R")
	)
	(via
		(at 53.94706 -118.44147)
		(size 0.6604)
		(drill 0.3048)
		(layers "F.Cu" "B.Cu")
		(net "P5V_B_2_CC")
	)
	(via
		(at 74.95286 -117.675406)
		(size 0.5588)
		(drill 0.3048)
		(layers "F.Cu" "B.Cu")
		(net "P5V_B_2_CC")
	)
	(segment
		(start 52.794662 -118.44147)
		(end 53.94706 -118.44147)
		(width 0.254)
		(layer "B.Cu")
		(net "P5V_B_2_CC")
	)
	(segment
		(start 74.95286 -117.103906)
		(end 74.95286 -117.675406)
		(width 0.254)
		(layer "B.Cu")
		(net "P5V_B_2_CC")
	)
	(segment
		(start 53.94706 -118.44147)
		(end 74.186796 -118.44147)
		(width 0.254)
		(layer "In2.Cu")
		(net "P5V_B_2_CC")
	)
	(segment
		(start 74.186796 -118.44147)
		(end 74.95286 -117.675406)
		(width 0.254)
		(layer "In2.Cu")
		(net "P5V_B_2_CC")
	)
	(segment
		(start 113.03 -100.986844)
		(end 113.033556 -100.9904)
		(width 0.508)
		(layer "F.Cu")
		(net "P5V_B_2")
	)
	(segment
		(start 259.21843 -229.60711)
		(end 259.204968 -229.593648)
		(width 0.508)
		(layer "F.Cu")
		(net "P5V_B_2")
	)
	(segment
		(start 58.03138 -114.110262)
		(end 62.724538 -114.110262)
		(width 0.508)
		(layer "F.Cu")
		(net "P5V_B_2")
	)
	(segment
		(start 52.730146 -117.67312)
		(end 52.730146 -117.671596)
		(width 0.508)
		(layer "F.Cu")
		(net "P5V_B_2")
	)
	(segment
		(start 143.256 -100.076)
		(end 143.256 -100.986844)
		(width 0.508)
		(layer "F.Cu")
		(net "P5V_B_2")
	)
	(segment
		(start 172.847 -100.076)
		(end 172.847 -100.986844)
		(width 0.508)
		(layer "F.Cu")
		(net "P5V_B_2")
	)
	(segment
		(start 258.092956 -229.593648)
		(end 257.880358 -229.38105)
		(width 0.508)
		(layer "F.Cu")
		(net "P5V_B_2")
	)
	(segment
		(start 144.526 -100.986844)
		(end 144.529556 -100.9904)
		(width 0.508)
		(layer "F.Cu")
		(net "P5V_B_2")
	)
	(segment
		(start 111.76 -100.986844)
		(end 111.763556 -100.9904)
		(width 0.508)
		(layer "F.Cu")
		(net "P5V_B_2")
	)
	(segment
		(start 144.526 -100.076)
		(end 144.526 -100.986844)
		(width 0.508)
		(layer "F.Cu")
		(net "P5V_B_2")
	)
	(segment
		(start 57.768236 -114.373406)
		(end 58.03138 -114.110262)
		(width 0.508)
		(layer "F.Cu")
		(net "P5V_B_2")
	)
	(segment
		(start 262.6868 -231.095296)
		(end 261.198614 -229.60711)
		(width 0.508)
		(layer "F.Cu")
		(net "P5V_B_2")
	)
	(segment
		(start 56.02986 -114.373406)
		(end 57.768236 -114.373406)
		(width 0.508)
		(layer "F.Cu")
		(net "P5V_B_2")
	)
	(segment
		(start 259.204968 -229.593648)
		(end 258.092956 -229.593648)
		(width 0.508)
		(layer "F.Cu")
		(net "P5V_B_2")
	)
	(segment
		(start 62.724538 -114.110262)
		(end 62.950344 -113.884456)
		(width 0.508)
		(layer "F.Cu")
		(net "P5V_B_2")
	)
	(segment
		(start 113.03 -100.076)
		(end 113.03 -100.986844)
		(width 0.508)
		(layer "F.Cu")
		(net "P5V_B_2")
	)
	(segment
		(start 172.847 -100.986844)
		(end 172.850556 -100.9904)
		(width 0.508)
		(layer "F.Cu")
		(net "P5V_B_2")
	)
	(segment
		(start 261.198614 -229.60711)
		(end 259.21843 -229.60711)
		(width 0.508)
		(layer "F.Cu")
		(net "P5V_B_2")
	)
	(segment
		(start 257.880358 -229.38105)
		(end 256.928874 -229.38105)
		(width 0.508)
		(layer "F.Cu")
		(net "P5V_B_2")
	)
	(segment
		(start 111.76 -100.076)
		(end 111.76 -100.986844)
		(width 0.508)
		(layer "F.Cu")
		(net "P5V_B_2")
	)
	(segment
		(start 143.256 -100.986844)
		(end 143.259556 -100.9904)
		(width 0.508)
		(layer "F.Cu")
		(net "P5V_B_2")
	)
	(segment
		(start 52.730146 -118.316756)
		(end 52.730146 -117.67312)
		(width 0.508)
		(layer "F.Cu")
		(net "P5V_B_2")
	)
	(segment
		(start 52.730146 -117.671596)
		(end 56.028336 -114.373406)
		(width 0.508)
		(layer "F.Cu")
		(net "P5V_B_2")
	)
	(segment
		(start 56.028336 -114.373406)
		(end 56.02986 -114.373406)
		(width 0.508)
		(layer "F.Cu")
		(net "P5V_B_2")
	)
	(segment
		(start 262.6868 -240.03)
		(end 262.6868 -231.095296)
		(width 0.508)
		(layer "F.Cu")
		(net "P5V_B_2")
	)
	(segment
		(start 62.950344 -113.884456)
		(end 65.310258 -113.884456)
		(width 0.508)
		(layer "F.Cu")
		(net "P5V_B_2")
	)
	(segment
		(start 174.117 -100.076)
		(end 174.117 -100.986844)
		(width 0.508)
		(layer "F.Cu")
		(net "P5V_B_2")
	)
	(segment
		(start 174.117 -100.986844)
		(end 174.120556 -100.9904)
		(width 0.508)
		(layer "F.Cu")
		(net "P5V_B_2")
	)
	(via
		(at 20.066 -22.225)
		(size 0.5588)
		(drill 0.3048)
		(layers "F.Cu" "B.Cu")
		(net "P5V_B_2")
	)
	(via
		(at 172.850556 -100.9904)
		(size 0.5588)
		(drill 0.3048)
		(layers "F.Cu" "B.Cu")
		(net "P5V_B_2")
	)
	(via
		(at 116.0526 -23.1394)
		(size 0.5588)
		(drill 0.3048)
		(layers "F.Cu" "B.Cu")
		(net "P5V_B_2")
	)
	(via
		(at 74.0283 -111.688626)
		(size 0.6096)
		(drill 0.3048)
		(layers "F.Cu" "B.Cu")
		(net "P5V_B_2")
	)
	(via
		(at 180.34 -22.225)
		(size 0.5588)
		(drill 0.3048)
		(layers "F.Cu" "B.Cu")
		(net "P5V_B_2")
	)
	(via
		(at 70.3834 -114.5794)
		(size 0.7112)
		(drill 0.4064)
		(layers "F.Cu" "B.Cu")
		(net "P5V_B_2")
	)
	(via
		(at 68.009008 -115.15344)
		(size 0.7112)
		(drill 0.4064)
		(layers "F.Cu" "B.Cu")
		(net "P5V_B_2")
	)
	(via
		(at 145.034 -22.225)
		(size 0.5588)
		(drill 0.3048)
		(layers "F.Cu" "B.Cu")
		(net "P5V_B_2")
	)
	(via
		(at 63.8048 -115.0874)
		(size 0.7112)
		(drill 0.4064)
		(layers "F.Cu" "B.Cu")
		(net "P5V_B_2")
	)
	(via
		(at 83.185 -22.225)
		(size 0.5588)
		(drill 0.3048)
		(layers "F.Cu" "B.Cu")
		(net "P5V_B_2")
	)
	(via
		(at 147.574 -137.16)
		(size 0.5588)
		(drill 0.3048)
		(layers "F.Cu" "B.Cu")
		(net "P5V_B_2")
	)
	(via
		(at 18.796 -22.225)
		(size 0.5588)
		(drill 0.3048)
		(layers "F.Cu" "B.Cu")
		(net "P5V_B_2")
	)
	(via
		(at 52.832 -22.225)
		(size 0.5588)
		(drill 0.3048)
		(layers "F.Cu" "B.Cu")
		(net "P5V_B_2")
	)
	(via
		(at 117.221 -137.16)
		(size 0.5588)
		(drill 0.3048)
		(layers "F.Cu" "B.Cu")
		(net "P5V_B_2")
	)
	(via
		(at 143.259556 -100.9904)
		(size 0.5588)
		(drill 0.3048)
		(layers "F.Cu" "B.Cu")
		(net "P5V_B_2")
	)
	(via
		(at 144.529556 -100.9904)
		(size 0.5588)
		(drill 0.3048)
		(layers "F.Cu" "B.Cu")
		(net "P5V_B_2")
	)
	(via
		(at 148.844 -22.225)
		(size 0.5588)
		(drill 0.3048)
		(layers "F.Cu" "B.Cu")
		(net "P5V_B_2")
	)
	(via
		(at 179.07 -22.225)
		(size 0.5588)
		(drill 0.3048)
		(layers "F.Cu" "B.Cu")
		(net "P5V_B_2")
	)
	(via
		(at 180.34 -137.16)
		(size 0.5588)
		(drill 0.3048)
		(layers "F.Cu" "B.Cu")
		(net "P5V_B_2")
	)
	(via
		(at 74.041 -114.5794)
		(size 0.7112)
		(drill 0.4064)
		(layers "F.Cu" "B.Cu")
		(net "P5V_B_2")
	)
	(via
		(at 115.951 -137.16)
		(size 0.5588)
		(drill 0.3048)
		(layers "F.Cu" "B.Cu")
		(net "P5V_B_2")
	)
	(via
		(at 75.2602 -113.3094)
		(size 0.7112)
		(drill 0.4064)
		(layers "F.Cu" "B.Cu")
		(net "P5V_B_2")
	)
	(via
		(at 192.849246 -256.2352)
		(size 0.5588)
		(drill 0.3048)
		(layers "F.Cu" "B.Cu")
		(net "P5V_B_2")
	)
	(via
		(at 84.455 -22.225)
		(size 0.5588)
		(drill 0.3048)
		(layers "F.Cu" "B.Cu")
		(net "P5V_B_2")
	)
	(via
		(at 148.844 -137.16)
		(size 0.5588)
		(drill 0.3048)
		(layers "F.Cu" "B.Cu")
		(net "P5V_B_2")
	)
	(via
		(at 51.562 -22.225)
		(size 0.5588)
		(drill 0.3048)
		(layers "F.Cu" "B.Cu")
		(net "P5V_B_2")
	)
	(via
		(at 71.6026 -114.5794)
		(size 0.7112)
		(drill 0.4064)
		(layers "F.Cu" "B.Cu")
		(net "P5V_B_2")
	)
	(via
		(at 75.86726 -112.094264)
		(size 0.6096)
		(drill 0.3048)
		(layers "F.Cu" "B.Cu")
		(net "P5V_B_2")
	)
	(via
		(at 176.403 -22.225)
		(size 0.5588)
		(drill 0.3048)
		(layers "F.Cu" "B.Cu")
		(net "P5V_B_2")
	)
	(via
		(at 71.6026 -113.3094)
		(size 0.7112)
		(drill 0.4064)
		(layers "F.Cu" "B.Cu")
		(net "P5V_B_2")
	)
	(via
		(at 111.763556 -100.9904)
		(size 0.5588)
		(drill 0.3048)
		(layers "F.Cu" "B.Cu")
		(net "P5V_B_2")
	)
	(via
		(at 113.411 -137.16)
		(size 0.5588)
		(drill 0.3048)
		(layers "F.Cu" "B.Cu")
		(net "P5V_B_2")
	)
	(via
		(at 66.529458 -113.884456)
		(size 0.7112)
		(drill 0.4064)
		(layers "F.Cu" "B.Cu")
		(net "P5V_B_2")
	)
	(via
		(at 114.7826 -23.1394)
		(size 0.5588)
		(drill 0.3048)
		(layers "F.Cu" "B.Cu")
		(net "P5V_B_2")
	)
	(via
		(at 146.304 -22.225)
		(size 0.5588)
		(drill 0.3048)
		(layers "F.Cu" "B.Cu")
		(net "P5V_B_2")
	)
	(via
		(at 177.8 -22.225)
		(size 0.5588)
		(drill 0.3048)
		(layers "F.Cu" "B.Cu")
		(net "P5V_B_2")
	)
	(via
		(at 117.3226 -23.1394)
		(size 0.5588)
		(drill 0.3048)
		(layers "F.Cu" "B.Cu")
		(net "P5V_B_2")
	)
	(via
		(at 63.8048 -111.3282)
		(size 0.7112)
		(drill 0.4064)
		(layers "F.Cu" "B.Cu")
		(net "P5V_B_2")
	)
	(via
		(at 63.8048 -116.3066)
		(size 0.7112)
		(drill 0.4064)
		(layers "F.Cu" "B.Cu")
		(net "P5V_B_2")
	)
	(via
		(at 177.8 -137.16)
		(size 0.5588)
		(drill 0.3048)
		(layers "F.Cu" "B.Cu")
		(net "P5V_B_2")
	)
	(via
		(at 179.07 -137.16)
		(size 0.5588)
		(drill 0.3048)
		(layers "F.Cu" "B.Cu")
		(net "P5V_B_2")
	)
	(via
		(at 114.681 -137.16)
		(size 0.5588)
		(drill 0.3048)
		(layers "F.Cu" "B.Cu")
		(net "P5V_B_2")
	)
	(via
		(at 57.768236 -114.373406)
		(size 0.6604)
		(drill 0.3302)
		(layers "F.Cu" "B.Cu")
		(net "P5V_B_2")
	)
	(via
		(at 72.8218 -114.5794)
		(size 0.7112)
		(drill 0.4064)
		(layers "F.Cu" "B.Cu")
		(net "P5V_B_2")
	)
	(via
		(at 22.606 -22.225)
		(size 0.5588)
		(drill 0.3048)
		(layers "F.Cu" "B.Cu")
		(net "P5V_B_2")
	)
	(via
		(at 75.230482 -110.080806)
		(size 0.6096)
		(drill 0.3048)
		(layers "F.Cu" "B.Cu")
		(net "P5V_B_2")
	)
	(via
		(at 81.915 -22.225)
		(size 0.5588)
		(drill 0.3048)
		(layers "F.Cu" "B.Cu")
		(net "P5V_B_2")
	)
	(via
		(at 54.102 -22.225)
		(size 0.5588)
		(drill 0.3048)
		(layers "F.Cu" "B.Cu")
		(net "P5V_B_2")
	)
	(via
		(at 113.033556 -100.9904)
		(size 0.5588)
		(drill 0.3048)
		(layers "F.Cu" "B.Cu")
		(net "P5V_B_2")
	)
	(via
		(at 168.821354 -130.302)
		(size 0.5588)
		(drill 0.3048)
		(layers "F.Cu" "B.Cu")
		(net "P5V_B_2")
	)
	(via
		(at 68.009008 -111.39424)
		(size 0.7112)
		(drill 0.4064)
		(layers "F.Cu" "B.Cu")
		(net "P5V_B_2")
	)
	(via
		(at 113.3856 -23.1394)
		(size 0.5588)
		(drill 0.3048)
		(layers "F.Cu" "B.Cu")
		(net "P5V_B_2")
	)
	(via
		(at 146.304 -137.16)
		(size 0.5588)
		(drill 0.3048)
		(layers "F.Cu" "B.Cu")
		(net "P5V_B_2")
	)
	(via
		(at 68.009008 -116.37264)
		(size 0.7112)
		(drill 0.4064)
		(layers "F.Cu" "B.Cu")
		(net "P5V_B_2")
	)
	(via
		(at 75.815444 -115.568984)
		(size 0.6096)
		(drill 0.3048)
		(layers "F.Cu" "B.Cu")
		(net "P5V_B_2")
	)
	(via
		(at 68.009008 -112.61344)
		(size 0.7112)
		(drill 0.4064)
		(layers "F.Cu" "B.Cu")
		(net "P5V_B_2")
	)
	(via
		(at 174.120556 -100.9904)
		(size 0.5588)
		(drill 0.3048)
		(layers "F.Cu" "B.Cu")
		(net "P5V_B_2")
	)
	(via
		(at 262.6868 -240.03)
		(size 0.5588)
		(drill 0.3048)
		(layers "F.Cu" "B.Cu")
		(net "P5V_B_2")
	)
	(via
		(at 63.8048 -112.5474)
		(size 0.7112)
		(drill 0.4064)
		(layers "F.Cu" "B.Cu")
		(net "P5V_B_2")
	)
	(via
		(at 69.1642 -114.5794)
		(size 0.7112)
		(drill 0.4064)
		(layers "F.Cu" "B.Cu")
		(net "P5V_B_2")
	)
	(via
		(at 21.336 -22.225)
		(size 0.5588)
		(drill 0.3048)
		(layers "F.Cu" "B.Cu")
		(net "P5V_B_2")
	)
	(via
		(at 145.034 -137.16)
		(size 0.5588)
		(drill 0.3048)
		(layers "F.Cu" "B.Cu")
		(net "P5V_B_2")
	)
	(via
		(at 147.574 -22.225)
		(size 0.5588)
		(drill 0.3048)
		(layers "F.Cu" "B.Cu")
		(net "P5V_B_2")
	)
	(via
		(at 70.3834 -113.3094)
		(size 0.7112)
		(drill 0.4064)
		(layers "F.Cu" "B.Cu")
		(net "P5V_B_2")
	)
	(via
		(at 85.725 -22.225)
		(size 0.5588)
		(drill 0.3048)
		(layers "F.Cu" "B.Cu")
		(net "P5V_B_2")
	)
	(via
		(at 69.1642 -113.3094)
		(size 0.7112)
		(drill 0.4064)
		(layers "F.Cu" "B.Cu")
		(net "P5V_B_2")
	)
	(via
		(at 74.041 -113.3094)
		(size 0.7112)
		(drill 0.4064)
		(layers "F.Cu" "B.Cu")
		(net "P5V_B_2")
	)
	(via
		(at 50.165 -22.225)
		(size 0.5588)
		(drill 0.3048)
		(layers "F.Cu" "B.Cu")
		(net "P5V_B_2")
	)
	(via
		(at 176.53 -137.16)
		(size 0.5588)
		(drill 0.3048)
		(layers "F.Cu" "B.Cu")
		(net "P5V_B_2")
	)
	(via
		(at 75.2602 -114.5794)
		(size 0.7112)
		(drill 0.4064)
		(layers "F.Cu" "B.Cu")
		(net "P5V_B_2")
	)
	(via
		(at 65.310258 -113.884456)
		(size 0.7112)
		(drill 0.4064)
		(layers "F.Cu" "B.Cu")
		(net "P5V_B_2")
	)
	(via
		(at 72.8218 -113.3094)
		(size 0.7112)
		(drill 0.4064)
		(layers "F.Cu" "B.Cu")
		(net "P5V_B_2")
	)
	(segment
		(start 61.198252 -110.912656)
		(end 57.791858 -110.912656)
		(width 0.508)
		(layer "B.Cu")
		(net "P5V_B_2")
	)
	(segment
		(start 57.791858 -110.912656)
		(end 57.141872 -111.562642)
		(width 0.508)
		(layer "B.Cu")
		(net "P5V_B_2")
	)
	(segment
		(start 57.141872 -111.562642)
		(end 57.141872 -117.146832)
		(width 0.508)
		(layer "B.Cu")
		(net "P5V_B_2")
	)
	(segment
		(start 74.95286 -116.976906)
		(end 74.95286 -116.405406)
		(width 0.254)
		(layer "B.Cu")
		(net "P5V_B_2")
	)
	(segment
		(start 178.04384 -169.96664)
		(end 178.04384 -213.649052)
		(width 0.508)
		(layer "In2.Cu")
		(net "P5V_B_2")
	)
	(segment
		(start 192.849246 -228.454458)
		(end 192.849246 -256.2352)
		(width 0.508)
		(layer "In2.Cu")
		(net "P5V_B_2")
	)
	(segment
		(start 178.04384 -213.649052)
		(end 192.849246 -228.454458)
		(width 0.508)
		(layer "In2.Cu")
		(net "P5V_B_2")
	)
	(segment
		(start 168.821354 -160.744154)
		(end 178.04384 -169.96664)
		(width 0.508)
		(layer "In2.Cu")
		(net "P5V_B_2")
	)
	(segment
		(start 168.821354 -130.302)
		(end 168.821354 -160.744154)
		(width 0.508)
		(layer "In2.Cu")
		(net "P5V_B_2")
	)
	(segment
		(start 202.592432 -265.965432)
		(end 192.8622 -256.2352)
		(width 0.508)
		(layer "In5.Cu")
		(net "P5V_B_2")
	)
	(segment
		(start 192.8622 -256.2352)
		(end 192.849246 -256.2352)
		(width 0.508)
		(layer "In5.Cu")
		(net "P5V_B_2")
	)
	(segment
		(start 262.6868 -240.03)
		(end 262.6868 -245.4402)
		(width 0.508)
		(layer "In5.Cu")
		(net "P5V_B_2")
	)
	(segment
		(start 242.161568 -265.965432)
		(end 202.592432 -265.965432)
		(width 0.508)
		(layer "In5.Cu")
		(net "P5V_B_2")
	)
	(segment
		(start 262.6868 -245.4402)
		(end 242.161568 -265.965432)
		(width 0.508)
		(layer "In5.Cu")
		(net "P5V_B_2")
	)
	(segment
		(start 17.783302 -225.57359)
		(end 17.933162 -225.42373)
		(width 0.254)
		(layer "F.Cu")
		(net "P5V_B_1_VREG")
	)
	(segment
		(start 17.783302 -226.57435)
		(end 17.783302 -225.57359)
		(width 0.254)
		(layer "F.Cu")
		(net "P5V_B_1_VREG")
	)
	(via
		(at 17.933162 -225.42373)
		(size 0.6604)
		(drill 0.3048)
		(layers "F.Cu" "B.Cu")
		(net "P5V_B_1_VREG")
	)
	(segment
		(start 19.140678 -225.417126)
		(end 17.939766 -225.417126)
		(width 0.254)
		(layer "B.Cu")
		(net "P5V_B_1_VREG")
	)
	(segment
		(start 16.711422 -225.42373)
		(end 17.933162 -225.42373)
		(width 0.254)
		(layer "B.Cu")
		(net "P5V_B_1_VREG")
	)
	(segment
		(start 17.939766 -225.417126)
		(end 17.933162 -225.42373)
		(width 0.254)
		(layer "B.Cu")
		(net "P5V_B_1_VREG")
	)
	(segment
		(start 16.703802 -225.43135)
		(end 16.711422 -225.42373)
		(width 0.254)
		(layer "B.Cu")
		(net "P5V_B_1_VREG")
	)
	(via
		(at 26.228802 -231.01935)
		(size 0.6096)
		(drill 0.3048)
		(layers "F.Cu" "B.Cu")
		(net "P5V_B_1_VFB_R")
	)
	(segment
		(start 26.422604 -229.626414)
		(end 25.618186 -229.626414)
		(width 0.254)
		(layer "B.Cu")
		(net "P5V_B_1_VFB_R")
	)
	(segment
		(start 26.422604 -230.825548)
		(end 26.228802 -231.01935)
		(width 0.254)
		(layer "B.Cu")
		(net "P5V_B_1_VFB_R")
	)
	(segment
		(start 24.895302 -230.63835)
		(end 25.847802 -230.63835)
		(width 0.254)
		(layer "B.Cu")
		(net "P5V_B_1_VFB_R")
	)
	(segment
		(start 25.847802 -230.63835)
		(end 26.228802 -231.01935)
		(width 0.254)
		(layer "B.Cu")
		(net "P5V_B_1_VFB_R")
	)
	(segment
		(start 26.422604 -229.626414)
		(end 26.422604 -230.825548)
		(width 0.254)
		(layer "B.Cu")
		(net "P5V_B_1_VFB_R")
	)
	(segment
		(start 25.618186 -229.626414)
		(end 25.5524 -229.6922)
		(width 0.254)
		(layer "B.Cu")
		(net "P5V_B_1_VFB_R")
	)
	(segment
		(start 25.5524 -229.6922)
		(end 24.9047 -229.6922)
		(width 0.254)
		(layer "B.Cu")
		(net "P5V_B_1_VFB_R")
	)
	(segment
		(start 27.357324 -223.027748)
		(end 26.651204 -223.027748)
		(width 0.508)
		(layer "F.Cu")
		(net "P5V_B_1_VBST_RC")
	)
	(segment
		(start 26.127202 -223.55175)
		(end 24.196802 -223.55175)
		(width 0.508)
		(layer "F.Cu")
		(net "P5V_B_1_VBST_RC")
	)
	(segment
		(start 26.651204 -223.027748)
		(end 26.127202 -223.55175)
		(width 0.508)
		(layer "F.Cu")
		(net "P5V_B_1_VBST_RC")
	)
	(via
		(at 26.127202 -223.55175)
		(size 0.6604)
		(drill 0.3302)
		(layers "F.Cu" "B.Cu")
		(net "P5V_B_1_VBST_RC")
	)
	(segment
		(start 25.282652 -226.1616)
		(end 25.929082 -226.1616)
		(width 0.508)
		(layer "F.Cu")
		(net "P5V_B_1_VBST")
	)
	(segment
		(start 24.196802 -225.07575)
		(end 25.282652 -226.1616)
		(width 0.508)
		(layer "F.Cu")
		(net "P5V_B_1_VBST")
	)
	(segment
		(start 25.929082 -226.1616)
		(end 25.960578 -226.193096)
		(width 0.508)
		(layer "F.Cu")
		(net "P5V_B_1_VBST")
	)
	(via
		(at 25.960578 -226.193096)
		(size 0.6604)
		(drill 0.3048)
		(layers "F.Cu" "B.Cu")
		(net "P5V_B_1_VBST")
	)
	(segment
		(start 24.039322 -225.916998)
		(end 25.68448 -225.916998)
		(width 0.3048)
		(layer "B.Cu")
		(net "P5V_B_1_VBST")
	)
	(segment
		(start 25.68448 -225.916998)
		(end 25.960578 -226.193096)
		(width 0.3048)
		(layer "B.Cu")
		(net "P5V_B_1_VBST")
	)
	(segment
		(start 18.113502 -229.24135)
		(end 18.113502 -229.74935)
		(width 0.254)
		(layer "F.Cu")
		(net "P5V_B_1_TRIP")
	)
	(segment
		(start 18.65122 -228.221286)
		(end 18.65122 -228.703632)
		(width 0.254)
		(layer "F.Cu")
		(net "P5V_B_1_TRIP")
	)
	(segment
		(start 18.113502 -230.96855)
		(end 18.113502 -229.74935)
		(width 0.254)
		(layer "F.Cu")
		(net "P5V_B_1_TRIP")
	)
	(segment
		(start 18.65122 -228.703632)
		(end 18.113502 -229.24135)
		(width 0.254)
		(layer "F.Cu")
		(net "P5V_B_1_TRIP")
	)
	(via
		(at 18.65122 -228.221286)
		(size 0.5588)
		(drill 0.3048)
		(layers "F.Cu" "B.Cu")
		(net "P5V_B_1_TRIP")
	)
	(via
		(at 18.113502 -229.74935)
		(size 0.6604)
		(drill 0.3302)
		(layers "F.Cu" "B.Cu")
		(net "P5V_B_1_TRIP")
	)
	(segment
		(start 18.532094 -226.916996)
		(end 18.304002 -227.145088)
		(width 0.254)
		(layer "B.Cu")
		(net "P5V_B_1_TRIP")
	)
	(segment
		(start 18.304002 -227.145088)
		(end 18.304002 -227.874068)
		(width 0.254)
		(layer "B.Cu")
		(net "P5V_B_1_TRIP")
	)
	(segment
		(start 19.140678 -226.916996)
		(end 18.532094 -226.916996)
		(width 0.254)
		(layer "B.Cu")
		(net "P5V_B_1_TRIP")
	)
	(segment
		(start 18.304002 -227.874068)
		(end 18.65122 -228.221286)
		(width 0.254)
		(layer "B.Cu")
		(net "P5V_B_1_TRIP")
	)
	(segment
		(start 27.350212 -221.75089)
		(end 26.101802 -221.75089)
		(width 0.508)
		(layer "F.Cu")
		(net "P5V_B_1_SNB")
	)
	(segment
		(start 25.934162 -221.58325)
		(end 26.101802 -221.75089)
		(width 0.508)
		(layer "F.Cu")
		(net "P5V_B_1_SNB")
	)
	(segment
		(start 24.077676 -221.58325)
		(end 25.934162 -221.58325)
		(width 0.508)
		(layer "F.Cu")
		(net "P5V_B_1_SNB")
	)
	(via
		(at 26.101802 -221.75089)
		(size 0.6604)
		(drill 0.3302)
		(layers "F.Cu" "B.Cu")
		(net "P5V_B_1_SNB")
	)
	(segment
		(start 20.7518 -228.717348)
		(end 21.209 -228.260148)
		(width 0.254)
		(layer "F.Cu")
		(net "P5V_B_1_ROVP")
	)
	(segment
		(start 20.7518 -229.06482)
		(end 20.7518 -228.717348)
		(width 0.254)
		(layer "F.Cu")
		(net "P5V_B_1_ROVP")
	)
	(via
		(at 21.209 -228.260148)
		(size 0.5588)
		(drill 0.3048)
		(layers "F.Cu" "B.Cu")
		(net "P5V_B_1_ROVP")
	)
	(via
		(at 27.016202 -226.92995)
		(size 0.6604)
		(drill 0.3048)
		(layers "F.Cu" "B.Cu")
		(net "P5V_B_1_ROVP")
	)
	(segment
		(start 24.039322 -225.417126)
		(end 24.671274 -225.417126)
		(width 0.254)
		(layer "B.Cu")
		(net "P5V_B_1_ROVP")
	)
	(segment
		(start 25.990296 -225.0948)
		(end 27.016202 -226.120706)
		(width 0.254)
		(layer "B.Cu")
		(net "P5V_B_1_ROVP")
	)
	(segment
		(start 24.671274 -225.417126)
		(end 24.9936 -225.0948)
		(width 0.254)
		(layer "B.Cu")
		(net "P5V_B_1_ROVP")
	)
	(segment
		(start 27.016202 -226.120706)
		(end 27.016202 -226.92995)
		(width 0.254)
		(layer "B.Cu")
		(net "P5V_B_1_ROVP")
	)
	(segment
		(start 24.9936 -225.0948)
		(end 25.990296 -225.0948)
		(width 0.254)
		(layer "B.Cu")
		(net "P5V_B_1_ROVP")
	)
	(segment
		(start 24.517604 -228.260148)
		(end 21.209 -228.260148)
		(width 0.254)
		(layer "In2.Cu")
		(net "P5V_B_1_ROVP")
	)
	(segment
		(start 27.016202 -226.92995)
		(end 25.847802 -226.92995)
		(width 0.254)
		(layer "In2.Cu")
		(net "P5V_B_1_ROVP")
	)
	(segment
		(start 25.847802 -226.92995)
		(end 24.517604 -228.260148)
		(width 0.254)
		(layer "In2.Cu")
		(net "P5V_B_1_ROVP")
	)
	(segment
		(start 18.672302 -226.57435)
		(end 19.015202 -226.57435)
		(width 0.254)
		(layer "F.Cu")
		(net "P5V_B_1_RF")
	)
	(segment
		(start 19.701002 -228.22535)
		(end 19.624802 -228.14915)
		(width 0.254)
		(layer "F.Cu")
		(net "P5V_B_1_RF")
	)
	(segment
		(start 19.624802 -228.14915)
		(end 19.624802 -227.18395)
		(width 0.254)
		(layer "F.Cu")
		(net "P5V_B_1_RF")
	)
	(segment
		(start 19.015202 -226.57435)
		(end 19.624802 -227.18395)
		(width 0.254)
		(layer "F.Cu")
		(net "P5V_B_1_RF")
	)
	(segment
		(start 19.701002 -229.05085)
		(end 19.701002 -228.22535)
		(width 0.254)
		(layer "F.Cu")
		(net "P5V_B_1_RF")
	)
	(via
		(at 19.624802 -227.18395)
		(size 0.6604)
		(drill 0.3302)
		(layers "F.Cu" "B.Cu")
		(net "P5V_B_1_RF")
	)
	(via
		(at 19.624802 -228.14915)
		(size 0.5588)
		(drill 0.3048)
		(layers "F.Cu" "B.Cu")
		(net "P5V_B_1_RF")
	)
	(segment
		(start 19.140678 -227.417122)
		(end 19.140678 -227.665026)
		(width 0.254)
		(layer "B.Cu")
		(net "P5V_B_1_RF")
	)
	(segment
		(start 19.140678 -227.665026)
		(end 19.624802 -228.14915)
		(width 0.254)
		(layer "B.Cu")
		(net "P5V_B_1_RF")
	)
	(segment
		(start 21.881338 -228.930454)
		(end 23.115524 -227.696268)
		(width 0.254)
		(layer "F.Cu")
		(net "P5V_B_1_PGOOD")
	)
	(segment
		(start 26.993088 -229.5017)
		(end 26.993088 -228.608636)
		(width 0.254)
		(layer "F.Cu")
		(net "P5V_B_1_PGOOD")
	)
	(segment
		(start 25.248362 -227.76815)
		(end 24.66467 -228.351842)
		(width 0.254)
		(layer "F.Cu")
		(net "P5V_B_1_PGOOD")
	)
	(segment
		(start 24.009096 -227.696268)
		(end 24.66467 -228.351842)
		(width 0.254)
		(layer "F.Cu")
		(net "P5V_B_1_PGOOD")
	)
	(segment
		(start 28.514802 -230.51135)
		(end 27.397202 -230.51135)
		(width 0.254)
		(layer "F.Cu")
		(net "P5V_B_1_PGOOD")
	)
	(segment
		(start 26.993088 -228.608636)
		(end 26.990802 -228.60635)
		(width 0.254)
		(layer "F.Cu")
		(net "P5V_B_1_PGOOD")
	)
	(segment
		(start 27.397202 -230.51135)
		(end 26.993088 -230.107236)
		(width 0.254)
		(layer "F.Cu")
		(net "P5V_B_1_PGOOD")
	)
	(segment
		(start 29.530802 -231.52735)
		(end 28.514802 -230.51135)
		(width 0.254)
		(layer "F.Cu")
		(net "P5V_B_1_PGOOD")
	)
	(segment
		(start 23.115524 -227.696268)
		(end 24.009096 -227.696268)
		(width 0.254)
		(layer "F.Cu")
		(net "P5V_B_1_PGOOD")
	)
	(segment
		(start 26.990802 -228.60635)
		(end 26.152602 -227.76815)
		(width 0.254)
		(layer "F.Cu")
		(net "P5V_B_1_PGOOD")
	)
	(segment
		(start 26.993088 -230.107236)
		(end 26.993088 -229.5017)
		(width 0.254)
		(layer "F.Cu")
		(net "P5V_B_1_PGOOD")
	)
	(segment
		(start 26.152602 -227.76815)
		(end 25.248362 -227.76815)
		(width 0.254)
		(layer "F.Cu")
		(net "P5V_B_1_PGOOD")
	)
	(via
		(at 26.990802 -228.60635)
		(size 0.5588)
		(drill 0.3048)
		(layers "F.Cu" "B.Cu")
		(net "P5V_B_1_PGOOD")
	)
	(segment
		(start 26.990802 -228.057202)
		(end 26.990802 -228.60635)
		(width 0.254)
		(layer "B.Cu")
		(net "P5V_B_1_PGOOD")
	)
	(segment
		(start 24.893524 -226.417124)
		(end 25.6032 -227.1268)
		(width 0.254)
		(layer "B.Cu")
		(net "P5V_B_1_PGOOD")
	)
	(segment
		(start 25.6032 -227.1268)
		(end 26.0604 -227.1268)
		(width 0.254)
		(layer "B.Cu")
		(net "P5V_B_1_PGOOD")
	)
	(segment
		(start 24.039322 -226.417124)
		(end 24.893524 -226.417124)
		(width 0.254)
		(layer "B.Cu")
		(net "P5V_B_1_PGOOD")
	)
	(segment
		(start 26.0604 -227.1268)
		(end 26.990802 -228.057202)
		(width 0.254)
		(layer "B.Cu")
		(net "P5V_B_1_PGOOD")
	)
	(segment
		(start 22.770338 -229.96271)
		(end 22.76983 -229.963218)
		(width 0.254)
		(layer "F.Cu")
		(net "P5V_B_1_MODE")
	)
	(segment
		(start 22.770338 -228.930454)
		(end 22.770338 -229.96271)
		(width 0.254)
		(layer "F.Cu")
		(net "P5V_B_1_MODE")
	)
	(segment
		(start 22.76983 -229.963218)
		(end 22.76983 -230.202486)
		(width 0.254)
		(layer "F.Cu")
		(net "P5V_B_1_MODE")
	)
	(segment
		(start 17.5006 -228.0158)
		(end 17.186402 -228.329998)
		(width 0.254)
		(layer "F.Cu")
		(net "P5V_B_1_MODE")
	)
	(segment
		(start 17.948402 -232.16235)
		(end 21.656802 -232.16235)
		(width 0.254)
		(layer "F.Cu")
		(net "P5V_B_1_MODE")
	)
	(segment
		(start 21.656802 -232.16235)
		(end 21.910802 -231.90835)
		(width 0.254)
		(layer "F.Cu")
		(net "P5V_B_1_MODE")
	)
	(segment
		(start 22.76983 -230.202486)
		(end 22.253956 -230.71836)
		(width 0.254)
		(layer "F.Cu")
		(net "P5V_B_1_MODE")
	)
	(segment
		(start 22.253956 -231.565196)
		(end 21.910802 -231.90835)
		(width 0.254)
		(layer "F.Cu")
		(net "P5V_B_1_MODE")
	)
	(segment
		(start 17.186402 -228.329998)
		(end 17.186402 -231.40035)
		(width 0.254)
		(layer "F.Cu")
		(net "P5V_B_1_MODE")
	)
	(segment
		(start 17.186402 -231.40035)
		(end 17.948402 -232.16235)
		(width 0.254)
		(layer "F.Cu")
		(net "P5V_B_1_MODE")
	)
	(segment
		(start 22.253956 -230.71836)
		(end 22.253956 -231.565196)
		(width 0.254)
		(layer "F.Cu")
		(net "P5V_B_1_MODE")
	)
	(via
		(at 17.5006 -228.0158)
		(size 0.5588)
		(drill 0.3048)
		(layers "F.Cu" "B.Cu")
		(net "P5V_B_1_MODE")
	)
	(via
		(at 21.910802 -231.90835)
		(size 0.6604)
		(drill 0.3302)
		(layers "F.Cu" "B.Cu")
		(net "P5V_B_1_MODE")
	)
	(segment
		(start 19.140678 -226.417124)
		(end 18.359628 -226.417124)
		(width 0.254)
		(layer "B.Cu")
		(net "P5V_B_1_MODE")
	)
	(segment
		(start 18.359628 -226.417124)
		(end 17.5006 -227.276152)
		(width 0.254)
		(layer "B.Cu")
		(net "P5V_B_1_MODE")
	)
	(segment
		(start 17.5006 -227.276152)
		(end 17.5006 -228.0158)
		(width 0.254)
		(layer "B.Cu")
		(net "P5V_B_1_MODE")
	)
	(via
		(at 32.070802 -232.16235)
		(size 0.6096)
		(drill 0.3048)
		(layers "F.Cu" "B.Cu")
		(net "P5V_B_1_LL_R")
	)
	(segment
		(start 28.239212 -221.13494)
		(end 28.641802 -220.73235)
		(width 0.508)
		(layer "F.Cu")
		(net "P5V_B_1_LL")
	)
	(segment
		(start 28.895802 -220.47835)
		(end 28.641802 -220.73235)
		(width 0.508)
		(layer "F.Cu")
		(net "P5V_B_1_LL")
	)
	(segment
		(start 28.239212 -221.75089)
		(end 28.239212 -221.13494)
		(width 0.508)
		(layer "F.Cu")
		(net "P5V_B_1_LL")
	)
	(segment
		(start 28.246324 -223.027748)
		(end 28.246324 -224.223072)
		(width 0.6096)
		(layer "F.Cu")
		(net "P5V_B_1_LL")
	)
	(segment
		(start 28.246324 -224.223072)
		(end 28.794202 -224.77095)
		(width 0.6096)
		(layer "F.Cu")
		(net "P5V_B_1_LL")
	)
	(segment
		(start 28.895802 -219.71635)
		(end 28.895802 -220.47835)
		(width 0.508)
		(layer "F.Cu")
		(net "P5V_B_1_LL")
	)
	(via
		(at 28.794202 -224.77095)
		(size 0.7112)
		(drill 0.4064)
		(layers "F.Cu" "B.Cu")
		(net "P5V_B_1_LL")
	)
	(via
		(at 28.895802 -219.71635)
		(size 0.5588)
		(drill 0.3048)
		(layers "F.Cu" "B.Cu")
		(net "P5V_B_1_LL")
	)
	(via
		(at 28.641802 -220.73235)
		(size 0.6604)
		(drill 0.3302)
		(layers "F.Cu" "B.Cu")
		(net "P5V_B_1_LL")
	)
	(segment
		(start 27.556206 -222.0976)
		(end 30.134052 -222.0976)
		(width 0.508)
		(layer "B.Cu")
		(net "P5V_B_1_LL")
	)
	(segment
		(start 30.920944 -222.884492)
		(end 30.920944 -228.656896)
		(width 0.508)
		(layer "B.Cu")
		(net "P5V_B_1_LL")
	)
	(segment
		(start 30.134052 -222.0976)
		(end 30.920944 -222.884492)
		(width 0.508)
		(layer "B.Cu")
		(net "P5V_B_1_LL")
	)
	(segment
		(start 25.466802 -229.49535)
		(end 25.466802 -228.499416)
		(width 0.254)
		(layer "F.Cu")
		(net "P5V_B_1_EN_R")
	)
	(segment
		(start 26.914602 -231.71785)
		(end 25.974802 -231.71785)
		(width 0.254)
		(layer "F.Cu")
		(net "P5V_B_1_EN_R")
	)
	(segment
		(start 25.784302 -231.90835)
		(end 25.974802 -231.71785)
		(width 0.254)
		(layer "F.Cu")
		(net "P5V_B_1_EN_R")
	)
	(segment
		(start 24.704802 -231.90835)
		(end 25.784302 -231.90835)
		(width 0.254)
		(layer "F.Cu")
		(net "P5V_B_1_EN_R")
	)
	(segment
		(start 24.704802 -231.90835)
		(end 24.704802 -231.20985)
		(width 0.254)
		(layer "F.Cu")
		(net "P5V_B_1_EN_R")
	)
	(segment
		(start 25.466802 -228.499416)
		(end 25.47874 -228.487478)
		(width 0.254)
		(layer "F.Cu")
		(net "P5V_B_1_EN_R")
	)
	(segment
		(start 24.895302 -231.01935)
		(end 24.895302 -230.63835)
		(width 0.254)
		(layer "F.Cu")
		(net "P5V_B_1_EN_R")
	)
	(segment
		(start 27.003502 -231.62895)
		(end 26.914602 -231.71785)
		(width 0.254)
		(layer "F.Cu")
		(net "P5V_B_1_EN_R")
	)
	(segment
		(start 24.895302 -230.63835)
		(end 24.895302 -230.06685)
		(width 0.254)
		(layer "F.Cu")
		(net "P5V_B_1_EN_R")
	)
	(segment
		(start 24.704802 -231.20985)
		(end 24.895302 -231.01935)
		(width 0.254)
		(layer "F.Cu")
		(net "P5V_B_1_EN_R")
	)
	(segment
		(start 24.895302 -230.06685)
		(end 25.466802 -229.49535)
		(width 0.254)
		(layer "F.Cu")
		(net "P5V_B_1_EN_R")
	)
	(via
		(at 25.47874 -228.487478)
		(size 0.5588)
		(drill 0.3048)
		(layers "F.Cu" "B.Cu")
		(net "P5V_B_1_EN_R")
	)
	(via
		(at 24.704802 -231.90835)
		(size 0.6604)
		(drill 0.3302)
		(layers "F.Cu" "B.Cu")
		(net "P5V_B_1_EN_R")
	)
	(segment
		(start 24.9936 -228.002338)
		(end 25.47874 -228.487478)
		(width 0.254)
		(layer "B.Cu")
		(net "P5V_B_1_EN_R")
	)
	(segment
		(start 24.682196 -226.916996)
		(end 24.9936 -227.2284)
		(width 0.254)
		(layer "B.Cu")
		(net "P5V_B_1_EN_R")
	)
	(segment
		(start 24.9936 -227.2284)
		(end 24.9936 -228.002338)
		(width 0.254)
		(layer "B.Cu")
		(net "P5V_B_1_EN_R")
	)
	(segment
		(start 24.039322 -226.916996)
		(end 24.682196 -226.916996)
		(width 0.254)
		(layer "B.Cu")
		(net "P5V_B_1_EN_R")
	)
	(via
		(at 50.104802 -228.86035)
		(size 0.5588)
		(drill 0.3048)
		(layers "F.Cu" "B.Cu")
		(net "P5V_B_1_CC")
	)
	(via
		(at 29.099002 -229.626414)
		(size 0.6604)
		(drill 0.3048)
		(layers "F.Cu" "B.Cu")
		(net "P5V_B_1_CC")
	)
	(segment
		(start 50.104802 -228.28885)
		(end 50.104802 -228.86035)
		(width 0.254)
		(layer "B.Cu")
		(net "P5V_B_1_CC")
	)
	(segment
		(start 27.946604 -229.626414)
		(end 29.099002 -229.626414)
		(width 0.254)
		(layer "B.Cu")
		(net "P5V_B_1_CC")
	)
	(segment
		(start 29.099002 -229.626414)
		(end 49.338738 -229.626414)
		(width 0.254)
		(layer "In2.Cu")
		(net "P5V_B_1_CC")
	)
	(segment
		(start 49.338738 -229.626414)
		(end 50.104802 -228.86035)
		(width 0.254)
		(layer "In2.Cu")
		(net "P5V_B_1_CC")
	)
	(segment
		(start 31.181802 -225.55835)
		(end 32.841692 -225.55835)
		(width 0.508)
		(layer "F.Cu")
		(net "P5V_B_1")
	)
	(segment
		(start 171.958 -224.917)
		(end 170.942 -224.917)
		(width 0.508)
		(layer "F.Cu")
		(net "P5V_B_1")
	)
	(segment
		(start 55.4228 -100.076)
		(end 55.4228 -100.986844)
		(width 0.508)
		(layer "F.Cu")
		(net "P5V_B_1")
	)
	(segment
		(start 49.784 -215.011)
		(end 49.784 -215.918796)
		(width 0.508)
		(layer "F.Cu")
		(net "P5V_B_1")
	)
	(segment
		(start 80.137 -215.918796)
		(end 80.143604 -215.9254)
		(width 0.508)
		(layer "F.Cu")
		(net "P5V_B_1")
	)
	(segment
		(start 17.399 -215.011)
		(end 17.399 -215.918796)
		(width 0.508)
		(layer "F.Cu")
		(net "P5V_B_1")
	)
	(segment
		(start 80.137 -100.986844)
		(end 80.140556 -100.9904)
		(width 0.508)
		(layer "F.Cu")
		(net "P5V_B_1")
	)
	(segment
		(start 54.1528 -100.986844)
		(end 54.156356 -100.9904)
		(width 0.508)
		(layer "F.Cu")
		(net "P5V_B_1")
	)
	(segment
		(start 81.407 -215.011)
		(end 81.407 -215.918796)
		(width 0.508)
		(layer "F.Cu")
		(net "P5V_B_1")
	)
	(segment
		(start 144.526 -215.011)
		(end 144.526 -215.918796)
		(width 0.508)
		(layer "F.Cu")
		(net "P5V_B_1")
	)
	(segment
		(start 143.256 -215.918796)
		(end 143.262604 -215.9254)
		(width 0.508)
		(layer "F.Cu")
		(net "P5V_B_1")
	)
	(segment
		(start 254.127 -229.395528)
		(end 254.141478 -229.38105)
		(width 0.508)
		(layer "F.Cu")
		(net "P5V_B_1")
	)
	(segment
		(start 173.1772 -226.1362)
		(end 196.494146 -226.1362)
		(width 0.508)
		(layer "F.Cu")
		(net "P5V_B_1")
	)
	(segment
		(start 253.706122 -229.38105)
		(end 253.222252 -228.89718)
		(width 0.4572)
		(layer "F.Cu")
		(net "P5V_B_1")
	)
	(segment
		(start 18.669 -215.011)
		(end 18.669 -215.918796)
		(width 0.508)
		(layer "F.Cu")
		(net "P5V_B_1")
	)
	(segment
		(start 55.4228 -100.986844)
		(end 55.426356 -100.9904)
		(width 0.508)
		(layer "F.Cu")
		(net "P5V_B_1")
	)
	(segment
		(start 81.407 -100.076)
		(end 81.407 -100.986844)
		(width 0.508)
		(layer "F.Cu")
		(net "P5V_B_1")
	)
	(segment
		(start 27.882088 -229.5017)
		(end 27.882088 -228.858064)
		(width 0.508)
		(layer "F.Cu")
		(net "P5V_B_1")
	)
	(segment
		(start 172.847 -215.918796)
		(end 172.853604 -215.9254)
		(width 0.508)
		(layer "F.Cu")
		(net "P5V_B_1")
	)
	(segment
		(start 171.958 -224.917)
		(end 173.1772 -226.1362)
		(width 0.508)
		(layer "F.Cu")
		(net "P5V_B_1")
	)
	(segment
		(start 113.03 -215.918796)
		(end 113.036604 -215.9254)
		(width 0.508)
		(layer "F.Cu")
		(net "P5V_B_1")
	)
	(segment
		(start 143.256 -215.011)
		(end 143.256 -215.918796)
		(width 0.508)
		(layer "F.Cu")
		(net "P5V_B_1")
	)
	(segment
		(start 144.526 -215.918796)
		(end 144.532604 -215.9254)
		(width 0.508)
		(layer "F.Cu")
		(net "P5V_B_1")
	)
	(segment
		(start 80.137 -215.011)
		(end 80.137 -215.918796)
		(width 0.508)
		(layer "F.Cu")
		(net "P5V_B_1")
	)
	(segment
		(start 48.514 -215.918796)
		(end 48.520604 -215.9254)
		(width 0.508)
		(layer "F.Cu")
		(net "P5V_B_1")
	)
	(segment
		(start 197.129146 -226.7712)
		(end 207.1116 -226.7712)
		(width 0.508)
		(layer "F.Cu")
		(net "P5V_B_1")
	)
	(segment
		(start 80.137 -100.076)
		(end 80.137 -100.986844)
		(width 0.508)
		(layer "F.Cu")
		(net "P5V_B_1")
	)
	(segment
		(start 18.669 -215.918796)
		(end 18.675604 -215.9254)
		(width 0.508)
		(layer "F.Cu")
		(net "P5V_B_1")
	)
	(segment
		(start 111.76 -215.918796)
		(end 111.766604 -215.9254)
		(width 0.508)
		(layer "F.Cu")
		(net "P5V_B_1")
	)
	(segment
		(start 174.117 -215.918796)
		(end 174.123604 -215.9254)
		(width 0.508)
		(layer "F.Cu")
		(net "P5V_B_1")
	)
	(segment
		(start 113.03 -215.011)
		(end 113.03 -215.918796)
		(width 0.508)
		(layer "F.Cu")
		(net "P5V_B_1")
	)
	(segment
		(start 54.1528 -100.076)
		(end 54.1528 -100.986844)
		(width 0.508)
		(layer "F.Cu")
		(net "P5V_B_1")
	)
	(segment
		(start 81.407 -215.918796)
		(end 81.413604 -215.9254)
		(width 0.508)
		(layer "F.Cu")
		(net "P5V_B_1")
	)
	(segment
		(start 49.784 -215.918796)
		(end 49.790604 -215.9254)
		(width 0.508)
		(layer "F.Cu")
		(net "P5V_B_1")
	)
	(segment
		(start 20.210018 -100.163884)
		(end 20.210018 -101.074728)
		(width 0.508)
		(layer "F.Cu")
		(net "P5V_B_1")
	)
	(segment
		(start 21.480018 -101.074728)
		(end 21.483574 -101.078284)
		(width 0.508)
		(layer "F.Cu")
		(net "P5V_B_1")
	)
	(segment
		(start 196.494146 -226.1362)
		(end 197.129146 -226.7712)
		(width 0.508)
		(layer "F.Cu")
		(net "P5V_B_1")
	)
	(segment
		(start 172.847 -215.011)
		(end 172.847 -215.918796)
		(width 0.508)
		(layer "F.Cu")
		(net "P5V_B_1")
	)
	(segment
		(start 27.882088 -228.858064)
		(end 31.181802 -225.55835)
		(width 0.508)
		(layer "F.Cu")
		(net "P5V_B_1")
	)
	(segment
		(start 17.399 -215.918796)
		(end 17.405604 -215.9254)
		(width 0.508)
		(layer "F.Cu")
		(net "P5V_B_1")
	)
	(segment
		(start 40.3606 -224.9678)
		(end 33.432242 -224.9678)
		(width 0.508)
		(layer "F.Cu")
		(net "P5V_B_1")
	)
	(segment
		(start 254.141478 -229.38105)
		(end 253.706122 -229.38105)
		(width 0.4572)
		(layer "F.Cu")
		(net "P5V_B_1")
	)
	(segment
		(start 81.407 -100.986844)
		(end 81.410556 -100.9904)
		(width 0.508)
		(layer "F.Cu")
		(net "P5V_B_1")
	)
	(segment
		(start 111.76 -215.011)
		(end 111.76 -215.918796)
		(width 0.508)
		(layer "F.Cu")
		(net "P5V_B_1")
	)
	(segment
		(start 254.127 -230.4415)
		(end 254.127 -229.395528)
		(width 0.508)
		(layer "F.Cu")
		(net "P5V_B_1")
	)
	(segment
		(start 48.514 -215.011)
		(end 48.514 -215.918796)
		(width 0.508)
		(layer "F.Cu")
		(net "P5V_B_1")
	)
	(segment
		(start 174.117 -215.011)
		(end 174.117 -215.918796)
		(width 0.508)
		(layer "F.Cu")
		(net "P5V_B_1")
	)
	(segment
		(start 21.480018 -100.163884)
		(end 21.480018 -101.074728)
		(width 0.508)
		(layer "F.Cu")
		(net "P5V_B_1")
	)
	(segment
		(start 20.210018 -101.074728)
		(end 20.213574 -101.078284)
		(width 0.508)
		(layer "F.Cu")
		(net "P5V_B_1")
	)
	(segment
		(start 33.432242 -224.9678)
		(end 32.841692 -225.55835)
		(width 0.508)
		(layer "F.Cu")
		(net "P5V_B_1")
	)
	(via
		(at 18.796 -137.16)
		(size 0.5588)
		(drill 0.3048)
		(layers "F.Cu" "B.Cu")
		(net "P5V_B_1")
	)
	(via
		(at 85.725 -252.222)
		(size 0.5588)
		(drill 0.3048)
		(layers "F.Cu" "B.Cu")
		(net "P5V_B_1")
	)
	(via
		(at 253.222252 -228.89718)
		(size 0.5588)
		(drill 0.3048)
		(layers "F.Cu" "B.Cu")
		(net "P5V_B_1")
	)
	(via
		(at 51.689 -252.222)
		(size 0.5588)
		(drill 0.3048)
		(layers "F.Cu" "B.Cu")
		(net "P5V_B_1")
	)
	(via
		(at 147.574 -252.222)
		(size 0.5588)
		(drill 0.3048)
		(layers "F.Cu" "B.Cu")
		(net "P5V_B_1")
	)
	(via
		(at 55.426356 -100.9904)
		(size 0.5588)
		(drill 0.3048)
		(layers "F.Cu" "B.Cu")
		(net "P5V_B_1")
	)
	(via
		(at 148.844 -252.222)
		(size 0.5588)
		(drill 0.3048)
		(layers "F.Cu" "B.Cu")
		(net "P5V_B_1")
	)
	(via
		(at 144.532604 -215.9254)
		(size 0.5588)
		(drill 0.3048)
		(layers "F.Cu" "B.Cu")
		(net "P5V_B_1")
	)
	(via
		(at 81.915 -137.16)
		(size 0.5588)
		(drill 0.3048)
		(layers "F.Cu" "B.Cu")
		(net "P5V_B_1")
	)
	(via
		(at 42.98061 -222.52559)
		(size 0.7112)
		(drill 0.4064)
		(layers "F.Cu" "B.Cu")
		(net "P5V_B_1")
	)
	(via
		(at 143.262604 -215.9254)
		(size 0.5588)
		(drill 0.3048)
		(layers "F.Cu" "B.Cu")
		(net "P5V_B_1")
	)
	(via
		(at 39.17061 -222.52559)
		(size 0.7112)
		(drill 0.4064)
		(layers "F.Cu" "B.Cu")
		(net "P5V_B_1")
	)
	(via
		(at 45.355002 -225.71075)
		(size 0.7112)
		(drill 0.4064)
		(layers "F.Cu" "B.Cu")
		(net "P5V_B_1")
	)
	(via
		(at 50.231802 -225.71075)
		(size 0.7112)
		(drill 0.4064)
		(layers "F.Cu" "B.Cu")
		(net "P5V_B_1")
	)
	(via
		(at 113.036604 -215.9254)
		(size 0.5588)
		(drill 0.3048)
		(layers "F.Cu" "B.Cu")
		(net "P5V_B_1")
	)
	(via
		(at 80.143604 -215.9254)
		(size 0.5588)
		(drill 0.3048)
		(layers "F.Cu" "B.Cu")
		(net "P5V_B_1")
	)
	(via
		(at 47.793402 -224.44075)
		(size 0.7112)
		(drill 0.4064)
		(layers "F.Cu" "B.Cu")
		(net "P5V_B_1")
	)
	(via
		(at 172.853604 -215.9254)
		(size 0.5588)
		(drill 0.3048)
		(layers "F.Cu" "B.Cu")
		(net "P5V_B_1")
	)
	(via
		(at 50.419 -252.222)
		(size 0.5588)
		(drill 0.3048)
		(layers "F.Cu" "B.Cu")
		(net "P5V_B_1")
	)
	(via
		(at 47.793402 -225.71075)
		(size 0.7112)
		(drill 0.4064)
		(layers "F.Cu" "B.Cu")
		(net "P5V_B_1")
	)
	(via
		(at 83.185 -137.16)
		(size 0.5588)
		(drill 0.3048)
		(layers "F.Cu" "B.Cu")
		(net "P5V_B_1")
	)
	(via
		(at 39.17061 -226.28479)
		(size 0.7112)
		(drill 0.4064)
		(layers "F.Cu" "B.Cu")
		(net "P5V_B_1")
	)
	(via
		(at 81.915 -252.222)
		(size 0.5588)
		(drill 0.3048)
		(layers "F.Cu" "B.Cu")
		(net "P5V_B_1")
	)
	(via
		(at 54.229 -252.222)
		(size 0.5588)
		(drill 0.3048)
		(layers "F.Cu" "B.Cu")
		(net "P5V_B_1")
	)
	(via
		(at 39.17061 -223.74479)
		(size 0.7112)
		(drill 0.4064)
		(layers "F.Cu" "B.Cu")
		(net "P5V_B_1")
	)
	(via
		(at 179.07 -252.222)
		(size 0.5588)
		(drill 0.3048)
		(layers "F.Cu" "B.Cu")
		(net "P5V_B_1")
	)
	(via
		(at 52.959 -252.222)
		(size 0.5588)
		(drill 0.3048)
		(layers "F.Cu" "B.Cu")
		(net "P5V_B_1")
	)
	(via
		(at 48.87595 -220.744542)
		(size 0.6096)
		(drill 0.3048)
		(layers "F.Cu" "B.Cu")
		(net "P5V_B_1")
	)
	(via
		(at 21.483574 -101.078284)
		(size 0.5588)
		(drill 0.3048)
		(layers "F.Cu" "B.Cu")
		(net "P5V_B_1")
	)
	(via
		(at 32.841692 -225.55835)
		(size 0.6604)
		(drill 0.3302)
		(layers "F.Cu" "B.Cu")
		(net "P5V_B_1")
	)
	(via
		(at 115.951 -252.222)
		(size 0.5588)
		(drill 0.3048)
		(layers "F.Cu" "B.Cu")
		(net "P5V_B_1")
	)
	(via
		(at 146.304 -252.222)
		(size 0.5588)
		(drill 0.3048)
		(layers "F.Cu" "B.Cu")
		(net "P5V_B_1")
	)
	(via
		(at 52.832 -137.16)
		(size 0.5588)
		(drill 0.3048)
		(layers "F.Cu" "B.Cu")
		(net "P5V_B_1")
	)
	(via
		(at 42.98061 -226.28479)
		(size 0.7112)
		(drill 0.4064)
		(layers "F.Cu" "B.Cu")
		(net "P5V_B_1")
	)
	(via
		(at 177.8 -252.222)
		(size 0.5588)
		(drill 0.3048)
		(layers "F.Cu" "B.Cu")
		(net "P5V_B_1")
	)
	(via
		(at 111.766604 -215.9254)
		(size 0.5588)
		(drill 0.3048)
		(layers "F.Cu" "B.Cu")
		(net "P5V_B_1")
	)
	(via
		(at 49.012602 -225.71075)
		(size 0.7112)
		(drill 0.4064)
		(layers "F.Cu" "B.Cu")
		(net "P5V_B_1")
	)
	(via
		(at 48.520604 -215.9254)
		(size 0.5588)
		(drill 0.3048)
		(layers "F.Cu" "B.Cu")
		(net "P5V_B_1")
	)
	(via
		(at 145.034 -252.222)
		(size 0.5588)
		(drill 0.3048)
		(layers "F.Cu" "B.Cu")
		(net "P5V_B_1")
	)
	(via
		(at 54.156356 -100.9904)
		(size 0.5588)
		(drill 0.3048)
		(layers "F.Cu" "B.Cu")
		(net "P5V_B_1")
	)
	(via
		(at 113.411 -252.222)
		(size 0.5588)
		(drill 0.3048)
		(layers "F.Cu" "B.Cu")
		(net "P5V_B_1")
	)
	(via
		(at 46.574202 -225.71075)
		(size 0.7112)
		(drill 0.4064)
		(layers "F.Cu" "B.Cu")
		(net "P5V_B_1")
	)
	(via
		(at 21.336 -137.16)
		(size 0.5588)
		(drill 0.3048)
		(layers "F.Cu" "B.Cu")
		(net "P5V_B_1")
	)
	(via
		(at 41.7068 -224.9678)
		(size 0.7112)
		(drill 0.4064)
		(layers "F.Cu" "B.Cu")
		(net "P5V_B_1")
	)
	(via
		(at 49.012602 -224.44075)
		(size 0.7112)
		(drill 0.4064)
		(layers "F.Cu" "B.Cu")
		(net "P5V_B_1")
	)
	(via
		(at 50.231802 -224.44075)
		(size 0.7112)
		(drill 0.4064)
		(layers "F.Cu" "B.Cu")
		(net "P5V_B_1")
	)
	(via
		(at 44.832524 -136.98093)
		(size 0.5588)
		(drill 0.3048)
		(layers "F.Cu" "B.Cu")
		(net "P5V_B_1")
	)
	(via
		(at 18.796 -252.222)
		(size 0.5588)
		(drill 0.3048)
		(layers "F.Cu" "B.Cu")
		(net "P5V_B_1")
	)
	(via
		(at 49.790604 -215.9254)
		(size 0.5588)
		(drill 0.3048)
		(layers "F.Cu" "B.Cu")
		(net "P5V_B_1")
	)
	(via
		(at 85.725 -137.16)
		(size 0.5588)
		(drill 0.3048)
		(layers "F.Cu" "B.Cu")
		(net "P5V_B_1")
	)
	(via
		(at 207.1116 -226.7712)
		(size 0.5588)
		(drill 0.3048)
		(layers "F.Cu" "B.Cu")
		(net "P5V_B_1")
	)
	(via
		(at 50.292 -137.16)
		(size 0.5588)
		(drill 0.3048)
		(layers "F.Cu" "B.Cu")
		(net "P5V_B_1")
	)
	(via
		(at 81.410556 -100.9904)
		(size 0.5588)
		(drill 0.3048)
		(layers "F.Cu" "B.Cu")
		(net "P5V_B_1")
	)
	(via
		(at 42.98061 -223.74479)
		(size 0.7112)
		(drill 0.4064)
		(layers "F.Cu" "B.Cu")
		(net "P5V_B_1")
	)
	(via
		(at 22.606 -137.16)
		(size 0.5588)
		(drill 0.3048)
		(layers "F.Cu" "B.Cu")
		(net "P5V_B_1")
	)
	(via
		(at 42.98061 -227.50399)
		(size 0.7112)
		(drill 0.4064)
		(layers "F.Cu" "B.Cu")
		(net "P5V_B_1")
	)
	(via
		(at 51.562 -137.16)
		(size 0.5588)
		(drill 0.3048)
		(layers "F.Cu" "B.Cu")
		(net "P5V_B_1")
	)
	(via
		(at 40.3606 -224.9678)
		(size 0.7112)
		(drill 0.4064)
		(layers "F.Cu" "B.Cu")
		(net "P5V_B_1")
	)
	(via
		(at 45.355002 -224.44075)
		(size 0.7112)
		(drill 0.4064)
		(layers "F.Cu" "B.Cu")
		(net "P5V_B_1")
	)
	(via
		(at 17.405604 -215.9254)
		(size 0.5588)
		(drill 0.3048)
		(layers "F.Cu" "B.Cu")
		(net "P5V_B_1")
	)
	(via
		(at 84.455 -137.16)
		(size 0.5588)
		(drill 0.3048)
		(layers "F.Cu" "B.Cu")
		(net "P5V_B_1")
	)
	(via
		(at 80.140556 -100.9904)
		(size 0.5588)
		(drill 0.3048)
		(layers "F.Cu" "B.Cu")
		(net "P5V_B_1")
	)
	(via
		(at 180.34 -252.222)
		(size 0.5588)
		(drill 0.3048)
		(layers "F.Cu" "B.Cu")
		(net "P5V_B_1")
	)
	(via
		(at 51.251612 -223.11995)
		(size 0.6096)
		(drill 0.3048)
		(layers "F.Cu" "B.Cu")
		(net "P5V_B_1")
	)
	(via
		(at 54.102 -137.16)
		(size 0.5588)
		(drill 0.3048)
		(layers "F.Cu" "B.Cu")
		(net "P5V_B_1")
	)
	(via
		(at 114.681 -252.222)
		(size 0.5588)
		(drill 0.3048)
		(layers "F.Cu" "B.Cu")
		(net "P5V_B_1")
	)
	(via
		(at 171.958 -224.917)
		(size 0.5588)
		(drill 0.3048)
		(layers "F.Cu" "B.Cu")
		(net "P5V_B_1")
	)
	(via
		(at 83.185 -252.222)
		(size 0.5588)
		(drill 0.3048)
		(layers "F.Cu" "B.Cu")
		(net "P5V_B_1")
	)
	(via
		(at 44.135802 -225.71075)
		(size 0.7112)
		(drill 0.4064)
		(layers "F.Cu" "B.Cu")
		(net "P5V_B_1")
	)
	(via
		(at 21.336 -252.222)
		(size 0.5588)
		(drill 0.3048)
		(layers "F.Cu" "B.Cu")
		(net "P5V_B_1")
	)
	(via
		(at 22.606 -252.222)
		(size 0.5588)
		(drill 0.3048)
		(layers "F.Cu" "B.Cu")
		(net "P5V_B_1")
	)
	(via
		(at 20.066 -252.222)
		(size 0.5588)
		(drill 0.3048)
		(layers "F.Cu" "B.Cu")
		(net "P5V_B_1")
	)
	(via
		(at 81.413604 -215.9254)
		(size 0.5588)
		(drill 0.3048)
		(layers "F.Cu" "B.Cu")
		(net "P5V_B_1")
	)
	(via
		(at 20.066 -137.16)
		(size 0.5588)
		(drill 0.3048)
		(layers "F.Cu" "B.Cu")
		(net "P5V_B_1")
	)
	(via
		(at 170.942 -224.917)
		(size 0.5588)
		(drill 0.3048)
		(layers "F.Cu" "B.Cu")
		(net "P5V_B_1")
	)
	(via
		(at 39.17061 -227.50399)
		(size 0.7112)
		(drill 0.4064)
		(layers "F.Cu" "B.Cu")
		(net "P5V_B_1")
	)
	(via
		(at 174.123604 -215.9254)
		(size 0.5588)
		(drill 0.3048)
		(layers "F.Cu" "B.Cu")
		(net "P5V_B_1")
	)
	(via
		(at 18.675604 -215.9254)
		(size 0.5588)
		(drill 0.3048)
		(layers "F.Cu" "B.Cu")
		(net "P5V_B_1")
	)
	(via
		(at 46.574202 -224.44075)
		(size 0.7112)
		(drill 0.4064)
		(layers "F.Cu" "B.Cu")
		(net "P5V_B_1")
	)
	(via
		(at 117.221 -252.222)
		(size 0.5588)
		(drill 0.3048)
		(layers "F.Cu" "B.Cu")
		(net "P5V_B_1")
	)
	(via
		(at 84.455 -252.222)
		(size 0.5588)
		(drill 0.3048)
		(layers "F.Cu" "B.Cu")
		(net "P5V_B_1")
	)
	(via
		(at 20.213574 -101.078284)
		(size 0.5588)
		(drill 0.3048)
		(layers "F.Cu" "B.Cu")
		(net "P5V_B_1")
	)
	(via
		(at 176.53 -252.222)
		(size 0.5588)
		(drill 0.3048)
		(layers "F.Cu" "B.Cu")
		(net "P5V_B_1")
	)
	(via
		(at 44.135802 -224.44075)
		(size 0.7112)
		(drill 0.4064)
		(layers "F.Cu" "B.Cu")
		(net "P5V_B_1")
	)
	(segment
		(start 32.9438 -222.0976)
		(end 32.293814 -222.747586)
		(width 0.508)
		(layer "B.Cu")
		(net "P5V_B_1")
	)
	(segment
		(start 32.293814 -222.747586)
		(end 32.293814 -228.331776)
		(width 0.508)
		(layer "B.Cu")
		(net "P5V_B_1")
	)
	(segment
		(start 50.104802 -228.16185)
		(end 50.104802 -227.59035)
		(width 0.254)
		(layer "B.Cu")
		(net "P5V_B_1")
	)
	(segment
		(start 36.350194 -222.0976)
		(end 32.9438 -222.0976)
		(width 0.508)
		(layer "B.Cu")
		(net "P5V_B_1")
	)
	(segment
		(start 113.036604 -215.9254)
		(end 111.766604 -215.9254)
		(width 0.508)
		(layer "In2.Cu")
		(net "P5V_B_1")
	)
	(segment
		(start 20.213574 -115.74145)
		(end 20.213574 -101.078284)
		(width 0.508)
		(layer "In2.Cu")
		(net "P5V_B_1")
	)
	(segment
		(start 144.532604 -215.9254)
		(end 143.262604 -215.9254)
		(width 0.508)
		(layer "In2.Cu")
		(net "P5V_B_1")
	)
	(segment
		(start 36.009326 -128.157732)
		(end 36.009326 -125.622558)
		(width 0.508)
		(layer "In2.Cu")
		(net "P5V_B_1")
	)
	(segment
		(start 33.344612 -122.957844)
		(end 27.429968 -122.957844)
		(width 0.508)
		(layer "In2.Cu")
		(net "P5V_B_1")
	)
	(segment
		(start 44.832524 -136.98093)
		(end 36.009326 -128.157732)
		(width 0.508)
		(layer "In2.Cu")
		(net "P5V_B_1")
	)
	(segment
		(start 172.853604 -215.9254)
		(end 174.123604 -215.9254)
		(width 0.508)
		(layer "In2.Cu")
		(net "P5V_B_1")
	)
	(segment
		(start 27.429968 -122.957844)
		(end 20.213574 -115.74145)
		(width 0.508)
		(layer "In2.Cu")
		(net "P5V_B_1")
	)
	(segment
		(start 36.009326 -125.622558)
		(end 33.344612 -122.957844)
		(width 0.508)
		(layer "In2.Cu")
		(net "P5V_B_1")
	)
	(segment
		(start 79.554578 -100.404422)
		(end 75.071986 -100.404422)
		(width 0.508)
		(layer "In5.Cu")
		(net "P5V_B_1")
	)
	(segment
		(start 45.149516 -101.078284)
		(end 21.483574 -101.078284)
		(width 0.508)
		(layer "In5.Cu")
		(net "P5V_B_1")
	)
	(segment
		(start 245.144798 -226.187)
		(end 246.507 -227.549202)
		(width 0.508)
		(layer "In5.Cu")
		(net "P5V_B_1")
	)
	(segment
		(start 207.1116 -226.7712)
		(end 212.5218 -226.7712)
		(width 0.508)
		(layer "In5.Cu")
		(net "P5V_B_1")
	)
	(segment
		(start 54.156356 -100.9904)
		(end 53.602636 -100.43668)
		(width 0.508)
		(layer "In5.Cu")
		(net "P5V_B_1")
	)
	(segment
		(start 20.213574 -101.078284)
		(end 21.483574 -101.078284)
		(width 0.508)
		(layer "In5.Cu")
		(net "P5V_B_1")
	)
	(segment
		(start 54.156356 -100.9904)
		(end 55.426356 -100.9904)
		(width 0.508)
		(layer "In5.Cu")
		(net "P5V_B_1")
	)
	(segment
		(start 212.5218 -226.7712)
		(end 215.1634 -229.4128)
		(width 0.508)
		(layer "In5.Cu")
		(net "P5V_B_1")
	)
	(segment
		(start 215.1634 -229.4128)
		(end 220.759782 -229.4128)
		(width 0.508)
		(layer "In5.Cu")
		(net "P5V_B_1")
	)
	(segment
		(start 53.602636 -100.43668)
		(end 45.79112 -100.43668)
		(width 0.508)
		(layer "In5.Cu")
		(net "P5V_B_1")
	)
	(segment
		(start 222.25 -227.922582)
		(end 239.961928 -227.922582)
		(width 0.508)
		(layer "In5.Cu")
		(net "P5V_B_1")
	)
	(segment
		(start 246.507 -227.549202)
		(end 249.374152 -227.549202)
		(width 0.508)
		(layer "In5.Cu")
		(net "P5V_B_1")
	)
	(segment
		(start 45.79112 -100.43668)
		(end 45.149516 -101.078284)
		(width 0.508)
		(layer "In5.Cu")
		(net "P5V_B_1")
	)
	(segment
		(start 241.939064 -226.187)
		(end 245.144798 -226.187)
		(width 0.508)
		(layer "In5.Cu")
		(net "P5V_B_1")
	)
	(segment
		(start 220.759782 -229.4128)
		(end 222.25 -227.922582)
		(width 0.508)
		(layer "In5.Cu")
		(net "P5V_B_1")
	)
	(segment
		(start 74.486008 -100.9904)
		(end 55.426356 -100.9904)
		(width 0.508)
		(layer "In5.Cu")
		(net "P5V_B_1")
	)
	(segment
		(start 249.394726 -227.528628)
		(end 251.8537 -227.528628)
		(width 0.508)
		(layer "In5.Cu")
		(net "P5V_B_1")
	)
	(segment
		(start 251.8537 -227.528628)
		(end 253.222252 -228.89718)
		(width 0.508)
		(layer "In5.Cu")
		(net "P5V_B_1")
	)
	(segment
		(start 75.071986 -100.404422)
		(end 74.486008 -100.9904)
		(width 0.508)
		(layer "In5.Cu")
		(net "P5V_B_1")
	)
	(segment
		(start 249.374152 -227.549202)
		(end 249.394726 -227.528628)
		(width 0.508)
		(layer "In5.Cu")
		(net "P5V_B_1")
	)
	(segment
		(start 239.961928 -227.922582)
		(end 240.26876 -227.857304)
		(width 0.508)
		(layer "In5.Cu")
		(net "P5V_B_1")
	)
	(segment
		(start 80.140556 -100.9904)
		(end 81.410556 -100.9904)
		(width 0.508)
		(layer "In5.Cu")
		(net "P5V_B_1")
	)
	(segment
		(start 80.140556 -100.9904)
		(end 79.554578 -100.404422)
		(width 0.508)
		(layer "In5.Cu")
		(net "P5V_B_1")
	)
	(segment
		(start 240.26876 -227.857304)
		(end 241.939064 -226.187)
		(width 0.508)
		(layer "In5.Cu")
		(net "P5V_B_1")
	)
	(segment
		(start 478.2058 -134.7724)
		(end 478.3582 -134.62)
		(width 0.508)
		(layer "F.Cu")
		(net "P3V3_STBY_B")
	)
	(segment
		(start 267.7795 -206.883)
		(end 267.106654 -206.883)
		(width 0.508)
		(layer "F.Cu")
		(net "P3V3_STBY_B")
	)
	(segment
		(start 250.318016 -131.7117)
		(end 250.606052 -131.999736)
		(width 0.508)
		(layer "F.Cu")
		(net "P3V3_STBY_B")
	)
	(segment
		(start 352.298 -261.2009)
		(end 352.298 -260.2738)
		(width 0.508)
		(layer "F.Cu")
		(net "P3V3_STBY_B")
	)
	(segment
		(start 181.1909 -248.4882)
		(end 182.0672 -248.4882)
		(width 0.508)
		(layer "F.Cu")
		(net "P3V3_STBY_B")
	)
	(segment
		(start 293.24173 -237.69701)
		(end 294.019224 -236.919516)
		(width 0.508)
		(layer "F.Cu")
		(net "P3V3_STBY_B")
	)
	(segment
		(start 352.1456 -146.1897)
		(end 351.523808 -145.567908)
		(width 0.508)
		(layer "F.Cu")
		(net "P3V3_STBY_B")
	)
	(segment
		(start 427.863 -13.1445)
		(end 427.863 -12.319)
		(width 0.508)
		(layer "F.Cu")
		(net "P3V3_STBY_B")
	)
	(segment
		(start 257.43789 -215.08339)
		(end 257.3655 -215.011)
		(width 0.3048)
		(layer "F.Cu")
		(net "P3V3_STBY_B")
	)
	(segment
		(start 213.93658 -237.846108)
		(end 213.075012 -237.846108)
		(width 0.508)
		(layer "F.Cu")
		(net "P3V3_STBY_B")
	)
	(segment
		(start 477.647 -11.6205)
		(end 477.647 -12.4206)
		(width 0.508)
		(layer "F.Cu")
		(net "P3V3_STBY_B")
	)
	(segment
		(start 284.451552 -354.780342)
		(end 284.451552 -355.040438)
		(width 0.2032)
		(layer "F.Cu")
		(net "P3V3_STBY_B")
	)
	(segment
		(start 130.3655 -148.082)
		(end 131.567936 -148.082)
		(width 0.508)
		(layer "F.Cu")
		(net "P3V3_STBY_B")
	)
	(segment
		(start 267.106654 -206.883)
		(end 266.896596 -207.093058)
		(width 0.508)
		(layer "F.Cu")
		(net "P3V3_STBY_B")
	)
	(segment
		(start 220.3704 -197.8914)
		(end 220.3704 -196.8627)
		(width 0.508)
		(layer "F.Cu")
		(net "P3V3_STBY_B")
	)
	(segment
		(start 477.9645 -19.685)
		(end 478.896934 -19.685)
		(width 0.508)
		(layer "F.Cu")
		(net "P3V3_STBY_B")
	)
	(segment
		(start 415.3662 -30.3784)
		(end 415.3662 -31.2039)
		(width 0.508)
		(layer "F.Cu")
		(net "P3V3_STBY_B")
	)
	(segment
		(start 229.766114 -199.671686)
		(end 230.6066 -198.8312)
		(width 0.508)
		(layer "F.Cu")
		(net "P3V3_STBY_B")
	)
	(segment
		(start 301.8155 -226.7204)
		(end 301.8155 -228.473)
		(width 0.508)
		(layer "F.Cu")
		(net "P3V3_STBY_B")
	)
	(segment
		(start 219.142564 -108.200698)
		(end 218.571826 -108.771436)
		(width 0.508)
		(layer "F.Cu")
		(net "P3V3_STBY_B")
	)
	(segment
		(start 206.8957 -196.088)
		(end 205.9178 -196.088)
		(width 0.508)
		(layer "F.Cu")
		(net "P3V3_STBY_B")
	)
	(segment
		(start 213.35238 -248.33072)
		(end 213.35238 -249.29338)
		(width 0.508)
		(layer "F.Cu")
		(net "P3V3_STBY_B")
	)
	(segment
		(start 477.4311 -134.7724)
		(end 478.2058 -134.7724)
		(width 0.508)
		(layer "F.Cu")
		(net "P3V3_STBY_B")
	)
	(segment
		(start 235.52404 -233.45648)
		(end 235.52404 -234.30738)
		(width 0.508)
		(layer "F.Cu")
		(net "P3V3_STBY_B")
	)
	(segment
		(start 260.672834 -211.051902)
		(end 260.2611 -211.051902)
		(width 0.508)
		(layer "F.Cu")
		(net "P3V3_STBY_B")
	)
	(segment
		(start 206.8703 -198.3994)
		(end 206.8703 -199.517)
		(width 0.508)
		(layer "F.Cu")
		(net "P3V3_STBY_B")
	)
	(segment
		(start 283.809948 -356.304342)
		(end 283.809948 -357.142542)
		(width 0.508)
		(layer "F.Cu")
		(net "P3V3_STBY_B")
	)
	(segment
		(start 263.559036 -216.33307)
		(end 263.558274 -216.333832)
		(width 0.508)
		(layer "F.Cu")
		(net "P3V3_STBY_B")
	)
	(segment
		(start 301.8155 -226.7204)
		(end 301.8155 -225.044)
		(width 0.508)
		(layer "F.Cu")
		(net "P3V3_STBY_B")
	)
	(segment
		(start 320.7004 -145.65503)
		(end 321.204844 -145.150586)
		(width 0.508)
		(layer "F.Cu")
		(net "P3V3_STBY_B")
	)
	(segment
		(start 223.114362 -205.994)
		(end 223.828864 -206.708502)
		(width 0.508)
		(layer "F.Cu")
		(net "P3V3_STBY_B")
	)
	(segment
		(start 249.7582 -131.7117)
		(end 250.318016 -131.7117)
		(width 0.508)
		(layer "F.Cu")
		(net "P3V3_STBY_B")
	)
	(segment
		(start 244.82298 -197.86854)
		(end 245.868444 -197.86854)
		(width 0.508)
		(layer "F.Cu")
		(net "P3V3_STBY_B")
	)
	(segment
		(start 96.393 -31.2039)
		(end 96.393 -30.353)
		(width 0.508)
		(layer "F.Cu")
		(net "P3V3_STBY_B")
	)
	(segment
		(start 300.933612 -231.7369)
		(end 301.8155 -230.855012)
		(width 0.508)
		(layer "F.Cu")
		(net "P3V3_STBY_B")
	)
	(segment
		(start 212.46846 -163.81476)
		(end 212.65896 -164.00526)
		(width 0.508)
		(layer "F.Cu")
		(net "P3V3_STBY_B")
	)
	(segment
		(start 23.4315 -247.015)
		(end 24.257 -247.015)
		(width 0.508)
		(layer "F.Cu")
		(net "P3V3_STBY_B")
	)
	(segment
		(start 383.8448 -145.3642)
		(end 383.8448 -146.1897)
		(width 0.508)
		(layer "F.Cu")
		(net "P3V3_STBY_B")
	)
	(segment
		(start 466.9663 -7.4422)
		(end 467.0171 -7.493)
		(width 0.508)
		(layer "F.Cu")
		(net "P3V3_STBY_B")
	)
	(segment
		(start 35.7505 -148.5265)
		(end 36.322 -149.098)
		(width 0.508)
		(layer "F.Cu")
		(net "P3V3_STBY_B")
	)
	(segment
		(start 162.8648 -263.144)
		(end 163.3474 -262.6614)
		(width 0.508)
		(layer "F.Cu")
		(net "P3V3_STBY_B")
	)
	(segment
		(start 223.240854 -220.565726)
		(end 223.46158 -220.565726)
		(width 0.508)
		(layer "F.Cu")
		(net "P3V3_STBY_B")
	)
	(segment
		(start 229.738936 -199.671686)
		(end 229.766114 -199.671686)
		(width 0.508)
		(layer "F.Cu")
		(net "P3V3_STBY_B")
	)
	(segment
		(start 207.111854 -166.41826)
		(end 207.047592 -166.353998)
		(width 0.508)
		(layer "F.Cu")
		(net "P3V3_STBY_B")
	)
	(segment
		(start 222.123 -197.8914)
		(end 220.3704 -197.8914)
		(width 0.508)
		(layer "F.Cu")
		(net "P3V3_STBY_B")
	)
	(segment
		(start 333.248 -243.1415)
		(end 333.248 -242.316)
		(width 0.508)
		(layer "F.Cu")
		(net "P3V3_STBY_B")
	)
	(segment
		(start 257.34772 -217.45702)
		(end 257.34772 -216.68232)
		(width 0.3048)
		(layer "F.Cu")
		(net "P3V3_STBY_B")
	)
	(segment
		(start 181.1401 -133.4262)
		(end 181.9402 -133.4262)
		(width 0.508)
		(layer "F.Cu")
		(net "P3V3_STBY_B")
	)
	(segment
		(start 218.515692 -105.115868)
		(end 218.515692 -105.964228)
		(width 0.508)
		(layer "F.Cu")
		(net "P3V3_STBY_B")
	)
	(segment
		(start 222.18396 -163.37026)
		(end 223.19996 -163.37026)
		(width 0.508)
		(layer "F.Cu")
		(net "P3V3_STBY_B")
	)
	(segment
		(start 301.8155 -230.855012)
		(end 301.8155 -230.1494)
		(width 0.508)
		(layer "F.Cu")
		(net "P3V3_STBY_B")
	)
	(segment
		(start 230.378 -194.6529)
		(end 231.284272 -194.6529)
		(width 0.508)
		(layer "F.Cu")
		(net "P3V3_STBY_B")
	)
	(segment
		(start 383.8956 -31.2039)
		(end 383.8956 -30.353)
		(width 0.508)
		(layer "F.Cu")
		(net "P3V3_STBY_B")
	)
	(segment
		(start 251.4854 -212.1408)
		(end 251.4854 -211.6455)
		(width 0.508)
		(layer "F.Cu")
		(net "P3V3_STBY_B")
	)
	(segment
		(start 54.9021 -133.4008)
		(end 55.5752 -133.4008)
		(width 0.508)
		(layer "F.Cu")
		(net "P3V3_STBY_B")
	)
	(segment
		(start 251.4854 -211.6455)
		(end 252.3236 -211.6455)
		(width 0.508)
		(layer "F.Cu")
		(net "P3V3_STBY_B")
	)
	(segment
		(start 222.5675 -203.606654)
		(end 222.569024 -203.60513)
		(width 0.508)
		(layer "F.Cu")
		(net "P3V3_STBY_B")
	)
	(segment
		(start 213.0806 -205.71968)
		(end 212.0773 -204.71638)
		(width 0.3556)
		(layer "F.Cu")
		(net "P3V3_STBY_B")
	)
	(segment
		(start 288.064448 -347.096842)
		(end 288.064448 -346.271342)
		(width 0.508)
		(layer "F.Cu")
		(net "P3V3_STBY_B")
	)
	(segment
		(start 243.3955 -228.219)
		(end 243.3955 -227.188776)
		(width 0.508)
		(layer "F.Cu")
		(net "P3V3_STBY_B")
	)
	(segment
		(start 242.57 -138.2649)
		(end 242.57 -137.3632)
		(width 0.508)
		(layer "F.Cu")
		(net "P3V3_STBY_B")
	)
	(segment
		(start 262.405368 -209.582258)
		(end 263.114028 -209.582258)
		(width 0.508)
		(layer "F.Cu")
		(net "P3V3_STBY_B")
	)
	(segment
		(start 260.615684 -213.995)
		(end 260.840728 -213.769956)
		(width 0.508)
		(layer "F.Cu")
		(net "P3V3_STBY_B")
	)
	(segment
		(start 251.394468 -223.4057)
		(end 251.394468 -224.2566)
		(width 0.508)
		(layer "F.Cu")
		(net "P3V3_STBY_B")
	)
	(segment
		(start 211.79028 -238.04372)
		(end 211.95538 -238.04372)
		(width 0.3556)
		(layer "F.Cu")
		(net "P3V3_STBY_B")
	)
	(segment
		(start 427.863 -128.2065)
		(end 427.863 -127.381)
		(width 0.508)
		(layer "F.Cu")
		(net "P3V3_STBY_B")
	)
	(segment
		(start 222.4405 -220.853)
		(end 222.95358 -220.853)
		(width 0.508)
		(layer "F.Cu")
		(net "P3V3_STBY_B")
	)
	(segment
		(start 149.6441 -133.4516)
		(end 150.4696 -133.4516)
		(width 0.508)
		(layer "F.Cu")
		(net "P3V3_STBY_B")
	)
	(segment
		(start 98.8695 -148.082)
		(end 98.8695 -149.159468)
		(width 0.508)
		(layer "F.Cu")
		(net "P3V3_STBY_B")
	)
	(segment
		(start 208.90738 -233.769408)
		(end 208.905602 -233.76763)
		(width 0.508)
		(layer "F.Cu")
		(net "P3V3_STBY_B")
	)
	(segment
		(start 279.9969 -348.2848)
		(end 279.1714 -348.2848)
		(width 0.508)
		(layer "F.Cu")
		(net "P3V3_STBY_B")
	)
	(segment
		(start 267.658596 -210.4136)
		(end 267.7795 -210.4136)
		(width 0.508)
		(layer "F.Cu")
		(net "P3V3_STBY_B")
	)
	(segment
		(start 221.180406 -192.151)
		(end 222.175324 -191.156082)
		(width 0.508)
		(layer "F.Cu")
		(net "P3V3_STBY_B")
	)
	(segment
		(start 285.016448 -347.096842)
		(end 285.016448 -346.271342)
		(width 0.508)
		(layer "F.Cu")
		(net "P3V3_STBY_B")
	)
	(segment
		(start 55.0545 -248.4374)
		(end 55.8546 -248.4374)
		(width 0.508)
		(layer "F.Cu")
		(net "P3V3_STBY_B")
	)
	(segment
		(start 221.1197 -192.151)
		(end 221.180406 -192.151)
		(width 0.508)
		(layer "F.Cu")
		(net "P3V3_STBY_B")
	)
	(segment
		(start 267.7795 -213.248494)
		(end 266.720828 -214.307166)
		(width 0.508)
		(layer "F.Cu")
		(net "P3V3_STBY_B")
	)
	(segment
		(start 222.5675 -203.962)
		(end 222.5675 -203.606654)
		(width 0.508)
		(layer "F.Cu")
		(net "P3V3_STBY_B")
	)
	(segment
		(start 118.0465 -133.4262)
		(end 118.059454 -133.4262)
		(width 0.508)
		(layer "F.Cu")
		(net "P3V3_STBY_B")
	)
	(segment
		(start 220.3704 -196.8627)
		(end 220.2307 -196.723)
		(width 0.508)
		(layer "F.Cu")
		(net "P3V3_STBY_B")
	)
	(segment
		(start 283.809948 -357.142542)
		(end 287.64992 -360.982514)
		(width 0.508)
		(layer "F.Cu")
		(net "P3V3_STBY_B")
	)
	(segment
		(start 222.18396 -165.40226)
		(end 223.19996 -165.40226)
		(width 0.508)
		(layer "F.Cu")
		(net "P3V3_STBY_B")
	)
	(segment
		(start 446.9384 -31.2039)
		(end 446.9384 -30.353)
		(width 0.508)
		(layer "F.Cu")
		(net "P3V3_STBY_B")
	)
	(segment
		(start 284.451552 -355.040438)
		(end 283.809948 -355.682042)
		(width 0.2032)
		(layer "F.Cu")
		(net "P3V3_STBY_B")
	)
	(segment
		(start 64.7446 -31.2039)
		(end 64.7446 -30.3784)
		(width 0.508)
		(layer "F.Cu")
		(net "P3V3_STBY_B")
	)
	(segment
		(start 279.9969 -349.3008)
		(end 279.1714 -349.3008)
		(width 0.508)
		(layer "F.Cu")
		(net "P3V3_STBY_B")
	)
	(segment
		(start 212.97138 -237.85322)
		(end 212.14588 -237.85322)
		(width 0.508)
		(layer "F.Cu")
		(net "P3V3_STBY_B")
	)
	(segment
		(start 263.558274 -217.419936)
		(end 263.558274 -218.1733)
		(width 0.508)
		(layer "F.Cu")
		(net "P3V3_STBY_B")
	)
	(segment
		(start 333.248 -128.2065)
		(end 333.248 -127.381)
		(width 0.508)
		(layer "F.Cu")
		(net "P3V3_STBY_B")
	)
	(segment
		(start 245.387622 -214.8205)
		(end 245.881652 -214.8205)
		(width 0.508)
		(layer "F.Cu")
		(net "P3V3_STBY_B")
	)
	(segment
		(start 159.512 -31.1785)
		(end 159.512 -30.353)
		(width 0.508)
		(layer "F.Cu")
		(net "P3V3_STBY_B")
	)
	(segment
		(start 478.896934 -19.685)
		(end 478.919032 -19.662902)
		(width 0.508)
		(layer "F.Cu")
		(net "P3V3_STBY_B")
	)
	(segment
		(start 239.415066 -140.050266)
		(end 238.399066 -140.050266)
		(width 0.508)
		(layer "F.Cu")
		(net "P3V3_STBY_B")
	)
	(segment
		(start 258.0513 -213.95944)
		(end 258.0513 -214.5157)
		(width 0.508)
		(layer "F.Cu")
		(net "P3V3_STBY_B")
	)
	(segment
		(start 212.46846 -162.019488)
		(end 212.46846 -162.98926)
		(width 0.508)
		(layer "F.Cu")
		(net "P3V3_STBY_B")
	)
	(segment
		(start 35.7505 -263.144)
		(end 35.7505 -263.9695)
		(width 0.508)
		(layer "F.Cu")
		(net "P3V3_STBY_B")
	)
	(segment
		(start 396.367 -128.2065)
		(end 396.367 -127.381)
		(width 0.508)
		(layer "F.Cu")
		(net "P3V3_STBY_B")
	)
	(segment
		(start 208.3816 -227.965)
		(end 209.3595 -227.965)
		(width 0.508)
		(layer "F.Cu")
		(net "P3V3_STBY_B")
	)
	(segment
		(start 352.3488 -30.060646)
		(end 353.529646 -28.8798)
		(width 0.508)
		(layer "F.Cu")
		(net "P3V3_STBY_B")
	)
	(segment
		(start 320.7004 -146.1897)
		(end 320.7004 -145.65503)
		(width 0.508)
		(layer "F.Cu")
		(net "P3V3_STBY_B")
	)
	(segment
		(start 266.901676 -209.65668)
		(end 267.658596 -210.4136)
		(width 0.508)
		(layer "F.Cu")
		(net "P3V3_STBY_B")
	)
	(segment
		(start 258.0513 -212.852)
		(end 258.0513 -213.95944)
		(width 0.508)
		(layer "F.Cu")
		(net "P3V3_STBY_B")
	)
	(segment
		(start 323.109336 -145.150586)
		(end 323.134228 -145.125694)
		(width 0.508)
		(layer "F.Cu")
		(net "P3V3_STBY_B")
	)
	(segment
		(start 250.327668 -223.4057)
		(end 250.327668 -224.2566)
		(width 0.508)
		(layer "F.Cu")
		(net "P3V3_STBY_B")
	)
	(segment
		(start 240.919 -214.8205)
		(end 240.919 -213.9696)
		(width 0.508)
		(layer "F.Cu")
		(net "P3V3_STBY_B")
	)
	(segment
		(start 149.6441 -18.4912)
		(end 149.6441 -17.653)
		(width 0.508)
		(layer "F.Cu")
		(net "P3V3_STBY_B")
	)
	(segment
		(start 211.95538 -248.33072)
		(end 211.95538 -249.29338)
		(width 0.508)
		(layer "F.Cu")
		(net "P3V3_STBY_B")
	)
	(segment
		(start 208.9785 -207.01)
		(end 207.792066 -207.01)
		(width 0.508)
		(layer "F.Cu")
		(net "P3V3_STBY_B")
	)
	(segment
		(start 236.29874 -218.07424)
		(end 237.236 -219.0115)
		(width 0.635)
		(layer "F.Cu")
		(net "P3V3_STBY_B")
	)
	(segment
		(start 246.898668 -223.8375)
		(end 246.898668 -224.6884)
		(width 0.508)
		(layer "F.Cu")
		(net "P3V3_STBY_B")
	)
	(segment
		(start 287.64992 -360.982514)
		(end 305.685698 -360.982514)
		(width 0.508)
		(layer "F.Cu")
		(net "P3V3_STBY_B")
	)
	(segment
		(start 257.43789 -216.59215)
		(end 257.43789 -215.08339)
		(width 0.3048)
		(layer "F.Cu")
		(net "P3V3_STBY_B")
	)
	(segment
		(start 217.2716 -196.36232)
		(end 219.87002 -196.36232)
		(width 0.3556)
		(layer "F.Cu")
		(net "P3V3_STBY_B")
	)
	(segment
		(start 245.868444 -197.86854)
		(end 246.684038 -197.052946)
		(width 0.508)
		(layer "F.Cu")
		(net "P3V3_STBY_B")
	)
	(segment
		(start 221.522798 -107.859068)
		(end 221.522798 -109.37621)
		(width 0.508)
		(layer "F.Cu")
		(net "P3V3_STBY_B")
	)
	(segment
		(start 222.569024 -203.60513)
		(end 222.569024 -202.91933)
		(width 0.508)
		(layer "F.Cu")
		(net "P3V3_STBY_B")
	)
	(segment
		(start 396.367 -243.1415)
		(end 396.367 -242.316)
		(width 0.508)
		(layer "F.Cu")
		(net "P3V3_STBY_B")
	)
	(segment
		(start 161.9885 -263.144)
		(end 162.8648 -263.144)
		(width 0.508)
		(layer "F.Cu")
		(net "P3V3_STBY_B")
	)
	(segment
		(start 86.5251 -18.4404)
		(end 86.5251 -17.6022)
		(width 0.508)
		(layer "F.Cu")
		(net "P3V3_STBY_B")
	)
	(segment
		(start 245.881652 -214.8205)
		(end 246.361204 -215.300052)
		(width 0.508)
		(layer "F.Cu")
		(net "P3V3_STBY_B")
	)
	(segment
		(start 251.23648 -214.6427)
		(end 251.23648 -212.725)
		(width 0.508)
		(layer "F.Cu")
		(net "P3V3_STBY_B")
	)
	(segment
		(start 251.497338 -229.48011)
		(end 251.497338 -228.7778)
		(width 0.4572)
		(layer "F.Cu")
		(net "P3V3_STBY_B")
	)
	(segment
		(start 118.059454 -133.4262)
		(end 118.059454 -132.373624)
		(width 0.508)
		(layer "F.Cu")
		(net "P3V3_STBY_B")
	)
	(segment
		(start 267.7795 -212.8012)
		(end 267.7795 -213.248494)
		(width 0.508)
		(layer "F.Cu")
		(net "P3V3_STBY_B")
	)
	(segment
		(start 98.8695 -263.144)
		(end 98.8695 -263.9695)
		(width 0.508)
		(layer "F.Cu")
		(net "P3V3_STBY_B")
	)
	(segment
		(start 212.69706 -164.04336)
		(end 212.65896 -164.00526)
		(width 0.3556)
		(layer "F.Cu")
		(net "P3V3_STBY_B")
	)
	(segment
		(start 194.4878 -263.144)
		(end 194.9196 -262.7122)
		(width 0.508)
		(layer "F.Cu")
		(net "P3V3_STBY_B")
	)
	(segment
		(start 395.605 -9.7155)
		(end 395.605 -8.89)
		(width 0.508)
		(layer "F.Cu")
		(net "P3V3_STBY_B")
	)
	(segment
		(start 55.5752 -133.4008)
		(end 55.88 -133.096)
		(width 0.508)
		(layer "F.Cu")
		(net "P3V3_STBY_B")
	)
	(segment
		(start 266.901676 -209.65668)
		(end 266.8651 -209.65668)
		(width 0.508)
		(layer "F.Cu")
		(net "P3V3_STBY_B")
	)
	(segment
		(start 234.38104 -233.45648)
		(end 234.38104 -234.30738)
		(width 0.508)
		(layer "F.Cu")
		(net "P3V3_STBY_B")
	)
	(segment
		(start 251.23648 -212.38972)
		(end 251.4854 -212.1408)
		(width 0.508)
		(layer "F.Cu")
		(net "P3V3_STBY_B")
	)
	(segment
		(start 86.5251 -248.4628)
		(end 87.4268 -248.4628)
		(width 0.508)
		(layer "F.Cu")
		(net "P3V3_STBY_B")
	)
	(segment
		(start 455.803 -16.0528)
		(end 455.7522 -16.1036)
		(width 0.508)
		(layer "F.Cu")
		(net "P3V3_STBY_B")
	)
	(segment
		(start 190.9445 -33.147)
		(end 190.9445 -34.730944)
		(width 0.508)
		(layer "F.Cu")
		(net "P3V3_STBY_B")
	)
	(segment
		(start 244.82298 -193.29654)
		(end 244.82298 -194.43954)
		(width 0.508)
		(layer "F.Cu")
		(net "P3V3_STBY_B")
	)
	(segment
		(start 212.14588 -237.85322)
		(end 211.95538 -238.04372)
		(width 0.508)
		(layer "F.Cu")
		(net "P3V3_STBY_B")
	)
	(segment
		(start 206.8957 -198.374)
		(end 206.8703 -198.3994)
		(width 0.508)
		(layer "F.Cu")
		(net "P3V3_STBY_B")
	)
	(segment
		(start 212.562948 -161.925)
		(end 212.46846 -162.019488)
		(width 0.508)
		(layer "F.Cu")
		(net "P3V3_STBY_B")
	)
	(segment
		(start 118.0211 -248.412)
		(end 118.9482 -248.412)
		(width 0.508)
		(layer "F.Cu")
		(net "P3V3_STBY_B")
	)
	(segment
		(start 301.8155 -228.473)
		(end 301.8155 -230.1494)
		(width 0.508)
		(layer "F.Cu")
		(net "P3V3_STBY_B")
	)
	(segment
		(start 243.3955 -229.743)
		(end 242.5065 -230.632)
		(width 0.508)
		(layer "F.Cu")
		(net "P3V3_STBY_B")
	)
	(segment
		(start 263.558274 -216.333832)
		(end 263.558274 -217.419936)
		(width 0.508)
		(layer "F.Cu")
		(net "P3V3_STBY_B")
	)
	(segment
		(start 222.95358 -220.853)
		(end 223.240854 -220.565726)
		(width 0.508)
		(layer "F.Cu")
		(net "P3V3_STBY_B")
	)
	(segment
		(start 244.82298 -191.554608)
		(end 244.82298 -193.29654)
		(width 0.508)
		(layer "F.Cu")
		(net "P3V3_STBY_B")
	)
	(segment
		(start 205.9178 -198.374)
		(end 206.8957 -198.374)
		(width 0.508)
		(layer "F.Cu")
		(net "P3V3_STBY_B")
	)
	(segment
		(start 415.3154 -261.2009)
		(end 415.3154 -260.2738)
		(width 0.508)
		(layer "F.Cu")
		(net "P3V3_STBY_B")
	)
	(segment
		(start 194.9196 -262.7122)
		(end 194.9196 -255.0668)
		(width 0.508)
		(layer "F.Cu")
		(net "P3V3_STBY_B")
	)
	(segment
		(start 149.6695 -248.4374)
		(end 150.5712 -248.4374)
		(width 0.508)
		(layer "F.Cu")
		(net "P3V3_STBY_B")
	)
	(segment
		(start 260.2611 -211.051902)
		(end 259.800852 -210.591654)
		(width 0.508)
		(layer "F.Cu")
		(net "P3V3_STBY_B")
	)
	(segment
		(start 181.9402 -133.4262)
		(end 181.9656 -133.4008)
		(width 0.508)
		(layer "F.Cu")
		(net "P3V3_STBY_B")
	)
	(segment
		(start 476.4532 -250.1265)
		(end 476.4532 -249.174)
		(width 0.508)
		(layer "F.Cu")
		(net "P3V3_STBY_B")
	)
	(segment
		(start 216.140538 -105.115868)
		(end 216.140538 -106.068368)
		(width 0.508)
		(layer "F.Cu")
		(net "P3V3_STBY_B")
	)
	(segment
		(start 446.8622 -261.2009)
		(end 446.8622 -260.3246)
		(width 0.508)
		(layer "F.Cu")
		(net "P3V3_STBY_B")
	)
	(segment
		(start 211.8868 -204.1525)
		(end 212.0773 -204.343)
		(width 0.508)
		(layer "F.Cu")
		(net "P3V3_STBY_B")
	)
	(segment
		(start 67.1703 -263.144)
		(end 67.1703 -263.9695)
		(width 0.508)
		(layer "F.Cu")
		(net "P3V3_STBY_B")
	)
	(segment
		(start 209.330798 -224.651062)
		(end 208.015586 -224.651062)
		(width 0.508)
		(layer "F.Cu")
		(net "P3V3_STBY_B")
	)
	(segment
		(start 251.2314 -228.511862)
		(end 251.2314 -228.4984)
		(width 0.4572)
		(layer "F.Cu")
		(net "P3V3_STBY_B")
	)
	(segment
		(start 258.0513 -214.5157)
		(end 257.556 -215.011)
		(width 0.508)
		(layer "F.Cu")
		(net "P3V3_STBY_B")
	)
	(segment
		(start 467.0171 -7.493)
		(end 467.9696 -7.493)
		(width 0.508)
		(layer "F.Cu")
		(net "P3V3_STBY_B")
	)
	(segment
		(start 210.99018 -238.84382)
		(end 211.79028 -238.04372)
		(width 0.3556)
		(layer "F.Cu")
		(net "P3V3_STBY_B")
	)
	(segment
		(start 467.9696 -6.4135)
		(end 467.9569 -6.4008)
		(width 0.508)
		(layer "F.Cu")
		(net "P3V3_STBY_B")
	)
	(segment
		(start 243.3955 -228.219)
		(end 243.3955 -229.743)
		(width 0.508)
		(layer "F.Cu")
		(net "P3V3_STBY_B")
	)
	(segment
		(start 35.7505 -148.082)
		(end 35.7505 -148.5265)
		(width 0.508)
		(layer "F.Cu")
		(net "P3V3_STBY_B")
	)
	(segment
		(start 267.7795 -209.3595)
		(end 267.198856 -209.3595)
		(width 0.508)
		(layer "F.Cu")
		(net "P3V3_STBY_B")
	)
	(segment
		(start 219.87002 -196.36232)
		(end 220.2307 -196.723)
		(width 0.3556)
		(layer "F.Cu")
		(net "P3V3_STBY_B")
	)
	(segment
		(start 300.933612 -231.863392)
		(end 300.933612 -231.7369)
		(width 0.508)
		(layer "F.Cu")
		(net "P3V3_STBY_B")
	)
	(segment
		(start 283.809948 -355.682042)
		(end 283.809948 -356.304342)
		(width 0.2032)
		(layer "F.Cu")
		(net "P3V3_STBY_B")
	)
	(segment
		(start 180.975 -19.6215)
		(end 180.4035 -20.193)
		(width 0.508)
		(layer "F.Cu")
		(net "P3V3_STBY_B")
	)
	(segment
		(start 231.07904 -233.45648)
		(end 231.07904 -235.06303)
		(width 0.508)
		(layer "F.Cu")
		(net "P3V3_STBY_B")
	)
	(segment
		(start 211.8868 -203.327)
		(end 211.8868 -204.1525)
		(width 0.508)
		(layer "F.Cu")
		(net "P3V3_STBY_B")
	)
	(segment
		(start 191.0588 -145.3642)
		(end 191.0588 -146.1897)
		(width 0.508)
		(layer "F.Cu")
		(net "P3V3_STBY_B")
	)
	(segment
		(start 163.3474 -262.6614)
		(end 163.3474 -256.9464)
		(width 0.508)
		(layer "F.Cu")
		(net "P3V3_STBY_B")
	)
	(segment
		(start 352.3488 -31.2039)
		(end 352.3488 -30.060646)
		(width 0.508)
		(layer "F.Cu")
		(net "P3V3_STBY_B")
	)
	(segment
		(start 459.359 -128.2065)
		(end 459.359 -127.381)
		(width 0.508)
		(layer "F.Cu")
		(net "P3V3_STBY_B")
	)
	(segment
		(start 87.376 -133.4262)
		(end 86.5505 -133.4262)
		(width 0.508)
		(layer "F.Cu")
		(net "P3V3_STBY_B")
	)
	(segment
		(start 263.114028 -209.582258)
		(end 264.80643 -211.27466)
		(width 0.508)
		(layer "F.Cu")
		(net "P3V3_STBY_B")
	)
	(segment
		(start 467.9696 -7.493)
		(end 467.9696 -6.4135)
		(width 0.508)
		(layer "F.Cu")
		(net "P3V3_STBY_B")
	)
	(segment
		(start 238.627158 -133.101842)
		(end 237.611158 -133.101842)
		(width 0.508)
		(layer "F.Cu")
		(net "P3V3_STBY_B")
	)
	(segment
		(start 207.792066 -207.01)
		(end 207.791558 -207.009492)
		(width 0.508)
		(layer "F.Cu")
		(net "P3V3_STBY_B")
	)
	(segment
		(start 55.8546 -248.4374)
		(end 55.88 -248.4628)
		(width 0.508)
		(layer "F.Cu")
		(net "P3V3_STBY_B")
	)
	(segment
		(start 427.863 -243.1415)
		(end 427.863 -242.316)
		(width 0.508)
		(layer "F.Cu")
		(net "P3V3_STBY_B")
	)
	(segment
		(start 161.9885 -148.082)
		(end 161.9885 -148.9075)
		(width 0.508)
		(layer "F.Cu")
		(net "P3V3_STBY_B")
	)
	(segment
		(start 231.41432 -218.59748)
		(end 231.41432 -217.78468)
		(width 0.508)
		(layer "F.Cu")
		(net "P3V3_STBY_B")
	)
	(segment
		(start 253.896114 -140.228574)
		(end 254.912114 -140.228574)
		(width 0.508)
		(layer "F.Cu")
		(net "P3V3_STBY_B")
	)
	(segment
		(start 320.6496 -261.1755)
		(end 320.6496 -260.2738)
		(width 0.508)
		(layer "F.Cu")
		(net "P3V3_STBY_B")
	)
	(segment
		(start 263.558274 -218.1733)
		(end 263.42594 -218.305634)
		(width 0.508)
		(layer "F.Cu")
		(net "P3V3_STBY_B")
	)
	(segment
		(start 24.1808 -18.3896)
		(end 24.3332 -18.2372)
		(width 0.508)
		(layer "F.Cu")
		(net "P3V3_STBY_B")
	)
	(segment
		(start 283.23667 -236.89437)
		(end 284.03931 -237.69701)
		(width 0.508)
		(layer "F.Cu")
		(net "P3V3_STBY_B")
	)
	(segment
		(start 243.3955 -227.188776)
		(end 243.397024 -227.187252)
		(width 0.508)
		(layer "F.Cu")
		(net "P3V3_STBY_B")
	)
	(segment
		(start 284.03931 -237.69701)
		(end 293.24173 -237.69701)
		(width 0.508)
		(layer "F.Cu")
		(net "P3V3_STBY_B")
	)
	(segment
		(start 67.2465 -148.082)
		(end 67.2465 -148.9075)
		(width 0.508)
		(layer "F.Cu")
		(net "P3V3_STBY_B")
	)
	(segment
		(start 257.34772 -216.68232)
		(end 257.43789 -216.59215)
		(width 0.3048)
		(layer "F.Cu")
		(net "P3V3_STBY_B")
	)
	(segment
		(start 219.142564 -107.859068)
		(end 219.142564 -108.200698)
		(width 0.508)
		(layer "F.Cu")
		(net "P3V3_STBY_B")
	)
	(segment
		(start 470.662 -243.9035)
		(end 470.662 -243.078)
		(width 0.508)
		(layer "F.Cu")
		(net "P3V3_STBY_B")
	)
	(segment
		(start 264.80643 -211.27466)
		(end 264.80643 -211.334604)
		(width 0.508)
		(layer "F.Cu")
		(net "P3V3_STBY_B")
	)
	(segment
		(start 250.4948 -138.2395)
		(end 251.5108 -138.2395)
		(width 0.508)
		(layer "F.Cu")
		(net "P3V3_STBY_B")
	)
	(segment
		(start 456.6031 -16.0528)
		(end 455.803 -16.0528)
		(width 0.508)
		(layer "F.Cu")
		(net "P3V3_STBY_B")
	)
	(segment
		(start 260.0325 -213.995)
		(end 260.615684 -213.995)
		(width 0.508)
		(layer "F.Cu")
		(net "P3V3_STBY_B")
	)
	(segment
		(start 264.033 -226.3394)
		(end 264.033 -225.2345)
		(width 0.508)
		(layer "F.Cu")
		(net "P3V3_STBY_B")
	)
	(segment
		(start 131.567936 -148.082)
		(end 131.571746 -148.08581)
		(width 0.508)
		(layer "F.Cu")
		(net "P3V3_STBY_B")
	)
	(segment
		(start 230.6066 -198.8312)
		(end 230.8225 -198.8312)
		(width 0.508)
		(layer "F.Cu")
		(net "P3V3_STBY_B")
	)
	(segment
		(start 130.3655 -263.144)
		(end 130.3655 -263.9695)
		(width 0.508)
		(layer "F.Cu")
		(net "P3V3_STBY_B")
	)
	(segment
		(start 279.999948 -353.383342)
		(end 279.174448 -353.383342)
		(width 0.508)
		(layer "F.Cu")
		(net "P3V3_STBY_B")
	)
	(segment
		(start 364.744 -13.1445)
		(end 364.744 -12.319)
		(width 0.508)
		(layer "F.Cu")
		(net "P3V3_STBY_B")
	)
	(segment
		(start 352.298 -260.2738)
		(end 352.2726 -260.2484)
		(width 0.508)
		(layer "F.Cu")
		(net "P3V3_STBY_B")
	)
	(segment
		(start 251.497338 -228.7778)
		(end 251.2314 -228.511862)
		(width 0.4572)
		(layer "F.Cu")
		(net "P3V3_STBY_B")
	)
	(segment
		(start 231.284272 -194.6529)
		(end 231.344978 -194.713606)
		(width 0.508)
		(layer "F.Cu")
		(net "P3V3_STBY_B")
	)
	(segment
		(start 213.0679 -237.85322)
		(end 212.97138 -237.85322)
		(width 0.508)
		(layer "F.Cu")
		(net "P3V3_STBY_B")
	)
	(segment
		(start 213.075012 -237.846108)
		(end 213.0679 -237.85322)
		(width 0.508)
		(layer "F.Cu")
		(net "P3V3_STBY_B")
	)
	(segment
		(start 24.2062 -133.4262)
		(end 24.257 -133.477)
		(width 0.508)
		(layer "F.Cu")
		(net "P3V3_STBY_B")
	)
	(segment
		(start 383.8956 -261.2009)
		(end 383.8956 -260.2484)
		(width 0.508)
		(layer "F.Cu")
		(net "P3V3_STBY_B")
	)
	(segment
		(start 54.737 -19.6215)
		(end 54.737 -20.447)
		(width 0.508)
		(layer "F.Cu")
		(net "P3V3_STBY_B")
	)
	(segment
		(start 221.522798 -109.37621)
		(end 221.384114 -109.514894)
		(width 0.508)
		(layer "F.Cu")
		(net "P3V3_STBY_B")
	)
	(segment
		(start 191.3001 -263.144)
		(end 194.4878 -263.144)
		(width 0.508)
		(layer "F.Cu")
		(net "P3V3_STBY_B")
	)
	(segment
		(start 446.9765 -148.209)
		(end 446.9765 -149.098)
		(width 0.508)
		(layer "F.Cu")
		(net "P3V3_STBY_B")
	)
	(segment
		(start 321.204844 -145.150586)
		(end 323.109336 -145.150586)
		(width 0.508)
		(layer "F.Cu")
		(net "P3V3_STBY_B")
	)
	(segment
		(start 257.556 -215.011)
		(end 257.3655 -215.011)
		(width 0.508)
		(layer "F.Cu")
		(net "P3V3_STBY_B")
	)
	(segment
		(start 242.062 -214.8205)
		(end 242.062 -213.9696)
		(width 0.508)
		(layer "F.Cu")
		(net "P3V3_STBY_B")
	)
	(segment
		(start 211.8868 -202.23988)
		(end 211.8868 -203.327)
		(width 0.508)
		(layer "F.Cu")
		(net "P3V3_STBY_B")
	)
	(segment
		(start 467.9569 -6.4008)
		(end 467.9569 -5.3594)
		(width 0.508)
		(layer "F.Cu")
		(net "P3V3_STBY_B")
	)
	(segment
		(start 208.90738 -234.74172)
		(end 208.90738 -233.769408)
		(width 0.508)
		(layer "F.Cu")
		(net "P3V3_STBY_B")
	)
	(segment
		(start 191.9224 -252.0696)
		(end 191.8208 -252.0696)
		(width 0.508)
		(layer "F.Cu")
		(net "P3V3_STBY_B")
	)
	(segment
		(start 117.856 -19.6215)
		(end 117.856 -20.447)
		(width 0.508)
		(layer "F.Cu")
		(net "P3V3_STBY_B")
	)
	(segment
		(start 332.232 -9.7155)
		(end 332.232 -8.89)
		(width 0.508)
		(layer "F.Cu")
		(net "P3V3_STBY_B")
	)
	(segment
		(start 239.353852 -134.393178)
		(end 238.337852 -134.393178)
		(width 0.508)
		(layer "F.Cu")
		(net "P3V3_STBY_B")
	)
	(segment
		(start 180.4035 -20.193)
		(end 180.086 -20.193)
		(width 0.508)
		(layer "F.Cu")
		(net "P3V3_STBY_B")
	)
	(segment
		(start 236.29874 -218.0717)
		(end 236.29874 -218.07424)
		(width 0.635)
		(layer "F.Cu")
		(net "P3V3_STBY_B")
	)
	(segment
		(start 212.0773 -204.71638)
		(end 212.0773 -204.343)
		(width 0.3556)
		(layer "F.Cu")
		(net "P3V3_STBY_B")
	)
	(segment
		(start 239.426242 -141.3764)
		(end 238.410242 -141.3764)
		(width 0.508)
		(layer "F.Cu")
		(net "P3V3_STBY_B")
	)
	(segment
		(start 252.221492 -137.04697)
		(end 253.237492 -137.04697)
		(width 0.508)
		(layer "F.Cu")
		(net "P3V3_STBY_B")
	)
	(segment
		(start 208.59496 -166.41826)
		(end 207.111854 -166.41826)
		(width 0.508)
		(layer "F.Cu")
		(net "P3V3_STBY_B")
	)
	(segment
		(start 23.3807 -133.4262)
		(end 24.2062 -133.4262)
		(width 0.508)
		(layer "F.Cu")
		(net "P3V3_STBY_B")
	)
	(segment
		(start 364.744 -243.1415)
		(end 364.744 -242.316)
		(width 0.508)
		(layer "F.Cu")
		(net "P3V3_STBY_B")
	)
	(segment
		(start 242.8367 -131.2037)
		(end 242.8494 -131.191)
		(width 0.508)
		(layer "F.Cu")
		(net "P3V3_STBY_B")
	)
	(segment
		(start 209.92338 -248.33072)
		(end 209.92338 -249.29338)
		(width 0.508)
		(layer "F.Cu")
		(net "P3V3_STBY_B")
	)
	(segment
		(start 150.4696 -133.4516)
		(end 150.495 -133.4262)
		(width 0.508)
		(layer "F.Cu")
		(net "P3V3_STBY_B")
	)
	(segment
		(start 163.3474 -256.9464)
		(end 158.623 -252.222)
		(width 0.508)
		(layer "F.Cu")
		(net "P3V3_STBY_B")
	)
	(segment
		(start 212.46846 -162.98926)
		(end 212.46846 -163.81476)
		(width 0.508)
		(layer "F.Cu")
		(net "P3V3_STBY_B")
	)
	(segment
		(start 23.4315 -18.3896)
		(end 24.1808 -18.3896)
		(width 0.508)
		(layer "F.Cu")
		(net "P3V3_STBY_B")
	)
	(segment
		(start 470.662 -128.8415)
		(end 470.662 -128.016)
		(width 0.508)
		(layer "F.Cu")
		(net "P3V3_STBY_B")
	)
	(segment
		(start 241.8334 -131.2037)
		(end 242.8367 -131.2037)
		(width 0.508)
		(layer "F.Cu")
		(net "P3V3_STBY_B")
	)
	(segment
		(start 210.1977 -238.84382)
		(end 210.99018 -238.84382)
		(width 0.3556)
		(layer "F.Cu")
		(net "P3V3_STBY_B")
	)
	(segment
		(start 267.198856 -209.3595)
		(end 266.901676 -209.65668)
		(width 0.508)
		(layer "F.Cu")
		(net "P3V3_STBY_B")
	)
	(segment
		(start 459.359 -243.1415)
		(end 459.359 -242.316)
		(width 0.508)
		(layer "F.Cu")
		(net "P3V3_STBY_B")
	)
	(segment
		(start 279.999948 -351.351342)
		(end 279.174448 -351.351342)
		(width 0.508)
		(layer "F.Cu")
		(net "P3V3_STBY_B")
	)
	(segment
		(start 218.515692 -105.964228)
		(end 218.621864 -106.0704)
		(width 0.508)
		(layer "F.Cu")
		(net "P3V3_STBY_B")
	)
	(segment
		(start 320.7004 -30.4038)
		(end 320.7004 -31.2039)
		(width 0.508)
		(layer "F.Cu")
		(net "P3V3_STBY_B")
	)
	(segment
		(start 190.9445 -34.730944)
		(end 191.382142 -35.168586)
		(width 0.508)
		(layer "F.Cu")
		(net "P3V3_STBY_B")
	)
	(segment
		(start 251.23648 -212.725)
		(end 251.23648 -212.38972)
		(width 0.508)
		(layer "F.Cu")
		(net "P3V3_STBY_B")
	)
	(segment
		(start 353.529646 -28.8798)
		(end 354.1268 -28.8798)
		(width 0.508)
		(layer "F.Cu")
		(net "P3V3_STBY_B")
	)
	(segment
		(start 98.8695 -149.159468)
		(end 99.220528 -149.510496)
		(width 0.508)
		(layer "F.Cu")
		(net "P3V3_STBY_B")
	)
	(segment
		(start 364.744 -128.2065)
		(end 364.744 -127.381)
		(width 0.508)
		(layer "F.Cu")
		(net "P3V3_STBY_B")
	)
	(segment
		(start 208.015586 -224.651062)
		(end 207.603598 -225.06305)
		(width 0.508)
		(layer "F.Cu")
		(net "P3V3_STBY_B")
	)
	(segment
		(start 209.3595 -227.965)
		(end 209.3595 -226.822)
		(width 0.508)
		(layer "F.Cu")
		(net "P3V3_STBY_B")
	)
	(segment
		(start 33.4264 -31.1531)
		(end 33.4264 -30.2514)
		(width 0.508)
		(layer "F.Cu")
		(net "P3V3_STBY_B")
	)
	(segment
		(start 212.69706 -165.12794)
		(end 212.69706 -164.04336)
		(width 0.3556)
		(layer "F.Cu")
		(net "P3V3_STBY_B")
	)
	(segment
		(start 415.0868 -145.3388)
		(end 415.0868 -146.1897)
		(width 0.508)
		(layer "F.Cu")
		(net "P3V3_STBY_B")
	)
	(segment
		(start 207.791558 -207.009492)
		(end 207.800702 -207.009492)
		(width 0.508)
		(layer "F.Cu")
		(net "P3V3_STBY_B")
	)
	(segment
		(start 208.026 -227.6094)
		(end 208.3816 -227.965)
		(width 0.508)
		(layer "F.Cu")
		(net "P3V3_STBY_B")
	)
	(segment
		(start 127.9906 -30.353)
		(end 127.9906 -31.1785)
		(width 0.508)
		(layer "F.Cu")
		(net "P3V3_STBY_B")
	)
	(segment
		(start 194.9196 -255.0668)
		(end 191.9224 -252.0696)
		(width 0.508)
		(layer "F.Cu")
		(net "P3V3_STBY_B")
	)
	(via
		(at 86.5251 -17.6022)
		(size 0.5588)
		(drill 0.3048)
		(layers "F.Cu" "B.Cu")
		(net "P3V3_STBY_B")
	)
	(via
		(at 182.0672 -248.4882)
		(size 0.5588)
		(drill 0.3048)
		(layers "F.Cu" "B.Cu")
		(net "P3V3_STBY_B")
	)
	(via
		(at 191.382142 -35.168586)
		(size 0.5588)
		(drill 0.3048)
		(layers "F.Cu" "B.Cu")
		(net "P3V3_STBY_B")
	)
	(via
		(at 227.3808 -248.92)
		(size 0.5588)
		(drill 0.3048)
		(layers "F.Cu" "B.Cu")
		(net "P3V3_STBY_B")
	)
	(via
		(at 213.35238 -249.29338)
		(size 0.5588)
		(drill 0.3048)
		(layers "F.Cu" "B.Cu")
		(net "P3V3_STBY_B")
	)
	(via
		(at 246.684038 -197.052946)
		(size 0.5588)
		(drill 0.3048)
		(layers "F.Cu" "B.Cu")
		(net "P3V3_STBY_B")
	)
	(via
		(at 227.457 -263.652)
		(size 0.5588)
		(drill 0.3048)
		(layers "F.Cu" "B.Cu")
		(net "P3V3_STBY_B")
	)
	(via
		(at 253.72187 -134.575296)
		(size 0.5588)
		(drill 0.3048)
		(layers "F.Cu" "B.Cu")
		(net "P3V3_STBY_B")
	)
	(via
		(at 487.426 -12.954)
		(size 0.5588)
		(drill 0.3048)
		(layers "F.Cu" "B.Cu")
		(net "P3V3_STBY_B")
	)
	(via
		(at 246.898668 -224.6884)
		(size 0.5588)
		(drill 0.3048)
		(layers "F.Cu" "B.Cu")
		(net "P3V3_STBY_B")
	)
	(via
		(at 415.3154 -260.2738)
		(size 0.5588)
		(drill 0.3048)
		(layers "F.Cu" "B.Cu")
		(net "P3V3_STBY_B")
	)
	(via
		(at 364.744 -242.316)
		(size 0.5588)
		(drill 0.3048)
		(layers "F.Cu" "B.Cu")
		(net "P3V3_STBY_B")
	)
	(via
		(at 476.4532 -249.174)
		(size 0.5588)
		(drill 0.3048)
		(layers "F.Cu" "B.Cu")
		(net "P3V3_STBY_B")
	)
	(via
		(at 47.129954 -5.468366)
		(size 0.5588)
		(drill 0.3048)
		(layers "F.Cu" "B.Cu")
		(net "P3V3_STBY_B")
	)
	(via
		(at 446.8622 -260.3246)
		(size 0.5588)
		(drill 0.3048)
		(layers "F.Cu" "B.Cu")
		(net "P3V3_STBY_B")
	)
	(via
		(at 218.571826 -108.771436)
		(size 0.5588)
		(drill 0.3048)
		(layers "F.Cu" "B.Cu")
		(net "P3V3_STBY_B")
	)
	(via
		(at 95.504 -252.222)
		(size 0.5588)
		(drill 0.3048)
		(layers "F.Cu" "B.Cu")
		(net "P3V3_STBY_B")
	)
	(via
		(at 24.257 -133.477)
		(size 0.5588)
		(drill 0.3048)
		(layers "F.Cu" "B.Cu")
		(net "P3V3_STBY_B")
	)
	(via
		(at 243.397024 -227.187252)
		(size 0.5588)
		(drill 0.3048)
		(layers "F.Cu" "B.Cu")
		(net "P3V3_STBY_B")
	)
	(via
		(at 427.863 -242.316)
		(size 0.5588)
		(drill 0.3048)
		(layers "F.Cu" "B.Cu")
		(net "P3V3_STBY_B")
	)
	(via
		(at 242.062 -213.9696)
		(size 0.5588)
		(drill 0.3048)
		(layers "F.Cu" "B.Cu")
		(net "P3V3_STBY_B")
	)
	(via
		(at 415.3662 -30.3784)
		(size 0.5588)
		(drill 0.3048)
		(layers "F.Cu" "B.Cu")
		(net "P3V3_STBY_B")
	)
	(via
		(at 127.9906 -30.353)
		(size 0.5588)
		(drill 0.3048)
		(layers "F.Cu" "B.Cu")
		(net "P3V3_STBY_B")
	)
	(via
		(at 250.327668 -224.2566)
		(size 0.5588)
		(drill 0.3048)
		(layers "F.Cu" "B.Cu")
		(net "P3V3_STBY_B")
	)
	(via
		(at 250.606052 -131.999736)
		(size 0.5588)
		(drill 0.3048)
		(layers "F.Cu" "B.Cu")
		(net "P3V3_STBY_B")
	)
	(via
		(at 223.46158 -220.565726)
		(size 0.5588)
		(drill 0.3048)
		(layers "F.Cu" "B.Cu")
		(net "P3V3_STBY_B")
	)
	(via
		(at 254.912114 -140.228574)
		(size 0.5588)
		(drill 0.3048)
		(layers "F.Cu" "B.Cu")
		(net "P3V3_STBY_B")
	)
	(via
		(at 158.623 -252.222)
		(size 0.5588)
		(drill 0.3048)
		(layers "F.Cu" "B.Cu")
		(net "P3V3_STBY_B")
	)
	(via
		(at 205.9178 -196.088)
		(size 0.5588)
		(drill 0.3048)
		(layers "F.Cu" "B.Cu")
		(net "P3V3_STBY_B")
	)
	(via
		(at 383.8956 -260.2484)
		(size 0.5588)
		(drill 0.3048)
		(layers "F.Cu" "B.Cu")
		(net "P3V3_STBY_B")
	)
	(via
		(at 236.29874 -218.0717)
		(size 0.5588)
		(drill 0.3048)
		(layers "F.Cu" "B.Cu")
		(net "P3V3_STBY_B")
	)
	(via
		(at 208.905602 -233.76763)
		(size 0.5588)
		(drill 0.3048)
		(layers "F.Cu" "B.Cu")
		(net "P3V3_STBY_B")
	)
	(via
		(at 33.4264 -30.2514)
		(size 0.5588)
		(drill 0.3048)
		(layers "F.Cu" "B.Cu")
		(net "P3V3_STBY_B")
	)
	(via
		(at 238.410242 -141.3764)
		(size 0.5588)
		(drill 0.3048)
		(layers "F.Cu" "B.Cu")
		(net "P3V3_STBY_B")
	)
	(via
		(at 218.7702 -227.4062)
		(size 0.5588)
		(drill 0.3048)
		(layers "F.Cu" "B.Cu")
		(net "P3V3_STBY_B")
	)
	(via
		(at 246.74068 -136.6393)
		(size 0.5588)
		(drill 0.3048)
		(layers "F.Cu" "B.Cu")
		(net "P3V3_STBY_B")
	)
	(via
		(at 225.552 -248.92)
		(size 0.5588)
		(drill 0.3048)
		(layers "F.Cu" "B.Cu")
		(net "P3V3_STBY_B")
	)
	(via
		(at 266.720828 -214.307166)
		(size 0.5588)
		(drill 0.3048)
		(layers "F.Cu" "B.Cu")
		(net "P3V3_STBY_B")
	)
	(via
		(at 241.173 -283.083)
		(size 0.5588)
		(drill 0.3048)
		(layers "F.Cu" "B.Cu")
		(net "P3V3_STBY_B")
	)
	(via
		(at 477.647 -12.4206)
		(size 0.5588)
		(drill 0.3048)
		(layers "F.Cu" "B.Cu")
		(net "P3V3_STBY_B")
	)
	(via
		(at 117.856 -20.447)
		(size 0.5588)
		(drill 0.3048)
		(layers "F.Cu" "B.Cu")
		(net "P3V3_STBY_B")
	)
	(via
		(at 251.5108 -138.2395)
		(size 0.5588)
		(drill 0.3048)
		(layers "F.Cu" "B.Cu")
		(net "P3V3_STBY_B")
	)
	(via
		(at 480.3902 -12.5476)
		(size 0.5588)
		(drill 0.3048)
		(layers "F.Cu" "B.Cu")
		(net "P3V3_STBY_B")
	)
	(via
		(at 64.7446 -30.3784)
		(size 0.5588)
		(drill 0.3048)
		(layers "F.Cu" "B.Cu")
		(net "P3V3_STBY_B")
	)
	(via
		(at 279.1714 -349.3008)
		(size 0.5588)
		(drill 0.3048)
		(layers "F.Cu" "B.Cu")
		(net "P3V3_STBY_B")
	)
	(via
		(at 364.744 -127.381)
		(size 0.5588)
		(drill 0.3048)
		(layers "F.Cu" "B.Cu")
		(net "P3V3_STBY_B")
	)
	(via
		(at 87.376 -133.4262)
		(size 0.5588)
		(drill 0.3048)
		(layers "F.Cu" "B.Cu")
		(net "P3V3_STBY_B")
	)
	(via
		(at 208.026 -227.6094)
		(size 0.5588)
		(drill 0.3048)
		(layers "F.Cu" "B.Cu")
		(net "P3V3_STBY_B")
	)
	(via
		(at 283.809948 -357.142542)
		(size 0.5588)
		(drill 0.3048)
		(layers "F.Cu" "B.Cu")
		(net "P3V3_STBY_B")
	)
	(via
		(at 292.3794 -301.9806)
		(size 0.7112)
		(drill 0.4064)
		(layers "F.Cu" "B.Cu")
		(net "P3V3_STBY_B")
	)
	(via
		(at 231.07904 -235.06303)
		(size 0.5588)
		(drill 0.3048)
		(layers "F.Cu" "B.Cu")
		(net "P3V3_STBY_B")
	)
	(via
		(at 242.951 -283.845)
		(size 0.5588)
		(drill 0.3048)
		(layers "F.Cu" "B.Cu")
		(net "P3V3_STBY_B")
	)
	(via
		(at 225.1456 -248.031)
		(size 0.5588)
		(drill 0.3048)
		(layers "F.Cu" "B.Cu")
		(net "P3V3_STBY_B")
	)
	(via
		(at 36.322 -149.098)
		(size 0.5588)
		(drill 0.3048)
		(layers "F.Cu" "B.Cu")
		(net "P3V3_STBY_B")
	)
	(via
		(at 130.3655 -263.9695)
		(size 0.5588)
		(drill 0.3048)
		(layers "F.Cu" "B.Cu")
		(net "P3V3_STBY_B")
	)
	(via
		(at 253.237492 -137.04697)
		(size 0.5588)
		(drill 0.3048)
		(layers "F.Cu" "B.Cu")
		(net "P3V3_STBY_B")
	)
	(via
		(at 87.4268 -248.4628)
		(size 0.5588)
		(drill 0.3048)
		(layers "F.Cu" "B.Cu")
		(net "P3V3_STBY_B")
	)
	(via
		(at 251.394468 -224.2566)
		(size 0.5588)
		(drill 0.3048)
		(layers "F.Cu" "B.Cu")
		(net "P3V3_STBY_B")
	)
	(via
		(at 396.367 -242.316)
		(size 0.5588)
		(drill 0.3048)
		(layers "F.Cu" "B.Cu")
		(net "P3V3_STBY_B")
	)
	(via
		(at 191.0588 -145.3642)
		(size 0.5588)
		(drill 0.3048)
		(layers "F.Cu" "B.Cu")
		(net "P3V3_STBY_B")
	)
	(via
		(at 218.621864 -106.0704)
		(size 0.5588)
		(drill 0.3048)
		(layers "F.Cu" "B.Cu")
		(net "P3V3_STBY_B")
	)
	(via
		(at 247.5357 -143.17726)
		(size 0.5588)
		(drill 0.3048)
		(layers "F.Cu" "B.Cu")
		(net "P3V3_STBY_B")
	)
	(via
		(at 415.0868 -145.3388)
		(size 0.5588)
		(drill 0.3048)
		(layers "F.Cu" "B.Cu")
		(net "P3V3_STBY_B")
	)
	(via
		(at 333.248 -127.381)
		(size 0.5588)
		(drill 0.3048)
		(layers "F.Cu" "B.Cu")
		(net "P3V3_STBY_B")
	)
	(via
		(at 320.7004 -30.4038)
		(size 0.5588)
		(drill 0.3048)
		(layers "F.Cu" "B.Cu")
		(net "P3V3_STBY_B")
	)
	(via
		(at 247.53062 -142.1257)
		(size 0.5588)
		(drill 0.3048)
		(layers "F.Cu" "B.Cu")
		(net "P3V3_STBY_B")
	)
	(via
		(at 207.047592 -166.353998)
		(size 0.5588)
		(drill 0.3048)
		(layers "F.Cu" "B.Cu")
		(net "P3V3_STBY_B")
	)
	(via
		(at 231.344978 -194.713606)
		(size 0.5588)
		(drill 0.3048)
		(layers "F.Cu" "B.Cu")
		(net "P3V3_STBY_B")
	)
	(via
		(at 364.744 -12.319)
		(size 0.5588)
		(drill 0.3048)
		(layers "F.Cu" "B.Cu")
		(net "P3V3_STBY_B")
	)
	(via
		(at 238.337852 -134.393178)
		(size 0.5588)
		(drill 0.3048)
		(layers "F.Cu" "B.Cu")
		(net "P3V3_STBY_B")
	)
	(via
		(at 470.662 -243.078)
		(size 0.5588)
		(drill 0.3048)
		(layers "F.Cu" "B.Cu")
		(net "P3V3_STBY_B")
	)
	(via
		(at 382.524 -252.222)
		(size 0.5588)
		(drill 0.3048)
		(layers "F.Cu" "B.Cu")
		(net "P3V3_STBY_B")
	)
	(via
		(at 427.863 -127.381)
		(size 0.5588)
		(drill 0.3048)
		(layers "F.Cu" "B.Cu")
		(net "P3V3_STBY_B")
	)
	(via
		(at 131.571746 -148.08581)
		(size 0.5588)
		(drill 0.3048)
		(layers "F.Cu" "B.Cu")
		(net "P3V3_STBY_B")
	)
	(via
		(at 242.57 -137.3632)
		(size 0.5588)
		(drill 0.3048)
		(layers "F.Cu" "B.Cu")
		(net "P3V3_STBY_B")
	)
	(via
		(at 383.8956 -30.353)
		(size 0.5588)
		(drill 0.3048)
		(layers "F.Cu" "B.Cu")
		(net "P3V3_STBY_B")
	)
	(via
		(at 427.863 -12.319)
		(size 0.5588)
		(drill 0.3048)
		(layers "F.Cu" "B.Cu")
		(net "P3V3_STBY_B")
	)
	(via
		(at 383.8448 -145.3642)
		(size 0.5588)
		(drill 0.3048)
		(layers "F.Cu" "B.Cu")
		(net "P3V3_STBY_B")
	)
	(via
		(at 414.401 -252.476)
		(size 0.5588)
		(drill 0.3048)
		(layers "F.Cu" "B.Cu")
		(net "P3V3_STBY_B")
	)
	(via
		(at 244.82298 -191.554608)
		(size 0.5588)
		(drill 0.3048)
		(layers "F.Cu" "B.Cu")
		(net "P3V3_STBY_B")
	)
	(via
		(at 238.399066 -140.050266)
		(size 0.5588)
		(drill 0.3048)
		(layers "F.Cu" "B.Cu")
		(net "P3V3_STBY_B")
	)
	(via
		(at 241.681 -283.845)
		(size 0.5588)
		(drill 0.3048)
		(layers "F.Cu" "B.Cu")
		(net "P3V3_STBY_B")
	)
	(via
		(at 279.1714 -348.2848)
		(size 0.5588)
		(drill 0.3048)
		(layers "F.Cu" "B.Cu")
		(net "P3V3_STBY_B")
	)
	(via
		(at 222.175324 -191.156082)
		(size 0.5588)
		(drill 0.3048)
		(layers "F.Cu" "B.Cu")
		(net "P3V3_STBY_B")
	)
	(via
		(at 211.95538 -249.29338)
		(size 0.5588)
		(drill 0.3048)
		(layers "F.Cu" "B.Cu")
		(net "P3V3_STBY_B")
	)
	(via
		(at 292.3794 -300.7614)
		(size 0.7112)
		(drill 0.4064)
		(layers "F.Cu" "B.Cu")
		(net "P3V3_STBY_B")
	)
	(via
		(at 246.361204 -215.300052)
		(size 0.5588)
		(drill 0.3048)
		(layers "F.Cu" "B.Cu")
		(net "P3V3_STBY_B")
	)
	(via
		(at 150.5712 -248.4374)
		(size 0.5588)
		(drill 0.3048)
		(layers "F.Cu" "B.Cu")
		(net "P3V3_STBY_B")
	)
	(via
		(at 222.123 -197.8914)
		(size 0.5588)
		(drill 0.3048)
		(layers "F.Cu" "B.Cu")
		(net "P3V3_STBY_B")
	)
	(via
		(at 226.4664 -248.92)
		(size 0.5588)
		(drill 0.3048)
		(layers "F.Cu" "B.Cu")
		(net "P3V3_STBY_B")
	)
	(via
		(at 446.024 -252.349)
		(size 0.5588)
		(drill 0.3048)
		(layers "F.Cu" "B.Cu")
		(net "P3V3_STBY_B")
	)
	(via
		(at 55.88 -133.096)
		(size 0.5588)
		(drill 0.3048)
		(layers "F.Cu" "B.Cu")
		(net "P3V3_STBY_B")
	)
	(via
		(at 237.611158 -133.101842)
		(size 0.5588)
		(drill 0.3048)
		(layers "F.Cu" "B.Cu")
		(net "P3V3_STBY_B")
	)
	(via
		(at 99.220528 -149.510496)
		(size 0.5588)
		(drill 0.3048)
		(layers "F.Cu" "B.Cu")
		(net "P3V3_STBY_B")
	)
	(via
		(at 212.562948 -161.925)
		(size 0.5588)
		(drill 0.3048)
		(layers "F.Cu" "B.Cu")
		(net "P3V3_STBY_B")
	)
	(via
		(at 285.016448 -346.271342)
		(size 0.5588)
		(drill 0.3048)
		(layers "F.Cu" "B.Cu")
		(net "P3V3_STBY_B")
	)
	(via
		(at 242.8494 -131.191)
		(size 0.5588)
		(drill 0.3048)
		(layers "F.Cu" "B.Cu")
		(net "P3V3_STBY_B")
	)
	(via
		(at 227.8888 -248.031)
		(size 0.5588)
		(drill 0.3048)
		(layers "F.Cu" "B.Cu")
		(net "P3V3_STBY_B")
	)
	(via
		(at 266.8651 -209.65668)
		(size 0.5588)
		(drill 0.3048)
		(layers "F.Cu" "B.Cu")
		(net "P3V3_STBY_B")
	)
	(via
		(at 470.662 -128.016)
		(size 0.5588)
		(drill 0.3048)
		(layers "F.Cu" "B.Cu")
		(net "P3V3_STBY_B")
	)
	(via
		(at 354.1268 -28.8798)
		(size 0.5588)
		(drill 0.3048)
		(layers "F.Cu" "B.Cu")
		(net "P3V3_STBY_B")
	)
	(via
		(at 446.9765 -149.098)
		(size 0.5588)
		(drill 0.3048)
		(layers "F.Cu" "B.Cu")
		(net "P3V3_STBY_B")
	)
	(via
		(at 240.538 -283.845)
		(size 0.5588)
		(drill 0.3048)
		(layers "F.Cu" "B.Cu")
		(net "P3V3_STBY_B")
	)
	(via
		(at 351.523808 -145.567908)
		(size 0.5588)
		(drill 0.3048)
		(layers "F.Cu" "B.Cu")
		(net "P3V3_STBY_B")
	)
	(via
		(at 67.1703 -263.9695)
		(size 0.5588)
		(drill 0.3048)
		(layers "F.Cu" "B.Cu")
		(net "P3V3_STBY_B")
	)
	(via
		(at 127 -251.968)
		(size 0.5588)
		(drill 0.3048)
		(layers "F.Cu" "B.Cu")
		(net "P3V3_STBY_B")
	)
	(via
		(at 235.52404 -234.30738)
		(size 0.5588)
		(drill 0.3048)
		(layers "F.Cu" "B.Cu")
		(net "P3V3_STBY_B")
	)
	(via
		(at 460.1464 -8.3312)
		(size 0.5588)
		(drill 0.3048)
		(layers "F.Cu" "B.Cu")
		(net "P3V3_STBY_B")
	)
	(via
		(at 251.2314 -228.4984)
		(size 0.5588)
		(drill 0.3048)
		(layers "F.Cu" "B.Cu")
		(net "P3V3_STBY_B")
	)
	(via
		(at 478.3582 -134.62)
		(size 0.5588)
		(drill 0.3048)
		(layers "F.Cu" "B.Cu")
		(net "P3V3_STBY_B")
	)
	(via
		(at 96.393 -30.353)
		(size 0.5588)
		(drill 0.3048)
		(layers "F.Cu" "B.Cu")
		(net "P3V3_STBY_B")
	)
	(via
		(at 293.5986 -300.7614)
		(size 0.7112)
		(drill 0.4064)
		(layers "F.Cu" "B.Cu")
		(net "P3V3_STBY_B")
	)
	(via
		(at 223.19996 -165.40226)
		(size 0.5588)
		(drill 0.3048)
		(layers "F.Cu" "B.Cu")
		(net "P3V3_STBY_B")
	)
	(via
		(at 459.359 -242.316)
		(size 0.5588)
		(drill 0.3048)
		(layers "F.Cu" "B.Cu")
		(net "P3V3_STBY_B")
	)
	(via
		(at 223.19996 -163.37026)
		(size 0.5588)
		(drill 0.3048)
		(layers "F.Cu" "B.Cu")
		(net "P3V3_STBY_B")
	)
	(via
		(at 222.569024 -202.91933)
		(size 0.5588)
		(drill 0.3048)
		(layers "F.Cu" "B.Cu")
		(net "P3V3_STBY_B")
	)
	(via
		(at 300.933612 -231.863392)
		(size 0.5588)
		(drill 0.3048)
		(layers "F.Cu" "B.Cu")
		(net "P3V3_STBY_B")
	)
	(via
		(at 264.80643 -211.334604)
		(size 0.5588)
		(drill 0.3048)
		(layers "F.Cu" "B.Cu")
		(net "P3V3_STBY_B")
	)
	(via
		(at 159.512 -30.353)
		(size 0.5588)
		(drill 0.3048)
		(layers "F.Cu" "B.Cu")
		(net "P3V3_STBY_B")
	)
	(via
		(at 242.443 -283.083)
		(size 0.5588)
		(drill 0.3048)
		(layers "F.Cu" "B.Cu")
		(net "P3V3_STBY_B")
	)
	(via
		(at 67.2465 -148.9075)
		(size 0.5588)
		(drill 0.3048)
		(layers "F.Cu" "B.Cu")
		(net "P3V3_STBY_B")
	)
	(via
		(at 258.0513 -212.852)
		(size 0.5588)
		(drill 0.3048)
		(layers "F.Cu" "B.Cu")
		(net "P3V3_STBY_B")
	)
	(via
		(at 266.896596 -207.093058)
		(size 0.5588)
		(drill 0.3048)
		(layers "F.Cu" "B.Cu")
		(net "P3V3_STBY_B")
	)
	(via
		(at 223.828864 -206.708502)
		(size 0.5588)
		(drill 0.3048)
		(layers "F.Cu" "B.Cu")
		(net "P3V3_STBY_B")
	)
	(via
		(at 320.6496 -260.2738)
		(size 0.5588)
		(drill 0.3048)
		(layers "F.Cu" "B.Cu")
		(net "P3V3_STBY_B")
	)
	(via
		(at 260.840728 -213.769956)
		(size 0.5588)
		(drill 0.3048)
		(layers "F.Cu" "B.Cu")
		(net "P3V3_STBY_B")
	)
	(via
		(at 64.008 -252.095)
		(size 0.5588)
		(drill 0.3048)
		(layers "F.Cu" "B.Cu")
		(net "P3V3_STBY_B")
	)
	(via
		(at 234.38104 -234.30738)
		(size 0.5588)
		(drill 0.3048)
		(layers "F.Cu" "B.Cu")
		(net "P3V3_STBY_B")
	)
	(via
		(at 239.522 -283.845)
		(size 0.5588)
		(drill 0.3048)
		(layers "F.Cu" "B.Cu")
		(net "P3V3_STBY_B")
	)
	(via
		(at 293.5986 -301.9806)
		(size 0.7112)
		(drill 0.4064)
		(layers "F.Cu" "B.Cu")
		(net "P3V3_STBY_B")
	)
	(via
		(at 221.384114 -109.514894)
		(size 0.5588)
		(drill 0.3048)
		(layers "F.Cu" "B.Cu")
		(net "P3V3_STBY_B")
	)
	(via
		(at 478.919032 -19.662902)
		(size 0.5588)
		(drill 0.3048)
		(layers "F.Cu" "B.Cu")
		(net "P3V3_STBY_B")
	)
	(via
		(at 213.93658 -237.846108)
		(size 0.5588)
		(drill 0.3048)
		(layers "F.Cu" "B.Cu")
		(net "P3V3_STBY_B")
	)
	(via
		(at 259.800852 -210.591654)
		(size 0.5588)
		(drill 0.3048)
		(layers "F.Cu" "B.Cu")
		(net "P3V3_STBY_B")
	)
	(via
		(at 320.04 -252.349)
		(size 0.5588)
		(drill 0.3048)
		(layers "F.Cu" "B.Cu")
		(net "P3V3_STBY_B")
	)
	(via
		(at 246.38 -284.861)
		(size 0.6096)
		(drill 0.3048)
		(layers "F.Cu" "B.Cu")
		(net "P3V3_STBY_B")
	)
	(via
		(at 161.9885 -148.9075)
		(size 0.5588)
		(drill 0.3048)
		(layers "F.Cu" "B.Cu")
		(net "P3V3_STBY_B")
	)
	(via
		(at 181.9656 -133.4008)
		(size 0.5588)
		(drill 0.3048)
		(layers "F.Cu" "B.Cu")
		(net "P3V3_STBY_B")
	)
	(via
		(at 231.41432 -217.78468)
		(size 0.5588)
		(drill 0.3048)
		(layers "F.Cu" "B.Cu")
		(net "P3V3_STBY_B")
	)
	(via
		(at 205.9178 -198.374)
		(size 0.5588)
		(drill 0.3048)
		(layers "F.Cu" "B.Cu")
		(net "P3V3_STBY_B")
	)
	(via
		(at 459.359 -127.381)
		(size 0.5588)
		(drill 0.3048)
		(layers "F.Cu" "B.Cu")
		(net "P3V3_STBY_B")
	)
	(via
		(at 207.800702 -207.009492)
		(size 0.5588)
		(drill 0.3048)
		(layers "F.Cu" "B.Cu")
		(net "P3V3_STBY_B")
	)
	(via
		(at 252.784102 -134.578598)
		(size 0.5588)
		(drill 0.3048)
		(layers "F.Cu" "B.Cu")
		(net "P3V3_STBY_B")
	)
	(via
		(at 263.42594 -218.305634)
		(size 0.5588)
		(drill 0.3048)
		(layers "F.Cu" "B.Cu")
		(net "P3V3_STBY_B")
	)
	(via
		(at 395.605 -8.89)
		(size 0.5588)
		(drill 0.3048)
		(layers "F.Cu" "B.Cu")
		(net "P3V3_STBY_B")
	)
	(via
		(at 446.9384 -30.353)
		(size 0.5588)
		(drill 0.3048)
		(layers "F.Cu" "B.Cu")
		(net "P3V3_STBY_B")
	)
	(via
		(at 240.919 -213.9696)
		(size 0.5588)
		(drill 0.3048)
		(layers "F.Cu" "B.Cu")
		(net "P3V3_STBY_B")
	)
	(via
		(at 332.232 -8.89)
		(size 0.5588)
		(drill 0.3048)
		(layers "F.Cu" "B.Cu")
		(net "P3V3_STBY_B")
	)
	(via
		(at 279.174448 -353.383342)
		(size 0.5588)
		(drill 0.3048)
		(layers "F.Cu" "B.Cu")
		(net "P3V3_STBY_B")
	)
	(via
		(at 150.495 -133.4262)
		(size 0.5588)
		(drill 0.3048)
		(layers "F.Cu" "B.Cu")
		(net "P3V3_STBY_B")
	)
	(via
		(at 191.8208 -252.0696)
		(size 0.5588)
		(drill 0.3048)
		(layers "F.Cu" "B.Cu")
		(net "P3V3_STBY_B")
	)
	(via
		(at 180.086 -20.193)
		(size 0.5588)
		(drill 0.3048)
		(layers "F.Cu" "B.Cu")
		(net "P3V3_STBY_B")
	)
	(via
		(at 35.7505 -263.9695)
		(size 0.5588)
		(drill 0.3048)
		(layers "F.Cu" "B.Cu")
		(net "P3V3_STBY_B")
	)
	(via
		(at 333.248 -242.316)
		(size 0.5588)
		(drill 0.3048)
		(layers "F.Cu" "B.Cu")
		(net "P3V3_STBY_B")
	)
	(via
		(at 288.064448 -346.271342)
		(size 0.5588)
		(drill 0.3048)
		(layers "F.Cu" "B.Cu")
		(net "P3V3_STBY_B")
	)
	(via
		(at 294.019224 -236.919516)
		(size 0.5588)
		(drill 0.3048)
		(layers "F.Cu" "B.Cu")
		(net "P3V3_STBY_B")
	)
	(via
		(at 118.9482 -248.412)
		(size 0.5588)
		(drill 0.3048)
		(layers "F.Cu" "B.Cu")
		(net "P3V3_STBY_B")
	)
	(via
		(at 396.367 -127.381)
		(size 0.5588)
		(drill 0.3048)
		(layers "F.Cu" "B.Cu")
		(net "P3V3_STBY_B")
	)
	(via
		(at 252.3236 -211.6455)
		(size 0.5588)
		(drill 0.3048)
		(layers "F.Cu" "B.Cu")
		(net "P3V3_STBY_B")
	)
	(via
		(at 244.094 -283.845)
		(size 0.5588)
		(drill 0.3048)
		(layers "F.Cu" "B.Cu")
		(net "P3V3_STBY_B")
	)
	(via
		(at 351.3328 -252.1458)
		(size 0.5588)
		(drill 0.3048)
		(layers "F.Cu" "B.Cu")
		(net "P3V3_STBY_B")
	)
	(via
		(at 226.06 -248.031)
		(size 0.5588)
		(drill 0.3048)
		(layers "F.Cu" "B.Cu")
		(net "P3V3_STBY_B")
	)
	(via
		(at 31.877 -252.095)
		(size 0.5588)
		(drill 0.3048)
		(layers "F.Cu" "B.Cu")
		(net "P3V3_STBY_B")
	)
	(via
		(at 293.5986 -299.5422)
		(size 0.7112)
		(drill 0.4064)
		(layers "F.Cu" "B.Cu")
		(net "P3V3_STBY_B")
	)
	(via
		(at 264.033 -226.3394)
		(size 0.5588)
		(drill 0.3048)
		(layers "F.Cu" "B.Cu")
		(net "P3V3_STBY_B")
	)
	(via
		(at 118.059454 -132.373624)
		(size 0.5588)
		(drill 0.3048)
		(layers "F.Cu" "B.Cu")
		(net "P3V3_STBY_B")
	)
	(via
		(at 209.92338 -249.29338)
		(size 0.5588)
		(drill 0.3048)
		(layers "F.Cu" "B.Cu")
		(net "P3V3_STBY_B")
	)
	(via
		(at 229.738936 -199.671686)
		(size 0.5588)
		(drill 0.3048)
		(layers "F.Cu" "B.Cu")
		(net "P3V3_STBY_B")
	)
	(via
		(at 55.88 -248.4628)
		(size 0.5588)
		(drill 0.3048)
		(layers "F.Cu" "B.Cu")
		(net "P3V3_STBY_B")
	)
	(via
		(at 54.737 -20.447)
		(size 0.5588)
		(drill 0.3048)
		(layers "F.Cu" "B.Cu")
		(net "P3V3_STBY_B")
	)
	(via
		(at 279.174448 -351.351342)
		(size 0.5588)
		(drill 0.3048)
		(layers "F.Cu" "B.Cu")
		(net "P3V3_STBY_B")
	)
	(via
		(at 24.257 -247.015)
		(size 0.5588)
		(drill 0.3048)
		(layers "F.Cu" "B.Cu")
		(net "P3V3_STBY_B")
	)
	(via
		(at 467.9696 -7.493)
		(size 0.5588)
		(drill 0.3048)
		(layers "F.Cu" "B.Cu")
		(net "P3V3_STBY_B")
	)
	(via
		(at 216.140538 -106.068368)
		(size 0.5588)
		(drill 0.3048)
		(layers "F.Cu" "B.Cu")
		(net "P3V3_STBY_B")
	)
	(via
		(at 247.88114 -136.59358)
		(size 0.5588)
		(drill 0.3048)
		(layers "F.Cu" "B.Cu")
		(net "P3V3_STBY_B")
	)
	(via
		(at 455.7522 -16.1036)
		(size 0.5588)
		(drill 0.3048)
		(layers "F.Cu" "B.Cu")
		(net "P3V3_STBY_B")
	)
	(via
		(at 211.8868 -202.23988)
		(size 0.5588)
		(drill 0.3048)
		(layers "F.Cu" "B.Cu")
		(net "P3V3_STBY_B")
	)
	(via
		(at 251.23648 -212.725)
		(size 0.6604)
		(drill 0.3302)
		(layers "F.Cu" "B.Cu")
		(net "P3V3_STBY_B")
	)
	(via
		(at 226.9744 -248.031)
		(size 0.5588)
		(drill 0.3048)
		(layers "F.Cu" "B.Cu")
		(net "P3V3_STBY_B")
	)
	(via
		(at 24.3332 -18.2372)
		(size 0.5588)
		(drill 0.3048)
		(layers "F.Cu" "B.Cu")
		(net "P3V3_STBY_B")
	)
	(via
		(at 323.134228 -145.125694)
		(size 0.5588)
		(drill 0.3048)
		(layers "F.Cu" "B.Cu")
		(net "P3V3_STBY_B")
	)
	(via
		(at 98.8695 -263.9695)
		(size 0.5588)
		(drill 0.3048)
		(layers "F.Cu" "B.Cu")
		(net "P3V3_STBY_B")
	)
	(via
		(at 352.2726 -260.2484)
		(size 0.5588)
		(drill 0.3048)
		(layers "F.Cu" "B.Cu")
		(net "P3V3_STBY_B")
	)
	(via
		(at 207.603598 -225.06305)
		(size 0.5588)
		(drill 0.3048)
		(layers "F.Cu" "B.Cu")
		(net "P3V3_STBY_B")
	)
	(via
		(at 292.3794 -299.5422)
		(size 0.7112)
		(drill 0.4064)
		(layers "F.Cu" "B.Cu")
		(net "P3V3_STBY_B")
	)
	(via
		(at 149.6441 -17.653)
		(size 0.5588)
		(drill 0.3048)
		(layers "F.Cu" "B.Cu")
		(net "P3V3_STBY_B")
	)
	(via
		(at 7.747 -17.018)
		(size 0.5588)
		(drill 0.3048)
		(layers "F.Cu" "B.Cu")
		(net "P3V3_STBY_B")
	)
	(via
		(at 218.2368 -226.5426)
		(size 0.6604)
		(drill 0.3302)
		(layers "F.Cu" "B.Cu")
		(net "P3V3_STBY_B")
	)
	(segment
		(start 316.966092 -263.957308)
		(end 227.762308 -263.957308)
		(width 0.508)
		(layer "B.Cu")
		(net "P3V3_STBY_B")
	)
	(segment
		(start 191.0588 -152.77592)
		(end 191.0588 -145.3642)
		(width 0.508)
		(layer "B.Cu")
		(net "P3V3_STBY_B")
	)
	(segment
		(start 207.047592 -166.353998)
		(end 204.636878 -166.353998)
		(width 0.508)
		(layer "B.Cu")
		(net "P3V3_STBY_B")
	)
	(segment
		(start 204.636878 -166.353998)
		(end 191.0588 -152.77592)
		(width 0.508)
		(layer "B.Cu")
		(net "P3V3_STBY_B")
	)
	(segment
		(start 245.237 -285.6865)
		(end 245.237 -285.115)
		(width 0.254)
		(layer "B.Cu")
		(net "P3V3_STBY_B")
	)
	(segment
		(start 227.762308 -263.957308)
		(end 227.457 -263.652)
		(width 0.508)
		(layer "B.Cu")
		(net "P3V3_STBY_B")
	)
	(segment
		(start 320.6496 -260.2738)
		(end 316.966092 -263.957308)
		(width 0.508)
		(layer "B.Cu")
		(net "P3V3_STBY_B")
	)
	(segment
		(start 446.9384 -28.9052)
		(end 455.282554 -20.561046)
		(width 0.508)
		(layer "In2.Cu")
		(net "P3V3_STBY_B")
	)
	(segment
		(start 186.326526 -26.574496)
		(end 186.326526 -28.978606)
		(width 0.508)
		(layer "In2.Cu")
		(net "P3V3_STBY_B")
	)
	(segment
		(start 31.877 -252.095)
		(end 32.385 -252.603)
		(width 0.508)
		(layer "In2.Cu")
		(net "P3V3_STBY_B")
	)
	(segment
		(start 392.022584 -13.488416)
		(end 395.605 -9.906)
		(width 0.508)
		(layer "In2.Cu")
		(net "P3V3_STBY_B")
	)
	(segment
		(start 180.086 -20.193)
		(end 181.514496 -20.193)
		(width 0.508)
		(layer "In2.Cu")
		(net "P3V3_STBY_B")
	)
	(segment
		(start 182.753 -23.00097)
		(end 186.326526 -26.574496)
		(width 0.508)
		(layer "In2.Cu")
		(net "P3V3_STBY_B")
	)
	(segment
		(start 383.8956 -260.2484)
		(end 382.524 -258.8768)
		(width 0.508)
		(layer "In2.Cu")
		(net "P3V3_STBY_B")
	)
	(segment
		(start 55.753 -140.589)
		(end 59.563 -144.399)
		(width 0.508)
		(layer "In2.Cu")
		(net "P3V3_STBY_B")
	)
	(segment
		(start 118.872 -133.18617)
		(end 118.059454 -132.373624)
		(width 0.508)
		(layer "In2.Cu")
		(net "P3V3_STBY_B")
	)
	(segment
		(start 392.303 -131.445)
		(end 396.367 -127.381)
		(width 0.508)
		(layer "In2.Cu")
		(net "P3V3_STBY_B")
	)
	(segment
		(start 55.88 -133.096)
		(end 55.753 -133.223)
		(width 0.508)
		(layer "In2.Cu")
		(net "P3V3_STBY_B")
	)
	(segment
		(start 423.802048 -17.522952)
		(end 427.863 -13.462)
		(width 0.508)
		(layer "In2.Cu")
		(net "P3V3_STBY_B")
	)
	(segment
		(start 387.5151 -29.1719)
		(end 392.022584 -24.664416)
		(width 0.508)
		(layer "In2.Cu")
		(net "P3V3_STBY_B")
	)
	(segment
		(start 150.495 -25.019)
		(end 150.495 -18.5039)
		(width 0.508)
		(layer "In2.Cu")
		(net "P3V3_STBY_B")
	)
	(segment
		(start 320.04 -252.349)
		(end 320.04 -259.6642)
		(width 0.508)
		(layer "In2.Cu")
		(net "P3V3_STBY_B")
	)
	(segment
		(start 184.124854 -135.560054)
		(end 181.9656 -133.4008)
		(width 0.508)
		(layer "In2.Cu")
		(net "P3V3_STBY_B")
	)
	(segment
		(start 161.9885 -148.9075)
		(end 161.9885 -148.666708)
		(width 0.508)
		(layer "In2.Cu")
		(net "P3V3_STBY_B")
	)
	(segment
		(start 384.7973 -29.1719)
		(end 387.5151 -29.1719)
		(width 0.508)
		(layer "In2.Cu")
		(net "P3V3_STBY_B")
	)
	(segment
		(start 354.717096 -28.873704)
		(end 354.132896 -28.873704)
		(width 0.508)
		(layer "In2.Cu")
		(net "P3V3_STBY_B")
	)
	(segment
		(start 131.571746 -148.08581)
		(end 123.567952 -140.082016)
		(width 0.508)
		(layer "In2.Cu")
		(net "P3V3_STBY_B")
	)
	(segment
		(start 121.73331 -140.082016)
		(end 118.872 -137.220706)
		(width 0.508)
		(layer "In2.Cu")
		(net "P3V3_STBY_B")
	)
	(segment
		(start 326.1741 -28.7274)
		(end 322.2752 -28.7274)
		(width 0.508)
		(layer "In2.Cu")
		(net "P3V3_STBY_B")
	)
	(segment
		(start 64.008 -260.8072)
		(end 67.1703 -263.9695)
		(width 0.508)
		(layer "In2.Cu")
		(net "P3V3_STBY_B")
	)
	(segment
		(start 481.609654 -244.96649)
		(end 477.402144 -249.174)
		(width 0.508)
		(layer "In2.Cu")
		(net "P3V3_STBY_B")
	)
	(segment
		(start 360.6546 -131.4704)
		(end 364.744 -127.381)
		(width 0.508)
		(layer "In2.Cu")
		(net "P3V3_STBY_B")
	)
	(segment
		(start 24.257 -133.477)
		(end 24.257 -137.033)
		(width 0.508)
		(layer "In2.Cu")
		(net "P3V3_STBY_B")
	)
	(segment
		(start 478.3582 -134.62)
		(end 481.301298 -137.563098)
		(width 0.508)
		(layer "In2.Cu")
		(net "P3V3_STBY_B")
	)
	(segment
		(start 87.376 -25.019)
		(end 87.376 -18.4531)
		(width 0.508)
		(layer "In2.Cu")
		(net "P3V3_STBY_B")
	)
	(segment
		(start 99.220528 -149.510496)
		(end 95.584264 -149.510496)
		(width 0.508)
		(layer "In2.Cu")
		(net "P3V3_STBY_B")
	)
	(segment
		(start 332.232 -8.89)
		(end 332.232 -9.652)
		(width 0.508)
		(layer "In2.Cu")
		(net "P3V3_STBY_B")
	)
	(segment
		(start 87.376 -18.4531)
		(end 86.5251 -17.6022)
		(width 0.508)
		(layer "In2.Cu")
		(net "P3V3_STBY_B")
	)
	(segment
		(start 478.4344 -19.2024)
		(end 478.894902 -19.662902)
		(width 0.508)
		(layer "In2.Cu")
		(net "P3V3_STBY_B")
	)
	(segment
		(start 487.7308 -230.8352)
		(end 487.7308 -237.572042)
		(width 0.508)
		(layer "In2.Cu")
		(net "P3V3_STBY_B")
	)
	(segment
		(start 487.9594 -230.6066)
		(end 487.7308 -230.8352)
		(width 0.508)
		(layer "In2.Cu")
		(net "P3V3_STBY_B")
	)
	(segment
		(start 454.72731 -99.771962)
		(end 461.250284 -99.771962)
		(width 0.508)
		(layer "In2.Cu")
		(net "P3V3_STBY_B")
	)
	(segment
		(start 118.3132 -24.4602)
		(end 118.3132 -20.9042)
		(width 0.508)
		(layer "In2.Cu")
		(net "P3V3_STBY_B")
	)
	(segment
		(start 470.662 -128.016)
		(end 476.0468 -133.4008)
		(width 0.508)
		(layer "In2.Cu")
		(net "P3V3_STBY_B")
	)
	(segment
		(start 459.359 -127.381)
		(end 459.359 -128.397)
		(width 0.508)
		(layer "In2.Cu")
		(net "P3V3_STBY_B")
	)
	(segment
		(start 332.232 -9.652)
		(end 331.2668 -10.6172)
		(width 0.508)
		(layer "In2.Cu")
		(net "P3V3_STBY_B")
	)
	(segment
		(start 352.2726 -260.2484)
		(end 351.282 -259.2578)
		(width 0.508)
		(layer "In2.Cu")
		(net "P3V3_STBY_B")
	)
	(segment
		(start 294.019224 -236.919516)
		(end 295.877488 -236.919516)
		(width 0.508)
		(layer "In2.Cu")
		(net "P3V3_STBY_B")
	)
	(segment
		(start 478.4344 -17.359376)
		(end 478.4344 -19.2024)
		(width 0.508)
		(layer "In2.Cu")
		(net "P3V3_STBY_B")
	)
	(segment
		(start 24.257 -18.3134)
		(end 24.3332 -18.2372)
		(width 0.508)
		(layer "In2.Cu")
		(net "P3V3_STBY_B")
	)
	(segment
		(start 94.3737 -28.0543)
		(end 90.4113 -28.0543)
		(width 0.508)
		(layer "In2.Cu")
		(net "P3V3_STBY_B")
	)
	(segment
		(start 420.3954 -27.5336)
		(end 423.802048 -24.126952)
		(width 0.508)
		(layer "In2.Cu")
		(net "P3V3_STBY_B")
	)
	(segment
		(start 308.575456 -229.454456)
		(end 314.579 -235.458)
		(width 0.508)
		(layer "In2.Cu")
		(net "P3V3_STBY_B")
	)
	(segment
		(start 416.820096 -143.605504)
		(end 415.0868 -145.3388)
		(width 0.5588)
		(layer "In2.Cu")
		(net "P3V3_STBY_B")
	)
	(segment
		(start 95.504 -260.604)
		(end 98.8695 -263.9695)
		(width 0.508)
		(layer "In2.Cu")
		(net "P3V3_STBY_B")
	)
	(segment
		(start 331.2668 -17.8054)
		(end 330.7588 -18.3134)
		(width 0.508)
		(layer "In2.Cu")
		(net "P3V3_STBY_B")
	)
	(segment
		(start 118.872 -137.220706)
		(end 118.872 -133.18617)
		(width 0.508)
		(layer "In2.Cu")
		(net "P3V3_STBY_B")
	)
	(segment
		(start 320.04 -259.6642)
		(end 320.6496 -260.2738)
		(width 0.508)
		(layer "In2.Cu")
		(net "P3V3_STBY_B")
	)
	(segment
		(start 189.432946 -143.738346)
		(end 186.2836 -143.738346)
		(width 0.508)
		(layer "In2.Cu")
		(net "P3V3_STBY_B")
	)
	(segment
		(start 64.7446 -30.3784)
		(end 63.4238 -29.0576)
		(width 0.508)
		(layer "In2.Cu")
		(net "P3V3_STBY_B")
	)
	(segment
		(start 360.774996 -16.923004)
		(end 360.774996 -22.815804)
		(width 0.508)
		(layer "In2.Cu")
		(net "P3V3_STBY_B")
	)
	(segment
		(start 354.132896 -28.873704)
		(end 354.1268 -28.8798)
		(width 0.508)
		(layer "In2.Cu")
		(net "P3V3_STBY_B")
	)
	(segment
		(start 418.211 -27.5336)
		(end 420.3954 -27.5336)
		(width 0.508)
		(layer "In2.Cu")
		(net "P3V3_STBY_B")
	)
	(segment
		(start 383.8448 -145.3642)
		(end 383.8448 -145.2118)
		(width 0.508)
		(layer "In2.Cu")
		(net "P3V3_STBY_B")
	)
	(segment
		(start 389.33755 -143.74495)
		(end 392.303 -140.7795)
		(width 0.508)
		(layer "In2.Cu")
		(net "P3V3_STBY_B")
	)
	(segment
		(start 424.053 -132.207)
		(end 424.053 -138.110468)
		(width 0.5588)
		(layer "In2.Cu")
		(net "P3V3_STBY_B")
	)
	(segment
		(start 55.0418 -20.7518)
		(end 54.737 -20.447)
		(width 0.508)
		(layer "In2.Cu")
		(net "P3V3_STBY_B")
	)
	(segment
		(start 360.6546 -140.8049)
		(end 360.6546 -131.4704)
		(width 0.508)
		(layer "In2.Cu")
		(net "P3V3_STBY_B")
	)
	(segment
		(start 127 -251.968)
		(end 127 -260.604)
		(width 0.508)
		(layer "In2.Cu")
		(net "P3V3_STBY_B")
	)
	(segment
		(start 324.362318 -143.897604)
		(end 326.065896 -143.897604)
		(width 0.508)
		(layer "In2.Cu")
		(net "P3V3_STBY_B")
	)
	(segment
		(start 329.2602 -140.7033)
		(end 329.2602 -131.3688)
		(width 0.508)
		(layer "In2.Cu")
		(net "P3V3_STBY_B")
	)
	(segment
		(start 55.0418 -24.3078)
		(end 55.0418 -20.7518)
		(width 0.508)
		(layer "In2.Cu")
		(net "P3V3_STBY_B")
	)
	(segment
		(start 480.441 -15.352776)
		(end 478.4344 -17.359376)
		(width 0.508)
		(layer "In2.Cu")
		(net "P3V3_STBY_B")
	)
	(segment
		(start 95.504 -252.222)
		(end 95.504 -260.604)
		(width 0.508)
		(layer "In2.Cu")
		(net "P3V3_STBY_B")
	)
	(segment
		(start 425.731178 -112.495076)
		(end 433.09159 -105.134664)
		(width 0.508)
		(layer "In2.Cu")
		(net "P3V3_STBY_B")
	)
	(segment
		(start 32.385 -260.604)
		(end 35.7505 -263.9695)
		(width 0.508)
		(layer "In2.Cu")
		(net "P3V3_STBY_B")
	)
	(segment
		(start 32.385 -252.603)
		(end 32.385 -260.604)
		(width 0.508)
		(layer "In2.Cu")
		(net "P3V3_STBY_B")
	)
	(segment
		(start 161.9885 -148.666708)
		(end 150.495 -137.173208)
		(width 0.508)
		(layer "In2.Cu")
		(net "P3V3_STBY_B")
	)
	(segment
		(start 481.609654 -243.693188)
		(end 481.609654 -244.96649)
		(width 0.508)
		(layer "In2.Cu")
		(net "P3V3_STBY_B")
	)
	(segment
		(start 63.4238 -29.0576)
		(end 59.7916 -29.0576)
		(width 0.508)
		(layer "In2.Cu")
		(net "P3V3_STBY_B")
	)
	(segment
		(start 182.753 -21.431504)
		(end 182.753 -23.00097)
		(width 0.508)
		(layer "In2.Cu")
		(net "P3V3_STBY_B")
	)
	(segment
		(start 96.393 -30.353)
		(end 96.393 -30.0736)
		(width 0.508)
		(layer "In2.Cu")
		(net "P3V3_STBY_B")
	)
	(segment
		(start 383.8956 -30.353)
		(end 383.8956 -30.0736)
		(width 0.508)
		(layer "In2.Cu")
		(net "P3V3_STBY_B")
	)
	(segment
		(start 13.081 -94.6404)
		(end 13.081 -122.301)
		(width 0.508)
		(layer "In2.Cu")
		(net "P3V3_STBY_B")
	)
	(segment
		(start 364.744 -12.319)
		(end 364.744 -12.954)
		(width 0.508)
		(layer "In2.Cu")
		(net "P3V3_STBY_B")
	)
	(segment
		(start 477.402144 -249.174)
		(end 476.4532 -249.174)
		(width 0.508)
		(layer "In2.Cu")
		(net "P3V3_STBY_B")
	)
	(segment
		(start 156.8831 -27.7241)
		(end 153.2001 -27.7241)
		(width 0.508)
		(layer "In2.Cu")
		(net "P3V3_STBY_B")
	)
	(segment
		(start 414.401 -259.3594)
		(end 414.401 -252.476)
		(width 0.508)
		(layer "In2.Cu")
		(net "P3V3_STBY_B")
	)
	(segment
		(start 47.129954 -8.9408)
		(end 47.129954 -5.468366)
		(width 0.508)
		(layer "In2.Cu")
		(net "P3V3_STBY_B")
	)
	(segment
		(start 330.7588 -18.3134)
		(end 329.8952 -18.3134)
		(width 0.508)
		(layer "In2.Cu")
		(net "P3V3_STBY_B")
	)
	(segment
		(start 351.523808 -145.567908)
		(end 351.523808 -145.352008)
		(width 0.508)
		(layer "In2.Cu")
		(net "P3V3_STBY_B")
	)
	(segment
		(start 455.282554 -16.573246)
		(end 455.7522 -16.1036)
		(width 0.508)
		(layer "In2.Cu")
		(net "P3V3_STBY_B")
	)
	(segment
		(start 427.863 -128.397)
		(end 424.053 -132.207)
		(width 0.5588)
		(layer "In2.Cu")
		(net "P3V3_STBY_B")
	)
	(segment
		(start 424.053 -138.110468)
		(end 418.557964 -143.605504)
		(width 0.5588)
		(layer "In2.Cu")
		(net "P3V3_STBY_B")
	)
	(segment
		(start 459.359 -128.397)
		(end 455.676 -132.08)
		(width 0.508)
		(layer "In2.Cu")
		(net "P3V3_STBY_B")
	)
	(segment
		(start 425.731178 -125.249178)
		(end 425.731178 -112.495076)
		(width 0.508)
		(layer "In2.Cu")
		(net "P3V3_STBY_B")
	)
	(segment
		(start 322.2752 -28.7274)
		(end 320.7004 -30.3022)
		(width 0.508)
		(layer "In2.Cu")
		(net "P3V3_STBY_B")
	)
	(segment
		(start 351.523808 -145.352008)
		(end 354.299012 -142.576804)
		(width 0.508)
		(layer "In2.Cu")
		(net "P3V3_STBY_B")
	)
	(segment
		(start 478.894902 -19.662902)
		(end 478.919032 -19.662902)
		(width 0.508)
		(layer "In2.Cu")
		(net "P3V3_STBY_B")
	)
	(segment
		(start 427.863 -13.462)
		(end 427.863 -12.319)
		(width 0.508)
		(layer "In2.Cu")
		(net "P3V3_STBY_B")
	)
	(segment
		(start 28.2194 -28.9814)
		(end 24.257 -25.019)
		(width 0.508)
		(layer "In2.Cu")
		(net "P3V3_STBY_B")
	)
	(segment
		(start 59.7916 -29.0576)
		(end 55.0418 -24.3078)
		(width 0.508)
		(layer "In2.Cu")
		(net "P3V3_STBY_B")
	)
	(segment
		(start 314.579 -235.458)
		(end 314.579 -246.888)
		(width 0.508)
		(layer "In2.Cu")
		(net "P3V3_STBY_B")
	)
	(segment
		(start 364.744 -12.954)
		(end 360.774996 -16.923004)
		(width 0.508)
		(layer "In2.Cu")
		(net "P3V3_STBY_B")
	)
	(segment
		(start 385.31165 -143.74495)
		(end 389.33755 -143.74495)
		(width 0.508)
		(layer "In2.Cu")
		(net "P3V3_STBY_B")
	)
	(segment
		(start 395.605 -9.906)
		(end 395.605 -8.89)
		(width 0.508)
		(layer "In2.Cu")
		(net "P3V3_STBY_B")
	)
	(segment
		(start 446.9384 -30.353)
		(end 446.9384 -28.9052)
		(width 0.508)
		(layer "In2.Cu")
		(net "P3V3_STBY_B")
	)
	(segment
		(start 300.933612 -231.863392)
		(end 303.342548 -229.454456)
		(width 0.508)
		(layer "In2.Cu")
		(net "P3V3_STBY_B")
	)
	(segment
		(start 329.8952 -18.3134)
		(end 329.209908 -18.998692)
		(width 0.508)
		(layer "In2.Cu")
		(net "P3V3_STBY_B")
	)
	(segment
		(start 392.022584 -24.664416)
		(end 392.022584 -13.488416)
		(width 0.508)
		(layer "In2.Cu")
		(net "P3V3_STBY_B")
	)
	(segment
		(start 189.683644 -33.470088)
		(end 191.382142 -35.168586)
		(width 0.508)
		(layer "In2.Cu")
		(net "P3V3_STBY_B")
	)
	(segment
		(start 487.9594 -170.5864)
		(end 487.9594 -230.6066)
		(width 0.508)
		(layer "In2.Cu")
		(net "P3V3_STBY_B")
	)
	(segment
		(start 118.3132 -20.9042)
		(end 117.856 -20.447)
		(width 0.508)
		(layer "In2.Cu")
		(net "P3V3_STBY_B")
	)
	(segment
		(start 122.5423 -28.6893)
		(end 118.3132 -24.4602)
		(width 0.508)
		(layer "In2.Cu")
		(net "P3V3_STBY_B")
	)
	(segment
		(start 90.4113 -28.0543)
		(end 87.376 -25.019)
		(width 0.508)
		(layer "In2.Cu")
		(net "P3V3_STBY_B")
	)
	(segment
		(start 95.584264 -149.510496)
		(end 87.376 -141.302232)
		(width 0.508)
		(layer "In2.Cu")
		(net "P3V3_STBY_B")
	)
	(segment
		(start 449.364608 -105.134664)
		(end 454.72731 -99.771962)
		(width 0.508)
		(layer "In2.Cu")
		(net "P3V3_STBY_B")
	)
	(segment
		(start 181.514496 -20.193)
		(end 182.753 -21.431504)
		(width 0.508)
		(layer "In2.Cu")
		(net "P3V3_STBY_B")
	)
	(segment
		(start 481.301298 -137.563098)
		(end 481.301298 -163.928298)
		(width 0.508)
		(layer "In2.Cu")
		(net "P3V3_STBY_B")
	)
	(segment
		(start 186.326526 -28.978606)
		(end 189.683644 -32.335724)
		(width 0.508)
		(layer "In2.Cu")
		(net "P3V3_STBY_B")
	)
	(segment
		(start 480.441 -12.5984)
		(end 480.441 -15.352776)
		(width 0.508)
		(layer "In2.Cu")
		(net "P3V3_STBY_B")
	)
	(segment
		(start 59.563 -144.399)
		(end 62.738 -144.399)
		(width 0.508)
		(layer "In2.Cu")
		(net "P3V3_STBY_B")
	)
	(segment
		(start 96.393 -30.0736)
		(end 94.3737 -28.0543)
		(width 0.508)
		(layer "In2.Cu")
		(net "P3V3_STBY_B")
	)
	(segment
		(start 153.2001 -27.7241)
		(end 150.495 -25.019)
		(width 0.508)
		(layer "In2.Cu")
		(net "P3V3_STBY_B")
	)
	(segment
		(start 87.376 -141.302232)
		(end 87.376 -133.4262)
		(width 0.508)
		(layer "In2.Cu")
		(net "P3V3_STBY_B")
	)
	(segment
		(start 32.1564 -28.9814)
		(end 28.2194 -28.9814)
		(width 0.508)
		(layer "In2.Cu")
		(net "P3V3_STBY_B")
	)
	(segment
		(start 54.737 -20.447)
		(end 54.737 -17.10944)
		(width 0.508)
		(layer "In2.Cu")
		(net "P3V3_STBY_B")
	)
	(segment
		(start 433.09159 -105.134664)
		(end 449.364608 -105.134664)
		(width 0.508)
		(layer "In2.Cu")
		(net "P3V3_STBY_B")
	)
	(segment
		(start 358.882696 -142.576804)
		(end 360.6546 -140.8049)
		(width 0.508)
		(layer "In2.Cu")
		(net "P3V3_STBY_B")
	)
	(segment
		(start 455.676 -132.08)
		(end 455.676 -140.3985)
		(width 0.508)
		(layer "In2.Cu")
		(net "P3V3_STBY_B")
	)
	(segment
		(start 351.282 -252.1966)
		(end 351.3328 -252.1458)
		(width 0.508)
		(layer "In2.Cu")
		(net "P3V3_STBY_B")
	)
	(segment
		(start 33.4264 -30.2514)
		(end 32.1564 -28.9814)
		(width 0.508)
		(layer "In2.Cu")
		(net "P3V3_STBY_B")
	)
	(segment
		(start 360.774996 -22.815804)
		(end 354.717096 -28.873704)
		(width 0.508)
		(layer "In2.Cu")
		(net "P3V3_STBY_B")
	)
	(segment
		(start 62.738 -144.399)
		(end 67.2465 -148.9075)
		(width 0.508)
		(layer "In2.Cu")
		(net "P3V3_STBY_B")
	)
	(segment
		(start 487.7308 -237.572042)
		(end 481.609654 -243.693188)
		(width 0.508)
		(layer "In2.Cu")
		(net "P3V3_STBY_B")
	)
	(segment
		(start 354.299012 -142.576804)
		(end 358.882696 -142.576804)
		(width 0.508)
		(layer "In2.Cu")
		(net "P3V3_STBY_B")
	)
	(segment
		(start 383.8448 -145.2118)
		(end 385.31165 -143.74495)
		(width 0.508)
		(layer "In2.Cu")
		(net "P3V3_STBY_B")
	)
	(segment
		(start 382.524 -258.8768)
		(end 382.524 -252.222)
		(width 0.508)
		(layer "In2.Cu")
		(net "P3V3_STBY_B")
	)
	(segment
		(start 49.796954 -12.169394)
		(end 49.796954 -11.6078)
		(width 0.508)
		(layer "In2.Cu")
		(net "P3V3_STBY_B")
	)
	(segment
		(start 7.747 -17.018)
		(end 7.747 -89.3064)
		(width 0.508)
		(layer "In2.Cu")
		(net "P3V3_STBY_B")
	)
	(segment
		(start 303.342548 -229.454456)
		(end 308.575456 -229.454456)
		(width 0.508)
		(layer "In2.Cu")
		(net "P3V3_STBY_B")
	)
	(segment
		(start 392.303 -140.7795)
		(end 392.303 -131.445)
		(width 0.508)
		(layer "In2.Cu")
		(net "P3V3_STBY_B")
	)
	(segment
		(start 54.737 -17.10944)
		(end 49.796954 -12.169394)
		(width 0.508)
		(layer "In2.Cu")
		(net "P3V3_STBY_B")
	)
	(segment
		(start 326.065896 -143.897604)
		(end 329.2602 -140.7033)
		(width 0.508)
		(layer "In2.Cu")
		(net "P3V3_STBY_B")
	)
	(segment
		(start 476.0468 -133.4008)
		(end 477.139 -133.4008)
		(width 0.508)
		(layer "In2.Cu")
		(net "P3V3_STBY_B")
	)
	(segment
		(start 423.802048 -24.126952)
		(end 423.802048 -17.522952)
		(width 0.508)
		(layer "In2.Cu")
		(net "P3V3_STBY_B")
	)
	(segment
		(start 415.3662 -30.3784)
		(end 418.211 -27.5336)
		(width 0.508)
		(layer "In2.Cu")
		(net "P3V3_STBY_B")
	)
	(segment
		(start 24.257 -137.033)
		(end 36.322 -149.098)
		(width 0.508)
		(layer "In2.Cu")
		(net "P3V3_STBY_B")
	)
	(segment
		(start 24.257 -25.019)
		(end 24.257 -18.3134)
		(width 0.508)
		(layer "In2.Cu")
		(net "P3V3_STBY_B")
	)
	(segment
		(start 159.512 -30.353)
		(end 156.8831 -27.7241)
		(width 0.508)
		(layer "In2.Cu")
		(net "P3V3_STBY_B")
	)
	(segment
		(start 487.426 -73.596246)
		(end 487.426 -12.954)
		(width 0.508)
		(layer "In2.Cu")
		(net "P3V3_STBY_B")
	)
	(segment
		(start 455.282554 -20.561046)
		(end 455.282554 -16.573246)
		(width 0.508)
		(layer "In2.Cu")
		(net "P3V3_STBY_B")
	)
	(segment
		(start 191.0588 -145.3642)
		(end 189.432946 -143.738346)
		(width 0.508)
		(layer "In2.Cu")
		(net "P3V3_STBY_B")
	)
	(segment
		(start 481.301298 -163.928298)
		(end 487.9594 -170.5864)
		(width 0.508)
		(layer "In2.Cu")
		(net "P3V3_STBY_B")
	)
	(segment
		(start 64.008 -252.095)
		(end 64.008 -260.8072)
		(width 0.508)
		(layer "In2.Cu")
		(net "P3V3_STBY_B")
	)
	(segment
		(start 127 -260.604)
		(end 130.3655 -263.9695)
		(width 0.508)
		(layer "In2.Cu")
		(net "P3V3_STBY_B")
	)
	(segment
		(start 55.753 -133.223)
		(end 55.753 -140.589)
		(width 0.508)
		(layer "In2.Cu")
		(net "P3V3_STBY_B")
	)
	(segment
		(start 295.877488 -236.919516)
		(end 300.933612 -231.863392)
		(width 0.508)
		(layer "In2.Cu")
		(net "P3V3_STBY_B")
	)
	(segment
		(start 427.863 -127.381)
		(end 427.863 -128.397)
		(width 0.5588)
		(layer "In2.Cu")
		(net "P3V3_STBY_B")
	)
	(segment
		(start 49.796954 -11.6078)
		(end 47.129954 -8.9408)
		(width 0.508)
		(layer "In2.Cu")
		(net "P3V3_STBY_B")
	)
	(segment
		(start 150.495 -18.5039)
		(end 149.6441 -17.653)
		(width 0.508)
		(layer "In2.Cu")
		(net "P3V3_STBY_B")
	)
	(segment
		(start 477.139 -133.4008)
		(end 478.3582 -134.62)
		(width 0.508)
		(layer "In2.Cu")
		(net "P3V3_STBY_B")
	)
	(segment
		(start 331.2668 -10.6172)
		(end 331.2668 -17.8054)
		(width 0.508)
		(layer "In2.Cu")
		(net "P3V3_STBY_B")
	)
	(segment
		(start 123.567952 -140.082016)
		(end 121.73331 -140.082016)
		(width 0.508)
		(layer "In2.Cu")
		(net "P3V3_STBY_B")
	)
	(segment
		(start 329.209908 -25.691592)
		(end 326.1741 -28.7274)
		(width 0.508)
		(layer "In2.Cu")
		(net "P3V3_STBY_B")
	)
	(segment
		(start 351.282 -259.2578)
		(end 351.282 -252.1966)
		(width 0.508)
		(layer "In2.Cu")
		(net "P3V3_STBY_B")
	)
	(segment
		(start 480.3902 -12.5476)
		(end 480.441 -12.5984)
		(width 0.508)
		(layer "In2.Cu")
		(net "P3V3_STBY_B")
	)
	(segment
		(start 461.250284 -99.771962)
		(end 487.426 -73.596246)
		(width 0.508)
		(layer "In2.Cu")
		(net "P3V3_STBY_B")
	)
	(segment
		(start 329.2602 -131.3688)
		(end 333.248 -127.381)
		(width 0.508)
		(layer "In2.Cu")
		(net "P3V3_STBY_B")
	)
	(segment
		(start 189.683644 -32.335724)
		(end 189.683644 -33.470088)
		(width 0.508)
		(layer "In2.Cu")
		(net "P3V3_STBY_B")
	)
	(segment
		(start 455.676 -140.3985)
		(end 446.9765 -149.098)
		(width 0.508)
		(layer "In2.Cu")
		(net "P3V3_STBY_B")
	)
	(segment
		(start 7.747 -89.3064)
		(end 13.081 -94.6404)
		(width 0.508)
		(layer "In2.Cu")
		(net "P3V3_STBY_B")
	)
	(segment
		(start 186.2836 -143.738346)
		(end 184.124854 -141.5796)
		(width 0.508)
		(layer "In2.Cu")
		(net "P3V3_STBY_B")
	)
	(segment
		(start 415.3154 -260.2738)
		(end 414.401 -259.3594)
		(width 0.508)
		(layer "In2.Cu")
		(net "P3V3_STBY_B")
	)
	(segment
		(start 323.134228 -145.125694)
		(end 324.362318 -143.897604)
		(width 0.508)
		(layer "In2.Cu")
		(net "P3V3_STBY_B")
	)
	(segment
		(start 127.9906 -30.353)
		(end 126.3269 -28.6893)
		(width 0.508)
		(layer "In2.Cu")
		(net "P3V3_STBY_B")
	)
	(segment
		(start 320.7004 -30.3022)
		(end 320.7004 -30.4038)
		(width 0.508)
		(layer "In2.Cu")
		(net "P3V3_STBY_B")
	)
	(segment
		(start 446.024 -259.4864)
		(end 446.024 -252.349)
		(width 0.508)
		(layer "In2.Cu")
		(net "P3V3_STBY_B")
	)
	(segment
		(start 13.081 -122.301)
		(end 24.257 -133.477)
		(width 0.508)
		(layer "In2.Cu")
		(net "P3V3_STBY_B")
	)
	(segment
		(start 383.8956 -30.0736)
		(end 384.7973 -29.1719)
		(width 0.508)
		(layer "In2.Cu")
		(net "P3V3_STBY_B")
	)
	(segment
		(start 184.124854 -141.5796)
		(end 184.124854 -135.560054)
		(width 0.508)
		(layer "In2.Cu")
		(net "P3V3_STBY_B")
	)
	(segment
		(start 314.579 -246.888)
		(end 320.04 -252.349)
		(width 0.508)
		(layer "In2.Cu")
		(net "P3V3_STBY_B")
	)
	(segment
		(start 126.3269 -28.6893)
		(end 122.5423 -28.6893)
		(width 0.508)
		(layer "In2.Cu")
		(net "P3V3_STBY_B")
	)
	(segment
		(start 446.8622 -260.3246)
		(end 446.024 -259.4864)
		(width 0.508)
		(layer "In2.Cu")
		(net "P3V3_STBY_B")
	)
	(segment
		(start 418.557964 -143.605504)
		(end 416.820096 -143.605504)
		(width 0.5588)
		(layer "In2.Cu")
		(net "P3V3_STBY_B")
	)
	(segment
		(start 150.495 -137.173208)
		(end 150.495 -133.4262)
		(width 0.508)
		(layer "In2.Cu")
		(net "P3V3_STBY_B")
	)
	(segment
		(start 427.863 -127.381)
		(end 425.731178 -125.249178)
		(width 0.508)
		(layer "In2.Cu")
		(net "P3V3_STBY_B")
	)
	(segment
		(start 329.209908 -18.998692)
		(end 329.209908 -25.691592)
		(width 0.508)
		(layer "In2.Cu")
		(net "P3V3_STBY_B")
	)
	(segment
		(start 366.776 -126.238)
		(end 395.224 -126.238)
		(width 0.508)
		(layer "In5.Cu")
		(net "P3V3_STBY_B")
	)
	(segment
		(start 185.6232 -248.4882)
		(end 182.0672 -248.4882)
		(width 0.508)
		(layer "In5.Cu")
		(net "P3V3_STBY_B")
	)
	(segment
		(start 353.730814 -11.338814)
		(end 351.282 -8.89)
		(width 0.508)
		(layer "In5.Cu")
		(net "P3V3_STBY_B")
	)
	(segment
		(start 95.504 -252.222)
		(end 91.7448 -248.4628)
		(width 0.508)
		(layer "In5.Cu")
		(net "P3V3_STBY_B")
	)
	(segment
		(start 109.4486 -126.746)
		(end 94.9198 -126.746)
		(width 0.508)
		(layer "In5.Cu")
		(net "P3V3_STBY_B")
	)
	(segment
		(start 458.47 -126.492)
		(end 459.359 -127.381)
		(width 0.508)
		(layer "In5.Cu")
		(net "P3V3_STBY_B")
	)
	(segment
		(start 54.9656 -248.4374)
		(end 55.88 -248.4374)
		(width 0.508)
		(layer "In5.Cu")
		(net "P3V3_STBY_B")
	)
	(segment
		(start 454.0758 -10.6934)
		(end 451.9676 -8.5852)
		(width 0.508)
		(layer "In5.Cu")
		(net "P3V3_STBY_B")
	)
	(segment
		(start 333.248 -127.381)
		(end 334.01 -126.619)
		(width 0.508)
		(layer "In5.Cu")
		(net "P3V3_STBY_B")
	)
	(segment
		(start 53.6702 -249.7328)
		(end 54.9656 -248.4374)
		(width 0.508)
		(layer "In5.Cu")
		(net "P3V3_STBY_B")
	)
	(segment
		(start 470.662 -243.078)
		(end 469.9 -242.316)
		(width 0.508)
		(layer "In5.Cu")
		(net "P3V3_STBY_B")
	)
	(segment
		(start 55.5498 -133.4262)
		(end 55.88 -133.096)
		(width 0.508)
		(layer "In5.Cu")
		(net "P3V3_STBY_B")
	)
	(segment
		(start 428.117 -242.316)
		(end 427.863 -242.316)
		(width 0.508)
		(layer "In5.Cu")
		(net "P3V3_STBY_B")
	)
	(segment
		(start 416.179 -8.89)
		(end 395.605 -8.89)
		(width 0.508)
		(layer "In5.Cu")
		(net "P3V3_STBY_B")
	)
	(segment
		(start 382.524 -252.222)
		(end 377.571 -252.222)
		(width 0.508)
		(layer "In5.Cu")
		(net "P3V3_STBY_B")
	)
	(segment
		(start 460.163926 -16.1036)
		(end 455.7522 -16.1036)
		(width 0.508)
		(layer "In5.Cu")
		(net "P3V3_STBY_B")
	)
	(segment
		(start 179.7304 -248.4882)
		(end 176.9618 -251.2568)
		(width 0.508)
		(layer "In5.Cu")
		(net "P3V3_STBY_B")
	)
	(segment
		(start 191.7954 -252.095)
		(end 189.23 -252.095)
		(width 0.508)
		(layer "In5.Cu")
		(net "P3V3_STBY_B")
	)
	(segment
		(start 333.248 -242.316)
		(end 328.549 -247.015)
		(width 0.508)
		(layer "In5.Cu")
		(net "P3V3_STBY_B")
	)
	(segment
		(start 347.853 -252.1458)
		(end 340.418928 -244.711728)
		(width 0.508)
		(layer "In5.Cu")
		(net "P3V3_STBY_B")
	)
	(segment
		(start 83.6422 -248.4628)
		(end 80.8736 -251.2314)
		(width 0.508)
		(layer "In5.Cu")
		(net "P3V3_STBY_B")
	)
	(segment
		(start 55.88 -248.4374)
		(end 55.88 -248.4628)
		(width 0.508)
		(layer "In5.Cu")
		(net "P3V3_STBY_B")
	)
	(segment
		(start 414.401 -252.476)
		(end 409.067 -252.476)
		(width 0.508)
		(layer "In5.Cu")
		(net "P3V3_STBY_B")
	)
	(segment
		(start 76.9366 -251.2314)
		(end 76.073 -252.095)
		(width 0.508)
		(layer "In5.Cu")
		(net "P3V3_STBY_B")
	)
	(segment
		(start 127 -251.968)
		(end 125.824488 -251.968)
		(width 0.508)
		(layer "In5.Cu")
		(net "P3V3_STBY_B")
	)
	(segment
		(start 120.610376 -132.373624)
		(end 118.059454 -132.373624)
		(width 0.508)
		(layer "In5.Cu")
		(net "P3V3_STBY_B")
	)
	(segment
		(start 366.903 -12.319)
		(end 364.744 -12.319)
		(width 0.508)
		(layer "In5.Cu")
		(net "P3V3_STBY_B")
	)
	(segment
		(start 388.493 -252.222)
		(end 382.524 -252.222)
		(width 0.508)
		(layer "In5.Cu")
		(net "P3V3_STBY_B")
	)
	(segment
		(start 426.72 -126.238)
		(end 427.863 -127.381)
		(width 0.508)
		(layer "In5.Cu")
		(net "P3V3_STBY_B")
	)
	(segment
		(start 7.747 -17.018)
		(end 18.796 -17.018)
		(width 0.508)
		(layer "In5.Cu")
		(net "P3V3_STBY_B")
	)
	(segment
		(start 481.5078 -11.43)
		(end 480.3902 -12.5476)
		(width 0.508)
		(layer "In5.Cu")
		(net "P3V3_STBY_B")
	)
	(segment
		(start 469.265 -126.619)
		(end 470.662 -128.016)
		(width 0.508)
		(layer "In5.Cu")
		(net "P3V3_STBY_B")
	)
	(segment
		(start 363.763814 -11.338814)
		(end 353.730814 -11.338814)
		(width 0.508)
		(layer "In5.Cu")
		(net "P3V3_STBY_B")
	)
	(segment
		(start 420.243 -252.476)
		(end 414.401 -252.476)
		(width 0.508)
		(layer "In5.Cu")
		(net "P3V3_STBY_B")
	)
	(segment
		(start 47.984918 -249.7328)
		(end 53.6702 -249.7328)
		(width 0.508)
		(layer "In5.Cu")
		(net "P3V3_STBY_B")
	)
	(segment
		(start 87.4268 -248.4628)
		(end 83.6422 -248.4628)
		(width 0.508)
		(layer "In5.Cu")
		(net "P3V3_STBY_B")
	)
	(segment
		(start 125.857 -127.127)
		(end 120.610376 -132.373624)
		(width 0.508)
		(layer "In5.Cu")
		(net "P3V3_STBY_B")
	)
	(segment
		(start 471.3732 -243.7892)
		(end 470.662 -243.078)
		(width 0.508)
		(layer "In5.Cu")
		(net "P3V3_STBY_B")
	)
	(segment
		(start 89.043002 -17.6022)
		(end 94.834202 -11.811)
		(width 0.508)
		(layer "In5.Cu")
		(net "P3V3_STBY_B")
	)
	(segment
		(start 364.744 -242.316)
		(end 361.188 -245.872)
		(width 0.508)
		(layer "In5.Cu")
		(net "P3V3_STBY_B")
	)
	(segment
		(start 461.0354 -15.232126)
		(end 460.163926 -16.1036)
		(width 0.508)
		(layer "In5.Cu")
		(net "P3V3_STBY_B")
	)
	(segment
		(start 115.189 -20.447)
		(end 117.856 -20.447)
		(width 0.508)
		(layer "In5.Cu")
		(net "P3V3_STBY_B")
	)
	(segment
		(start 209.92338 -248.92762)
		(end 209.92338 -249.29338)
		(width 0.508)
		(layer "In5.Cu")
		(net "P3V3_STBY_B")
	)
	(segment
		(start 88.265 -133.4008)
		(end 87.4014 -133.4008)
		(width 0.508)
		(layer "In5.Cu")
		(net "P3V3_STBY_B")
	)
	(segment
		(start 149.6441 -17.653)
		(end 152.146 -17.653)
		(width 0.508)
		(layer "In5.Cu")
		(net "P3V3_STBY_B")
	)
	(segment
		(start 430.911 -12.319)
		(end 427.863 -12.319)
		(width 0.508)
		(layer "In5.Cu")
		(net "P3V3_STBY_B")
	)
	(segment
		(start 191.8462 -252.095)
		(end 191.8208 -252.0696)
		(width 0.508)
		(layer "In5.Cu")
		(net "P3V3_STBY_B")
	)
	(segment
		(start 47.4472 -127.508)
		(end 53.3654 -133.4262)
		(width 0.508)
		(layer "In5.Cu")
		(net "P3V3_STBY_B")
	)
	(segment
		(start 144.907 -251.079)
		(end 129.43586 -251.079)
		(width 0.508)
		(layer "In5.Cu")
		(net "P3V3_STBY_B")
	)
	(segment
		(start 367.793524 -244.602)
		(end 365.507524 -242.316)
		(width 0.508)
		(layer "In5.Cu")
		(net "P3V3_STBY_B")
	)
	(segment
		(start 56.642 -133.096)
		(end 63.373 -126.365)
		(width 0.508)
		(layer "In5.Cu")
		(net "P3V3_STBY_B")
	)
	(segment
		(start 91.7448 -248.4628)
		(end 87.4268 -248.4628)
		(width 0.508)
		(layer "In5.Cu")
		(net "P3V3_STBY_B")
	)
	(segment
		(start 80.6704 -11.7475)
		(end 86.5251 -17.6022)
		(width 0.508)
		(layer "In5.Cu")
		(net "P3V3_STBY_B")
	)
	(segment
		(start 467.9696 -7.493)
		(end 467.6394 -7.1628)
		(width 0.508)
		(layer "In5.Cu")
		(net "P3V3_STBY_B")
	)
	(segment
		(start 460.121 -126.619)
		(end 469.265 -126.619)
		(width 0.508)
		(layer "In5.Cu")
		(net "P3V3_STBY_B")
	)
	(segment
		(start 59.0804 -248.4374)
		(end 55.88 -248.4374)
		(width 0.508)
		(layer "In5.Cu")
		(net "P3V3_STBY_B")
	)
	(segment
		(start 152.146 -17.653)
		(end 161.590228 -8.208772)
		(width 0.508)
		(layer "In5.Cu")
		(net "P3V3_STBY_B")
	)
	(segment
		(start 340.418928 -244.711728)
		(end 335.643728 -244.711728)
		(width 0.508)
		(layer "In5.Cu")
		(net "P3V3_STBY_B")
	)
	(segment
		(start 392.938 -245.745)
		(end 392.938 -247.777)
		(width 0.508)
		(layer "In5.Cu")
		(net "P3V3_STBY_B")
	)
	(segment
		(start 487.426 -12.954)
		(end 485.902 -11.43)
		(width 0.508)
		(layer "In5.Cu")
		(net "P3V3_STBY_B")
	)
	(segment
		(start 430.276 -244.475)
		(end 428.117 -242.316)
		(width 0.508)
		(layer "In5.Cu")
		(net "P3V3_STBY_B")
	)
	(segment
		(start 63.5635 -11.7475)
		(end 80.6704 -11.7475)
		(width 0.508)
		(layer "In5.Cu")
		(net "P3V3_STBY_B")
	)
	(segment
		(start 128.54686 -251.968)
		(end 127 -251.968)
		(width 0.508)
		(layer "In5.Cu")
		(net "P3V3_STBY_B")
	)
	(segment
		(start 179.664868 -19.11604)
		(end 180.086 -19.537172)
		(width 0.508)
		(layer "In5.Cu")
		(net "P3V3_STBY_B")
	)
	(segment
		(start 54.864 -20.447)
		(end 63.5635 -11.7475)
		(width 0.508)
		(layer "In5.Cu")
		(net "P3V3_STBY_B")
	)
	(segment
		(start 460.1464 -12.3444)
		(end 461.0354 -13.2334)
		(width 0.508)
		(layer "In5.Cu")
		(net "P3V3_STBY_B")
	)
	(segment
		(start 397.764 -242.316)
		(end 396.367 -242.316)
		(width 0.508)
		(layer "In5.Cu")
		(net "P3V3_STBY_B")
	)
	(segment
		(start 423.8625 -248.8565)
		(end 420.243 -252.476)
		(width 0.508)
		(layer "In5.Cu")
		(net "P3V3_STBY_B")
	)
	(segment
		(start 149.105112 -133.4262)
		(end 142.805912 -127.127)
		(width 0.508)
		(layer "In5.Cu")
		(net "P3V3_STBY_B")
	)
	(segment
		(start 365.633 -127.381)
		(end 366.776 -126.238)
		(width 0.508)
		(layer "In5.Cu")
		(net "P3V3_STBY_B")
	)
	(segment
		(start 485.902 -11.43)
		(end 481.5078 -11.43)
		(width 0.508)
		(layer "In5.Cu")
		(net "P3V3_STBY_B")
	)
	(segment
		(start 334.01 -126.619)
		(end 363.982 -126.619)
		(width 0.508)
		(layer "In5.Cu")
		(net "P3V3_STBY_B")
	)
	(segment
		(start 396.367 -242.316)
		(end 392.938 -245.745)
		(width 0.508)
		(layer "In5.Cu")
		(net "P3V3_STBY_B")
	)
	(segment
		(start 83.82 -133.4008)
		(end 87.4014 -133.4008)
		(width 0.508)
		(layer "In5.Cu")
		(net "P3V3_STBY_B")
	)
	(segment
		(start 182.0672 -248.4882)
		(end 179.7304 -248.4882)
		(width 0.508)
		(layer "In5.Cu")
		(net "P3V3_STBY_B")
	)
	(segment
		(start 430.276 -126.492)
		(end 458.47 -126.492)
		(width 0.508)
		(layer "In5.Cu")
		(net "P3V3_STBY_B")
	)
	(segment
		(start 179.538884 -133.4008)
		(end 173.518576 -127.380492)
		(width 0.508)
		(layer "In5.Cu")
		(net "P3V3_STBY_B")
	)
	(segment
		(start 427.863 -242.316)
		(end 423.8625 -246.3165)
		(width 0.508)
		(layer "In5.Cu")
		(net "P3V3_STBY_B")
	)
	(segment
		(start 126.0475 -12.2555)
		(end 143.1925 -12.2555)
		(width 0.508)
		(layer "In5.Cu")
		(net "P3V3_STBY_B")
	)
	(segment
		(start 53.3654 -133.4262)
		(end 55.5498 -133.4262)
		(width 0.508)
		(layer "In5.Cu")
		(net "P3V3_STBY_B")
	)
	(segment
		(start 351.3328 -252.1458)
		(end 347.853 -252.1458)
		(width 0.508)
		(layer "In5.Cu")
		(net "P3V3_STBY_B")
	)
	(segment
		(start 479.6028 -11.7602)
		(end 478.3074 -11.7602)
		(width 0.508)
		(layer "In5.Cu")
		(net "P3V3_STBY_B")
	)
	(segment
		(start 115.076224 -132.373624)
		(end 109.4486 -126.746)
		(width 0.508)
		(layer "In5.Cu")
		(net "P3V3_STBY_B")
	)
	(segment
		(start 20.0152 -18.2372)
		(end 24.3332 -18.2372)
		(width 0.508)
		(layer "In5.Cu")
		(net "P3V3_STBY_B")
	)
	(segment
		(start 26.797 -247.015)
		(end 31.877 -252.095)
		(width 0.508)
		(layer "In5.Cu")
		(net "P3V3_STBY_B")
	)
	(segment
		(start 426.72 -11.176)
		(end 418.465 -11.176)
		(width 0.508)
		(layer "In5.Cu")
		(net "P3V3_STBY_B")
	)
	(segment
		(start 148.59 -17.653)
		(end 149.6441 -17.653)
		(width 0.508)
		(layer "In5.Cu")
		(net "P3V3_STBY_B")
	)
	(segment
		(start 427.863 -12.319)
		(end 426.72 -11.176)
		(width 0.508)
		(layer "In5.Cu")
		(net "P3V3_STBY_B")
	)
	(segment
		(start 76.7842 -126.365)
		(end 83.82 -133.4008)
		(width 0.508)
		(layer "In5.Cu")
		(net "P3V3_STBY_B")
	)
	(segment
		(start 396.367 -127.381)
		(end 397.637 -127.381)
		(width 0.508)
		(layer "In5.Cu")
		(net "P3V3_STBY_B")
	)
	(segment
		(start 151.203406 -133.4262)
		(end 150.495 -133.4262)
		(width 0.508)
		(layer "In5.Cu")
		(net "P3V3_STBY_B")
	)
	(segment
		(start 477.647 -12.4206)
		(end 474.1164 -8.89)
		(width 0.508)
		(layer "In5.Cu")
		(net "P3V3_STBY_B")
	)
	(segment
		(start 143.1925 -12.2555)
		(end 148.59 -17.653)
		(width 0.508)
		(layer "In5.Cu")
		(net "P3V3_STBY_B")
	)
	(segment
		(start 64.008 -252.095)
		(end 62.738 -252.095)
		(width 0.508)
		(layer "In5.Cu")
		(net "P3V3_STBY_B")
	)
	(segment
		(start 62.738 -252.095)
		(end 59.0804 -248.4374)
		(width 0.508)
		(layer "In5.Cu")
		(net "P3V3_STBY_B")
	)
	(segment
		(start 118.059454 -132.373624)
		(end 115.076224 -132.373624)
		(width 0.508)
		(layer "In5.Cu")
		(net "P3V3_STBY_B")
	)
	(segment
		(start 455.7522 -16.1036)
		(end 454.0758 -14.4272)
		(width 0.508)
		(layer "In5.Cu")
		(net "P3V3_STBY_B")
	)
	(segment
		(start 357.5812 -252.1458)
		(end 351.3328 -252.1458)
		(width 0.508)
		(layer "In5.Cu")
		(net "P3V3_STBY_B")
	)
	(segment
		(start 461.3148 -7.1628)
		(end 460.1464 -8.3312)
		(width 0.508)
		(layer "In5.Cu")
		(net "P3V3_STBY_B")
	)
	(segment
		(start 118.9482 -248.412)
		(end 115.0112 -248.412)
		(width 0.508)
		(layer "In5.Cu")
		(net "P3V3_STBY_B")
	)
	(segment
		(start 364.744 -127.381)
		(end 365.633 -127.381)
		(width 0.508)
		(layer "In5.Cu")
		(net "P3V3_STBY_B")
	)
	(segment
		(start 142.805912 -127.127)
		(end 125.857 -127.127)
		(width 0.508)
		(layer "In5.Cu")
		(net "P3V3_STBY_B")
	)
	(segment
		(start 474.1164 -8.89)
		(end 469.3666 -8.89)
		(width 0.508)
		(layer "In5.Cu")
		(net "P3V3_STBY_B")
	)
	(segment
		(start 150.5712 -248.4374)
		(end 147.5486 -248.4374)
		(width 0.508)
		(layer "In5.Cu")
		(net "P3V3_STBY_B")
	)
	(segment
		(start 129.43586 -251.079)
		(end 128.54686 -251.968)
		(width 0.508)
		(layer "In5.Cu")
		(net "P3V3_STBY_B")
	)
	(segment
		(start 211.074 -248.412)
		(end 210.439 -248.412)
		(width 0.508)
		(layer "In5.Cu")
		(net "P3V3_STBY_B")
	)
	(segment
		(start 363.982 -126.619)
		(end 364.744 -127.381)
		(width 0.508)
		(layer "In5.Cu")
		(net "P3V3_STBY_B")
	)
	(segment
		(start 335.643728 -244.711728)
		(end 333.248 -242.316)
		(width 0.508)
		(layer "In5.Cu")
		(net "P3V3_STBY_B")
	)
	(segment
		(start 409.067 -252.476)
		(end 400.685 -244.094)
		(width 0.508)
		(layer "In5.Cu")
		(net "P3V3_STBY_B")
	)
	(segment
		(start 157.249114 -127.380492)
		(end 151.203406 -133.4262)
		(width 0.508)
		(layer "In5.Cu")
		(net "P3V3_STBY_B")
	)
	(segment
		(start 38.525704 -5.468366)
		(end 47.129954 -5.468366)
		(width 0.508)
		(layer "In5.Cu")
		(net "P3V3_STBY_B")
	)
	(segment
		(start 86.5251 -17.6022)
		(end 89.043002 -17.6022)
		(width 0.508)
		(layer "In5.Cu")
		(net "P3V3_STBY_B")
	)
	(segment
		(start 467.6394 -7.1628)
		(end 461.3148 -7.1628)
		(width 0.508)
		(layer "In5.Cu")
		(net "P3V3_STBY_B")
	)
	(segment
		(start 446.024 -252.349)
		(end 440.436 -252.349)
		(width 0.508)
		(layer "In5.Cu")
		(net "P3V3_STBY_B")
	)
	(segment
		(start 395.605 -8.89)
		(end 394.462 -7.747)
		(width 0.508)
		(layer "In5.Cu")
		(net "P3V3_STBY_B")
	)
	(segment
		(start 106.553 -11.811)
		(end 115.189 -20.447)
		(width 0.508)
		(layer "In5.Cu")
		(net "P3V3_STBY_B")
	)
	(segment
		(start 377.571 -252.222)
		(end 369.951 -244.602)
		(width 0.508)
		(layer "In5.Cu")
		(net "P3V3_STBY_B")
	)
	(segment
		(start 478.3074 -11.7602)
		(end 477.647 -12.4206)
		(width 0.508)
		(layer "In5.Cu")
		(net "P3V3_STBY_B")
	)
	(segment
		(start 24.257 -247.015)
		(end 26.797 -247.015)
		(width 0.508)
		(layer "In5.Cu")
		(net "P3V3_STBY_B")
	)
	(segment
		(start 364.744 -12.319)
		(end 363.763814 -11.338814)
		(width 0.508)
		(layer "In5.Cu")
		(net "P3V3_STBY_B")
	)
	(segment
		(start 115.0112 -248.412)
		(end 112.8522 -250.571)
		(width 0.508)
		(layer "In5.Cu")
		(net "P3V3_STBY_B")
	)
	(segment
		(start 189.23 -252.095)
		(end 185.6232 -248.4882)
		(width 0.508)
		(layer "In5.Cu")
		(net "P3V3_STBY_B")
	)
	(segment
		(start 112.8522 -250.571)
		(end 108.204 -250.571)
		(width 0.508)
		(layer "In5.Cu")
		(net "P3V3_STBY_B")
	)
	(segment
		(start 427.863 -127.381)
		(end 429.387 -127.381)
		(width 0.508)
		(layer "In5.Cu")
		(net "P3V3_STBY_B")
	)
	(segment
		(start 475.0308 -249.174)
		(end 471.3732 -245.5164)
		(width 0.508)
		(layer "In5.Cu")
		(net "P3V3_STBY_B")
	)
	(segment
		(start 87.4014 -133.4008)
		(end 87.376 -133.4262)
		(width 0.508)
		(layer "In5.Cu")
		(net "P3V3_STBY_B")
	)
	(segment
		(start 392.938 -247.777)
		(end 388.493 -252.222)
		(width 0.508)
		(layer "In5.Cu")
		(net "P3V3_STBY_B")
	)
	(segment
		(start 461.0354 -13.2334)
		(end 461.0354 -15.232126)
		(width 0.508)
		(layer "In5.Cu")
		(net "P3V3_STBY_B")
	)
	(segment
		(start 207.12176 -252.095)
		(end 191.8462 -252.095)
		(width 0.508)
		(layer "In5.Cu")
		(net "P3V3_STBY_B")
	)
	(segment
		(start 365.507524 -242.316)
		(end 364.744 -242.316)
		(width 0.508)
		(layer "In5.Cu")
		(net "P3V3_STBY_B")
	)
	(segment
		(start 25.75687 -18.2372)
		(end 38.525704 -5.468366)
		(width 0.508)
		(layer "In5.Cu")
		(net "P3V3_STBY_B")
	)
	(segment
		(start 122.268488 -248.412)
		(end 118.9482 -248.412)
		(width 0.508)
		(layer "In5.Cu")
		(net "P3V3_STBY_B")
	)
	(segment
		(start 451.231 -252.349)
		(end 446.024 -252.349)
		(width 0.508)
		(layer "In5.Cu")
		(net "P3V3_STBY_B")
	)
	(segment
		(start 18.796 -17.018)
		(end 20.0152 -18.2372)
		(width 0.508)
		(layer "In5.Cu")
		(net "P3V3_STBY_B")
	)
	(segment
		(start 63.373 -126.365)
		(end 76.7842 -126.365)
		(width 0.508)
		(layer "In5.Cu")
		(net "P3V3_STBY_B")
	)
	(segment
		(start 371.475 -7.747)
		(end 366.903 -12.319)
		(width 0.508)
		(layer "In5.Cu")
		(net "P3V3_STBY_B")
	)
	(segment
		(start 480.3902 -12.5476)
		(end 479.6028 -11.7602)
		(width 0.508)
		(layer "In5.Cu")
		(net "P3V3_STBY_B")
	)
	(segment
		(start 400.685 -244.094)
		(end 399.542 -244.094)
		(width 0.508)
		(layer "In5.Cu")
		(net "P3V3_STBY_B")
	)
	(segment
		(start 471.3732 -245.5164)
		(end 471.3732 -243.7892)
		(width 0.508)
		(layer "In5.Cu")
		(net "P3V3_STBY_B")
	)
	(segment
		(start 328.549 -249.428)
		(end 325.628 -252.349)
		(width 0.508)
		(layer "In5.Cu")
		(net "P3V3_STBY_B")
	)
	(segment
		(start 176.9618 -251.2568)
		(end 172.002196 -251.2568)
		(width 0.508)
		(layer "In5.Cu")
		(net "P3V3_STBY_B")
	)
	(segment
		(start 369.951 -244.602)
		(end 367.793524 -244.602)
		(width 0.508)
		(layer "In5.Cu")
		(net "P3V3_STBY_B")
	)
	(segment
		(start 172.002196 -251.2568)
		(end 171.036996 -252.222)
		(width 0.508)
		(layer "In5.Cu")
		(net "P3V3_STBY_B")
	)
	(segment
		(start 325.628 -252.349)
		(end 320.04 -252.349)
		(width 0.508)
		(layer "In5.Cu")
		(net "P3V3_STBY_B")
	)
	(segment
		(start 434.6448 -8.5852)
		(end 430.911 -12.319)
		(width 0.508)
		(layer "In5.Cu")
		(net "P3V3_STBY_B")
	)
	(segment
		(start 147.5486 -248.4374)
		(end 144.907 -251.079)
		(width 0.508)
		(layer "In5.Cu")
		(net "P3V3_STBY_B")
	)
	(segment
		(start 76.073 -252.095)
		(end 64.008 -252.095)
		(width 0.508)
		(layer "In5.Cu")
		(net "P3V3_STBY_B")
	)
	(segment
		(start 181.9656 -133.4008)
		(end 179.538884 -133.4008)
		(width 0.508)
		(layer "In5.Cu")
		(net "P3V3_STBY_B")
	)
	(segment
		(start 394.462 -7.747)
		(end 371.475 -7.747)
		(width 0.508)
		(layer "In5.Cu")
		(net "P3V3_STBY_B")
	)
	(segment
		(start 158.623 -252.222)
		(end 154.8384 -248.4374)
		(width 0.508)
		(layer "In5.Cu")
		(net "P3V3_STBY_B")
	)
	(segment
		(start 154.8384 -248.4374)
		(end 150.5712 -248.4374)
		(width 0.508)
		(layer "In5.Cu")
		(net "P3V3_STBY_B")
	)
	(segment
		(start 395.224 -126.238)
		(end 396.367 -127.381)
		(width 0.508)
		(layer "In5.Cu")
		(net "P3V3_STBY_B")
	)
	(segment
		(start 432.562 -244.475)
		(end 430.276 -244.475)
		(width 0.508)
		(layer "In5.Cu")
		(net "P3V3_STBY_B")
	)
	(segment
		(start 211.95538 -249.29338)
		(end 211.074 -248.412)
		(width 0.508)
		(layer "In5.Cu")
		(net "P3V3_STBY_B")
	)
	(segment
		(start 440.436 -252.349)
		(end 432.562 -244.475)
		(width 0.508)
		(layer "In5.Cu")
		(net "P3V3_STBY_B")
	)
	(segment
		(start 328.549 -247.015)
		(end 328.549 -249.428)
		(width 0.508)
		(layer "In5.Cu")
		(net "P3V3_STBY_B")
	)
	(segment
		(start 31.877 -252.095)
		(end 45.622718 -252.095)
		(width 0.508)
		(layer "In5.Cu")
		(net "P3V3_STBY_B")
	)
	(segment
		(start 469.9 -242.316)
		(end 459.359 -242.316)
		(width 0.508)
		(layer "In5.Cu")
		(net "P3V3_STBY_B")
	)
	(segment
		(start 397.637 -127.381)
		(end 398.78 -126.238)
		(width 0.508)
		(layer "In5.Cu")
		(net "P3V3_STBY_B")
	)
	(segment
		(start 459.359 -127.381)
		(end 460.121 -126.619)
		(width 0.508)
		(layer "In5.Cu")
		(net "P3V3_STBY_B")
	)
	(segment
		(start 179.664868 -15.04061)
		(end 179.664868 -19.11604)
		(width 0.508)
		(layer "In5.Cu")
		(net "P3V3_STBY_B")
	)
	(segment
		(start 469.3666 -8.89)
		(end 467.9696 -7.493)
		(width 0.508)
		(layer "In5.Cu")
		(net "P3V3_STBY_B")
	)
	(segment
		(start 459.359 -242.316)
		(end 456.692 -244.983)
		(width 0.508)
		(layer "In5.Cu")
		(net "P3V3_STBY_B")
	)
	(segment
		(start 351.282 -8.89)
		(end 332.232 -8.89)
		(width 0.508)
		(layer "In5.Cu")
		(net "P3V3_STBY_B")
	)
	(segment
		(start 451.9676 -8.5852)
		(end 434.6448 -8.5852)
		(width 0.508)
		(layer "In5.Cu")
		(net "P3V3_STBY_B")
	)
	(segment
		(start 117.856 -20.447)
		(end 126.0475 -12.2555)
		(width 0.508)
		(layer "In5.Cu")
		(net "P3V3_STBY_B")
	)
	(segment
		(start 191.8208 -252.0696)
		(end 191.7954 -252.095)
		(width 0.508)
		(layer "In5.Cu")
		(net "P3V3_STBY_B")
	)
	(segment
		(start 361.188 -245.872)
		(end 361.188 -248.539)
		(width 0.508)
		(layer "In5.Cu")
		(net "P3V3_STBY_B")
	)
	(segment
		(start 180.086 -19.537172)
		(end 180.086 -20.193)
		(width 0.508)
		(layer "In5.Cu")
		(net "P3V3_STBY_B")
	)
	(segment
		(start 456.692 -246.888)
		(end 451.231 -252.349)
		(width 0.508)
		(layer "In5.Cu")
		(net "P3V3_STBY_B")
	)
	(segment
		(start 429.387 -127.381)
		(end 430.276 -126.492)
		(width 0.508)
		(layer "In5.Cu")
		(net "P3V3_STBY_B")
	)
	(segment
		(start 173.518576 -127.380492)
		(end 157.249114 -127.380492)
		(width 0.508)
		(layer "In5.Cu")
		(net "P3V3_STBY_B")
	)
	(segment
		(start 30.988 -127.508)
		(end 47.4472 -127.508)
		(width 0.508)
		(layer "In5.Cu")
		(net "P3V3_STBY_B")
	)
	(segment
		(start 24.257 -133.477)
		(end 25.019 -133.477)
		(width 0.508)
		(layer "In5.Cu")
		(net "P3V3_STBY_B")
	)
	(segment
		(start 418.465 -11.176)
		(end 416.179 -8.89)
		(width 0.508)
		(layer "In5.Cu")
		(net "P3V3_STBY_B")
	)
	(segment
		(start 172.83303 -8.208772)
		(end 179.664868 -15.04061)
		(width 0.508)
		(layer "In5.Cu")
		(net "P3V3_STBY_B")
	)
	(segment
		(start 45.622718 -252.095)
		(end 47.984918 -249.7328)
		(width 0.508)
		(layer "In5.Cu")
		(net "P3V3_STBY_B")
	)
	(segment
		(start 25.019 -133.477)
		(end 30.988 -127.508)
		(width 0.508)
		(layer "In5.Cu")
		(net "P3V3_STBY_B")
	)
	(segment
		(start 94.9198 -126.746)
		(end 88.265 -133.4008)
		(width 0.508)
		(layer "In5.Cu")
		(net "P3V3_STBY_B")
	)
	(segment
		(start 80.8736 -251.2314)
		(end 76.9366 -251.2314)
		(width 0.508)
		(layer "In5.Cu")
		(net "P3V3_STBY_B")
	)
	(segment
		(start 94.834202 -11.811)
		(end 106.553 -11.811)
		(width 0.508)
		(layer "In5.Cu")
		(net "P3V3_STBY_B")
	)
	(segment
		(start 106.553 -252.222)
		(end 95.504 -252.222)
		(width 0.508)
		(layer "In5.Cu")
		(net "P3V3_STBY_B")
	)
	(segment
		(start 399.542 -244.094)
		(end 397.764 -242.316)
		(width 0.508)
		(layer "In5.Cu")
		(net "P3V3_STBY_B")
	)
	(segment
		(start 24.3332 -18.2372)
		(end 25.75687 -18.2372)
		(width 0.508)
		(layer "In5.Cu")
		(net "P3V3_STBY_B")
	)
	(segment
		(start 171.036996 -252.222)
		(end 158.623 -252.222)
		(width 0.508)
		(layer "In5.Cu")
		(net "P3V3_STBY_B")
	)
	(segment
		(start 209.92338 -249.29338)
		(end 207.12176 -252.095)
		(width 0.508)
		(layer "In5.Cu")
		(net "P3V3_STBY_B")
	)
	(segment
		(start 210.439 -248.412)
		(end 209.92338 -248.92762)
		(width 0.508)
		(layer "In5.Cu")
		(net "P3V3_STBY_B")
	)
	(segment
		(start 150.495 -133.4262)
		(end 149.105112 -133.4262)
		(width 0.508)
		(layer "In5.Cu")
		(net "P3V3_STBY_B")
	)
	(segment
		(start 361.188 -248.539)
		(end 357.5812 -252.1458)
		(width 0.508)
		(layer "In5.Cu")
		(net "P3V3_STBY_B")
	)
	(segment
		(start 55.88 -133.096)
		(end 56.642 -133.096)
		(width 0.508)
		(layer "In5.Cu")
		(net "P3V3_STBY_B")
	)
	(segment
		(start 125.824488 -251.968)
		(end 122.268488 -248.412)
		(width 0.508)
		(layer "In5.Cu")
		(net "P3V3_STBY_B")
	)
	(segment
		(start 423.8625 -246.3165)
		(end 423.8625 -248.8565)
		(width 0.508)
		(layer "In5.Cu")
		(net "P3V3_STBY_B")
	)
	(segment
		(start 108.204 -250.571)
		(end 106.553 -252.222)
		(width 0.508)
		(layer "In5.Cu")
		(net "P3V3_STBY_B")
	)
	(segment
		(start 456.692 -244.983)
		(end 456.692 -246.888)
		(width 0.508)
		(layer "In5.Cu")
		(net "P3V3_STBY_B")
	)
	(segment
		(start 476.4532 -249.174)
		(end 475.0308 -249.174)
		(width 0.508)
		(layer "In5.Cu")
		(net "P3V3_STBY_B")
	)
	(segment
		(start 213.35238 -249.29338)
		(end 211.95538 -249.29338)
		(width 0.508)
		(layer "In5.Cu")
		(net "P3V3_STBY_B")
	)
	(segment
		(start 161.590228 -8.208772)
		(end 172.83303 -8.208772)
		(width 0.508)
		(layer "In5.Cu")
		(net "P3V3_STBY_B")
	)
	(segment
		(start 454.0758 -14.4272)
		(end 454.0758 -10.6934)
		(width 0.508)
		(layer "In5.Cu")
		(net "P3V3_STBY_B")
	)
	(segment
		(start 460.1464 -8.3312)
		(end 460.1464 -12.3444)
		(width 0.508)
		(layer "In5.Cu")
		(net "P3V3_STBY_B")
	)
	(segment
		(start 398.78 -126.238)
		(end 426.72 -126.238)
		(width 0.508)
		(layer "In5.Cu")
		(net "P3V3_STBY_B")
	)
	(segment
		(start 54.737 -20.447)
		(end 54.864 -20.447)
		(width 0.508)
		(layer "In5.Cu")
		(net "P3V3_STBY_B")
	)
	(segment
		(start 252.386338 -228.981)
		(end 252.344682 -228.939344)
		(width 0.254)
		(layer "F.Cu")
		(net "P3V3_SENSE")
	)
	(segment
		(start 252.344682 -227.720906)
		(end 252.360938 -227.70465)
		(width 0.254)
		(layer "F.Cu")
		(net "P3V3_SENSE")
	)
	(segment
		(start 252.360938 -227.70465)
		(end 252.360938 -227.37191)
		(width 0.254)
		(layer "F.Cu")
		(net "P3V3_SENSE")
	)
	(segment
		(start 252.386338 -229.48011)
		(end 252.386338 -228.981)
		(width 0.254)
		(layer "F.Cu")
		(net "P3V3_SENSE")
	)
	(segment
		(start 252.386338 -227.34651)
		(end 252.386338 -226.362768)
		(width 0.254)
		(layer "F.Cu")
		(net "P3V3_SENSE")
	)
	(segment
		(start 252.344682 -228.939344)
		(end 252.344682 -228.398324)
		(width 0.254)
		(layer "F.Cu")
		(net "P3V3_SENSE")
	)
	(segment
		(start 252.360938 -227.37191)
		(end 252.386338 -227.34651)
		(width 0.254)
		(layer "F.Cu")
		(net "P3V3_SENSE")
	)
	(segment
		(start 253.57709 -226.35591)
		(end 252.393196 -226.35591)
		(width 0.254)
		(layer "F.Cu")
		(net "P3V3_SENSE")
	)
	(segment
		(start 254.74676 -225.18624)
		(end 253.57709 -226.35591)
		(width 0.254)
		(layer "F.Cu")
		(net "P3V3_SENSE")
	)
	(segment
		(start 254.74676 -223.09582)
		(end 254.74676 -225.18624)
		(width 0.254)
		(layer "F.Cu")
		(net "P3V3_SENSE")
	)
	(segment
		(start 252.386338 -226.362768)
		(end 252.393196 -226.35591)
		(width 0.254)
		(layer "F.Cu")
		(net "P3V3_SENSE")
	)
	(segment
		(start 252.344682 -228.398324)
		(end 252.344682 -227.720906)
		(width 0.254)
		(layer "F.Cu")
		(net "P3V3_SENSE")
	)
	(via
		(at 252.344682 -228.398324)
		(size 0.6604)
		(drill 0.3302)
		(layers "F.Cu" "B.Cu")
		(net "P3V3_SENSE")
	)
	(segment
		(start 303.029366 -216.92362)
		(end 308.747414 -222.641668)
		(width 0.254)
		(layer "F.Cu")
		(net "P12V_IN_PGOOD")
	)
	(segment
		(start 282.621228 -173.030642)
		(end 287.488376 -173.030642)
		(width 0.254)
		(layer "F.Cu")
		(net "P12V_IN_PGOOD")
	)
	(segment
		(start 308.747414 -182.350918)
		(end 308.747414 -203.248006)
		(width 0.254)
		(layer "F.Cu")
		(net "P12V_IN_PGOOD")
	)
	(segment
		(start 180.975 -374.8151)
		(end 180.9369 -374.8532)
		(width 0.254)
		(layer "F.Cu")
		(net "P12V_IN_PGOOD")
	)
	(segment
		(start 178.5366 -374.8532)
		(end 180.9369 -374.8532)
		(width 0.254)
		(layer "F.Cu")
		(net "P12V_IN_PGOOD")
	)
	(segment
		(start 308.747414 -222.641668)
		(end 308.747414 -233.316018)
		(width 0.254)
		(layer "F.Cu")
		(net "P12V_IN_PGOOD")
	)
	(segment
		(start 261.620762 -366.940846)
		(end 262.446262 -366.940846)
		(width 0.254)
		(layer "F.Cu")
		(net "P12V_IN_PGOOD")
	)
	(segment
		(start 306.060602 -236.600238)
		(end 296.091102 -236.600238)
		(width 0.254)
		(layer "F.Cu")
		(net "P12V_IN_PGOOD")
	)
	(segment
		(start 306.64531 -180.248814)
		(end 308.747414 -182.350918)
		(width 0.254)
		(layer "F.Cu")
		(net "P12V_IN_PGOOD")
	)
	(segment
		(start 180.4543 -373.3546)
		(end 180.8861 -373.7864)
		(width 0.254)
		(layer "F.Cu")
		(net "P12V_IN_PGOOD")
	)
	(segment
		(start 296.091102 -236.600238)
		(end 285.80334 -246.888)
		(width 0.254)
		(layer "F.Cu")
		(net "P12V_IN_PGOOD")
	)
	(segment
		(start 176.509934 -371.6655)
		(end 176.509934 -372.826534)
		(width 0.254)
		(layer "F.Cu")
		(net "P12V_IN_PGOOD")
	)
	(segment
		(start 308.747414 -203.248006)
		(end 303.029366 -208.966054)
		(width 0.254)
		(layer "F.Cu")
		(net "P12V_IN_PGOOD")
	)
	(segment
		(start 285.80334 -246.888)
		(end 277.771352 -246.888)
		(width 0.254)
		(layer "F.Cu")
		(net "P12V_IN_PGOOD")
	)
	(segment
		(start 300.902116 -174.50562)
		(end 306.64531 -180.248814)
		(width 0.254)
		(layer "F.Cu")
		(net "P12V_IN_PGOOD")
	)
	(segment
		(start 179.9844 -373.3546)
		(end 180.4543 -373.3546)
		(width 0.254)
		(layer "F.Cu")
		(net "P12V_IN_PGOOD")
	)
	(segment
		(start 308.747414 -233.316018)
		(end 308.747668 -233.316272)
		(width 0.254)
		(layer "F.Cu")
		(net "P12V_IN_PGOOD")
	)
	(segment
		(start 287.488376 -173.030642)
		(end 288.963354 -174.50562)
		(width 0.254)
		(layer "F.Cu")
		(net "P12V_IN_PGOOD")
	)
	(segment
		(start 180.975 -373.8753)
		(end 180.975 -374.8151)
		(width 0.254)
		(layer "F.Cu")
		(net "P12V_IN_PGOOD")
	)
	(segment
		(start 288.963354 -174.50562)
		(end 300.902116 -174.50562)
		(width 0.254)
		(layer "F.Cu")
		(net "P12V_IN_PGOOD")
	)
	(segment
		(start 308.747668 -233.913172)
		(end 306.060602 -236.600238)
		(width 0.254)
		(layer "F.Cu")
		(net "P12V_IN_PGOOD")
	)
	(segment
		(start 180.8861 -373.7864)
		(end 180.975 -373.8753)
		(width 0.254)
		(layer "F.Cu")
		(net "P12V_IN_PGOOD")
	)
	(segment
		(start 303.029366 -208.966054)
		(end 303.029366 -216.92362)
		(width 0.254)
		(layer "F.Cu")
		(net "P12V_IN_PGOOD")
	)
	(segment
		(start 176.509934 -372.826534)
		(end 178.5366 -374.8532)
		(width 0.254)
		(layer "F.Cu")
		(net "P12V_IN_PGOOD")
	)
	(segment
		(start 308.747668 -233.316272)
		(end 308.747668 -233.913172)
		(width 0.254)
		(layer "F.Cu")
		(net "P12V_IN_PGOOD")
	)
	(via
		(at 263.669018 -112.239044)
		(size 0.5588)
		(drill 0.3048)
		(layers "F.Cu" "B.Cu")
		(net "P12V_IN_PGOOD")
	)
	(via
		(at 262.446262 -366.940846)
		(size 0.5588)
		(drill 0.3048)
		(layers "F.Cu" "B.Cu")
		(net "P12V_IN_PGOOD")
	)
	(via
		(at 282.621228 -173.030642)
		(size 0.5588)
		(drill 0.3048)
		(layers "F.Cu" "B.Cu")
		(net "P12V_IN_PGOOD")
	)
	(via
		(at 306.64531 -180.248814)
		(size 0.6604)
		(drill 0.3302)
		(layers "F.Cu" "B.Cu")
		(net "P12V_IN_PGOOD")
	)
	(via
		(at 179.9844 -373.3546)
		(size 0.5588)
		(drill 0.3048)
		(layers "F.Cu" "B.Cu")
		(net "P12V_IN_PGOOD")
	)
	(via
		(at 277.771352 -246.888)
		(size 0.5588)
		(drill 0.3048)
		(layers "F.Cu" "B.Cu")
		(net "P12V_IN_PGOOD")
	)
	(segment
		(start 226.200208 -72.900032)
		(end 224.348548 -74.751692)
		(width 0.254)
		(layer "B.Cu")
		(net "P12V_IN_PGOOD")
	)
	(segment
		(start 239.480344 -99.394264)
		(end 246.346472 -99.394264)
		(width 0.254)
		(layer "B.Cu")
		(net "P12V_IN_PGOOD")
	)
	(segment
		(start 226.943412 -86.857332)
		(end 239.480344 -99.394264)
		(width 0.254)
		(layer "B.Cu")
		(net "P12V_IN_PGOOD")
	)
	(segment
		(start 246.346472 -99.394264)
		(end 256.733548 -109.78134)
		(width 0.254)
		(layer "B.Cu")
		(net "P12V_IN_PGOOD")
	)
	(segment
		(start 180.721 -372.618)
		(end 179.9844 -373.3546)
		(width 0.254)
		(layer "B.Cu")
		(net "P12V_IN_PGOOD")
	)
	(segment
		(start 224.348548 -83.41106)
		(end 226.943412 -86.005924)
		(width 0.254)
		(layer "B.Cu")
		(net "P12V_IN_PGOOD")
	)
	(segment
		(start 226.943412 -86.005924)
		(end 226.943412 -86.857332)
		(width 0.254)
		(layer "B.Cu")
		(net "P12V_IN_PGOOD")
	)
	(segment
		(start 261.211314 -109.78134)
		(end 263.669018 -112.239044)
		(width 0.254)
		(layer "B.Cu")
		(net "P12V_IN_PGOOD")
	)
	(segment
		(start 256.733548 -109.78134)
		(end 261.211314 -109.78134)
		(width 0.254)
		(layer "B.Cu")
		(net "P12V_IN_PGOOD")
	)
	(segment
		(start 180.721 -371.7544)
		(end 180.721 -372.618)
		(width 0.254)
		(layer "B.Cu")
		(net "P12V_IN_PGOOD")
	)
	(segment
		(start 224.348548 -74.751692)
		(end 224.348548 -83.41106)
		(width 0.254)
		(layer "B.Cu")
		(net "P12V_IN_PGOOD")
	)
	(segment
		(start 299.285152 -141.66215)
		(end 299.285406 -141.661896)
		(width 0.254)
		(layer "In5.Cu")
		(net "P12V_IN_PGOOD")
	)
	(segment
		(start 265.26236 -260.293866)
		(end 265.26236 -314.367418)
		(width 0.254)
		(layer "In5.Cu")
		(net "P12V_IN_PGOOD")
	)
	(segment
		(start 299.285406 -141.661896)
		(end 299.285406 -141.075664)
		(width 0.254)
		(layer "In5.Cu")
		(net "P12V_IN_PGOOD")
	)
	(segment
		(start 283.790136 -124.726954)
		(end 282.39085 -124.726954)
		(width 0.254)
		(layer "In5.Cu")
		(net "P12V_IN_PGOOD")
	)
	(segment
		(start 273.635216 -330.368656)
		(end 273.635216 -350.29775)
		(width 0.254)
		(layer "In5.Cu")
		(net "P12V_IN_PGOOD")
	)
	(segment
		(start 294.440356 -153.344118)
		(end 299.285152 -148.499322)
		(width 0.254)
		(layer "In5.Cu")
		(net "P12V_IN_PGOOD")
	)
	(segment
		(start 299.285406 -141.075664)
		(end 299.285152 -141.07541)
		(width 0.254)
		(layer "In5.Cu")
		(net "P12V_IN_PGOOD")
	)
	(segment
		(start 299.285152 -140.22197)
		(end 283.790136 -124.726954)
		(width 0.254)
		(layer "In5.Cu")
		(net "P12V_IN_PGOOD")
	)
	(segment
		(start 282.39085 -124.726954)
		(end 279.568402 -121.904506)
		(width 0.254)
		(layer "In5.Cu")
		(net "P12V_IN_PGOOD")
	)
	(segment
		(start 274.7899 -323.894958)
		(end 274.7899 -329.213972)
		(width 0.254)
		(layer "In5.Cu")
		(net "P12V_IN_PGOOD")
	)
	(segment
		(start 266.979146 -364.11535)
		(end 264.15365 -366.940846)
		(width 0.254)
		(layer "In5.Cu")
		(net "P12V_IN_PGOOD")
	)
	(segment
		(start 259.272024 -372.4402)
		(end 262.446262 -369.265962)
		(width 0.254)
		(layer "In5.Cu")
		(net "P12V_IN_PGOOD")
	)
	(segment
		(start 274.7899 -329.213972)
		(end 273.635216 -330.368656)
		(width 0.254)
		(layer "In5.Cu")
		(net "P12V_IN_PGOOD")
	)
	(segment
		(start 265.26236 -314.367418)
		(end 274.7899 -323.894958)
		(width 0.254)
		(layer "In5.Cu")
		(net "P12V_IN_PGOOD")
	)
	(segment
		(start 294.440356 -161.476944)
		(end 294.440356 -153.344118)
		(width 0.254)
		(layer "In5.Cu")
		(net "P12V_IN_PGOOD")
	)
	(segment
		(start 277.771352 -247.784874)
		(end 265.26236 -260.293866)
		(width 0.254)
		(layer "In5.Cu")
		(net "P12V_IN_PGOOD")
	)
	(segment
		(start 273.635216 -350.29775)
		(end 266.979146 -356.95382)
		(width 0.254)
		(layer "In5.Cu")
		(net "P12V_IN_PGOOD")
	)
	(segment
		(start 264.15365 -366.940846)
		(end 262.446262 -366.940846)
		(width 0.254)
		(layer "In5.Cu")
		(net "P12V_IN_PGOOD")
	)
	(segment
		(start 299.285152 -148.499322)
		(end 299.285152 -141.66215)
		(width 0.254)
		(layer "In5.Cu")
		(net "P12V_IN_PGOOD")
	)
	(segment
		(start 279.568402 -121.904506)
		(end 276.514306 -121.904506)
		(width 0.254)
		(layer "In5.Cu")
		(net "P12V_IN_PGOOD")
	)
	(segment
		(start 277.771352 -246.888)
		(end 277.771352 -247.784874)
		(width 0.254)
		(layer "In5.Cu")
		(net "P12V_IN_PGOOD")
	)
	(segment
		(start 299.285152 -141.07541)
		(end 299.285152 -140.22197)
		(width 0.254)
		(layer "In5.Cu")
		(net "P12V_IN_PGOOD")
	)
	(segment
		(start 185.376312 -366.699038)
		(end 202.742038 -366.699038)
		(width 0.254)
		(layer "In5.Cu")
		(net "P12V_IN_PGOOD")
	)
	(segment
		(start 262.446262 -369.265962)
		(end 262.446262 -366.940846)
		(width 0.254)
		(layer "In5.Cu")
		(net "P12V_IN_PGOOD")
	)
	(segment
		(start 181.618636 -370.456714)
		(end 185.376312 -366.699038)
		(width 0.254)
		(layer "In5.Cu")
		(net "P12V_IN_PGOOD")
	)
	(segment
		(start 208.4832 -372.4402)
		(end 259.272024 -372.4402)
		(width 0.254)
		(layer "In5.Cu")
		(net "P12V_IN_PGOOD")
	)
	(segment
		(start 202.742038 -366.699038)
		(end 208.4832 -372.4402)
		(width 0.254)
		(layer "In5.Cu")
		(net "P12V_IN_PGOOD")
	)
	(segment
		(start 266.979146 -356.95382)
		(end 266.979146 -364.11535)
		(width 0.254)
		(layer "In5.Cu")
		(net "P12V_IN_PGOOD")
	)
	(segment
		(start 276.514306 -121.904506)
		(end 266.864846 -112.255046)
		(width 0.254)
		(layer "In5.Cu")
		(net "P12V_IN_PGOOD")
	)
	(segment
		(start 266.864846 -112.255046)
		(end 263.669018 -112.255046)
		(width 0.254)
		(layer "In5.Cu")
		(net "P12V_IN_PGOOD")
	)
	(segment
		(start 179.9844 -373.3546)
		(end 181.618636 -371.720364)
		(width 0.254)
		(layer "In5.Cu")
		(net "P12V_IN_PGOOD")
	)
	(segment
		(start 282.621228 -173.030642)
		(end 282.886658 -173.030642)
		(width 0.254)
		(layer "In5.Cu")
		(net "P12V_IN_PGOOD")
	)
	(segment
		(start 282.886658 -173.030642)
		(end 294.440356 -161.476944)
		(width 0.254)
		(layer "In5.Cu")
		(net "P12V_IN_PGOOD")
	)
	(segment
		(start 181.618636 -371.720364)
		(end 181.618636 -370.456714)
		(width 0.254)
		(layer "In5.Cu")
		(net "P12V_IN_PGOOD")
	)
	(segment
		(start 263.669018 -112.255046)
		(end 263.669018 -112.239044)
		(width 0.254)
		(layer "In5.Cu")
		(net "P12V_IN_PGOOD")
	)
	(segment
		(start 324.732396 -378.1044)
		(end 324.757796 -378.1298)
		(width 0.508)
		(layer "F.Cu")
		(net "P12V_IN")
	)
	(segment
		(start 37.940996 -368.8842)
		(end 38.575996 -368.2492)
		(width 0.508)
		(layer "F.Cu")
		(net "P12V_IN")
	)
	(segment
		(start 462.870804 -376.6566)
		(end 462.870804 -376.3264)
		(width 0.4064)
		(layer "F.Cu")
		(net "P12V_IN")
	)
	(segment
		(start 463.505804 -373.6086)
		(end 463.505804 -373.6594)
		(width 0.508)
		(layer "F.Cu")
		(net "P12V_IN")
	)
	(segment
		(start 210.201764 -372.347236)
		(end 192.108328 -372.347236)
		(width 0.508)
		(layer "F.Cu")
		(net "P12V_IN")
	)
	(segment
		(start 326.954896 -367.157)
		(end 325.722996 -367.157)
		(width 0.508)
		(layer "F.Cu")
		(net "P12V_IN")
	)
	(segment
		(start 241.550952 -363.046772)
		(end 240.13541 -363.046772)
		(width 0.508)
		(layer "F.Cu")
		(net "P12V_IN")
	)
	(segment
		(start 29.901896 -376.0216)
		(end 30.270196 -376.0216)
		(width 0.4572)
		(layer "F.Cu")
		(net "P12V_IN")
	)
	(segment
		(start 30.600396 -376.6312)
		(end 30.600396 -377.19)
		(width 0.4064)
		(layer "F.Cu")
		(net "P12V_IN")
	)
	(segment
		(start 30.600396 -377.19)
		(end 30.336236 -377.45416)
		(width 0.4064)
		(layer "F.Cu")
		(net "P12V_IN")
	)
	(segment
		(start 329.278996 -364.5535)
		(end 329.278996 -363.3978)
		(width 0.508)
		(layer "F.Cu")
		(net "P12V_IN")
	)
	(segment
		(start 423.538904 -371.856)
		(end 422.307004 -371.856)
		(width 0.508)
		(layer "F.Cu")
		(net "P12V_IN")
	)
	(segment
		(start 38.08857 -363.622844)
		(end 38.08857 -363.619542)
		(width 0.508)
		(layer "F.Cu")
		(net "P12V_IN")
	)
	(segment
		(start 131.445 -370.490496)
		(end 130.460496 -370.490496)
		(width 0.508)
		(layer "F.Cu")
		(net "P12V_IN")
	)
	(segment
		(start 329.278996 -368.559588)
		(end 329.460606 -368.377978)
		(width 0.508)
		(layer "F.Cu")
		(net "P12V_IN")
	)
	(segment
		(start 37.940996 -364.5535)
		(end 37.940996 -363.770418)
		(width 0.508)
		(layer "F.Cu")
		(net "P12V_IN")
	)
	(segment
		(start 244.399816 -363.702346)
		(end 244.382544 -363.685074)
		(width 0.508)
		(layer "F.Cu")
		(net "P12V_IN")
	)
	(segment
		(start 459.685644 -374.9548)
		(end 459.848204 -374.9548)
		(width 0.508)
		(layer "F.Cu")
		(net "P12V_IN")
	)
	(segment
		(start 246.175022 -363.702346)
		(end 244.399816 -363.702346)
		(width 0.508)
		(layer "F.Cu")
		(net "P12V_IN")
	)
	(segment
		(start 28.102306 -378.75464)
		(end 26.907236 -378.75464)
		(width 0.4064)
		(layer "F.Cu")
		(net "P12V_IN")
	)
	(segment
		(start 132.969 -369.2017)
		(end 132.969 -369.6716)
		(width 0.508)
		(layer "F.Cu")
		(net "P12V_IN")
	)
	(segment
		(start 30.270196 -376.0216)
		(end 30.600396 -376.3518)
		(width 0.4572)
		(layer "F.Cu")
		(net "P12V_IN")
	)
	(segment
		(start 35.616896 -371.856)
		(end 34.384996 -371.856)
		(width 0.508)
		(layer "F.Cu")
		(net "P12V_IN")
	)
	(segment
		(start 188.336428 -372.423436)
		(end 188.653928 -372.423436)
		(width 0.508)
		(layer "F.Cu")
		(net "P12V_IN")
	)
	(segment
		(start 265.075924 -365.228124)
		(end 265.075924 -367.004346)
		(width 0.508)
		(layer "F.Cu")
		(net "P12V_IN")
	)
	(segment
		(start 462.404714 -377.12269)
		(end 462.870804 -376.6566)
		(width 0.4064)
		(layer "F.Cu")
		(net "P12V_IN")
	)
	(segment
		(start 423.538904 -367.157)
		(end 422.307004 -367.157)
		(width 0.508)
		(layer "F.Cu")
		(net "P12V_IN")
	)
	(segment
		(start 30.600396 -376.3518)
		(end 30.600396 -376.6312)
		(width 0.4572)
		(layer "F.Cu")
		(net "P12V_IN")
	)
	(segment
		(start 320.909696 -377.1646)
		(end 321.328796 -377.1646)
		(width 0.508)
		(layer "F.Cu")
		(net "P12V_IN")
	)
	(segment
		(start 425.863004 -369.2525)
		(end 425.863004 -368.0714)
		(width 0.508)
		(layer "F.Cu")
		(net "P12V_IN")
	)
	(segment
		(start 192.108328 -372.347236)
		(end 191.257428 -372.347236)
		(width 0.508)
		(layer "F.Cu")
		(net "P12V_IN")
	)
	(segment
		(start 30.336236 -377.45416)
		(end 30.152086 -377.45416)
		(width 0.4064)
		(layer "F.Cu")
		(net "P12V_IN")
	)
	(segment
		(start 241.550952 -358.855772)
		(end 240.135156 -358.855772)
		(width 0.508)
		(layer "F.Cu")
		(net "P12V_IN")
	)
	(segment
		(start 321.735196 -377.8758)
		(end 321.735196 -378.4346)
		(width 0.4064)
		(layer "F.Cu")
		(net "P12V_IN")
	)
	(segment
		(start 189.145418 -373.881396)
		(end 189.238128 -373.788686)
		(width 0.4064)
		(layer "F.Cu")
		(net "P12V_IN")
	)
	(segment
		(start 172.847 -375.8565)
		(end 172.847 -376.6312)
		(width 0.508)
		(layer "F.Cu")
		(net "P12V_IN")
	)
	(segment
		(start 318.179196 -380.1872)
		(end 318.392556 -379.97384)
		(width 0.4064)
		(layer "F.Cu")
		(net "P12V_IN")
	)
	(segment
		(start 460.645764 -375.07291)
		(end 460.527654 -374.9548)
		(width 0.4064)
		(layer "F.Cu")
		(net "P12V_IN")
	)
	(segment
		(start 329.278996 -369.2525)
		(end 329.278996 -368.559588)
		(width 0.508)
		(layer "F.Cu")
		(net "P12V_IN")
	)
	(segment
		(start 37.940996 -363.770418)
		(end 38.08857 -363.622844)
		(width 0.508)
		(layer "F.Cu")
		(net "P12V_IN")
	)
	(segment
		(start 460.527654 -374.9548)
		(end 459.848204 -374.9548)
		(width 0.4064)
		(layer "F.Cu")
		(net "P12V_IN")
	)
	(segment
		(start 127.762254 -368.727736)
		(end 127.762254 -369.550188)
		(width 0.508)
		(layer "F.Cu")
		(net "P12V_IN")
	)
	(segment
		(start 265.938 -362.1278)
		(end 265.938 -361.1372)
		(width 0.508)
		(layer "F.Cu")
		(net "P12V_IN")
	)
	(segment
		(start 323.805296 -378.1044)
		(end 324.732396 -378.1044)
		(width 0.508)
		(layer "F.Cu")
		(net "P12V_IN")
	)
	(segment
		(start 219.964 -362.585)
		(end 210.201764 -372.347236)
		(width 0.508)
		(layer "F.Cu")
		(net "P12V_IN")
	)
	(segment
		(start 181.7751 -373.7864)
		(end 182.2958 -373.7864)
		(width 0.508)
		(layer "F.Cu")
		(net "P12V_IN")
	)
	(segment
		(start 189.238128 -373.788686)
		(end 189.238128 -373.007636)
		(width 0.4064)
		(layer "F.Cu")
		(net "P12V_IN")
	)
	(segment
		(start 172.847 -376.6312)
		(end 172.6692 -376.809)
		(width 0.508)
		(layer "F.Cu")
		(net "P12V_IN")
	)
	(segment
		(start 37.940996 -369.2525)
		(end 37.940996 -368.8842)
		(width 0.508)
		(layer "F.Cu")
		(net "P12V_IN")
	)
	(segment
		(start 318.392556 -379.97384)
		(end 319.262506 -379.97384)
		(width 0.4064)
		(layer "F.Cu")
		(net "P12V_IN")
	)
	(segment
		(start 128.8415 -373.507)
		(end 128.016 -373.507)
		(width 0.508)
		(layer "F.Cu")
		(net "P12V_IN")
	)
	(segment
		(start 219.964 -355.092)
		(end 219.964 -362.585)
		(width 0.508)
		(layer "F.Cu")
		(net "P12V_IN")
	)
	(segment
		(start 463.505804 -373.6594)
		(end 463.455004 -373.6086)
		(width 0.508)
		(layer "F.Cu")
		(net "P12V_IN")
	)
	(segment
		(start 321.496436 -378.67336)
		(end 321.312286 -378.67336)
		(width 0.4064)
		(layer "F.Cu")
		(net "P12V_IN")
	)
	(segment
		(start 32.797496 -376.9868)
		(end 33.699196 -376.9868)
		(width 0.508)
		(layer "F.Cu")
		(net "P12V_IN")
	)
	(segment
		(start 35.616896 -367.157)
		(end 34.384996 -367.157)
		(width 0.508)
		(layer "F.Cu")
		(net "P12V_IN")
	)
	(segment
		(start 127.761746 -368.727228)
		(end 127.762254 -368.727736)
		(width 0.508)
		(layer "F.Cu")
		(net "P12V_IN")
	)
	(segment
		(start 265.3538 -359.918)
		(end 264.1346 -359.918)
		(width 0.508)
		(layer "F.Cu")
		(net "P12V_IN")
	)
	(segment
		(start 425.863004 -364.5535)
		(end 425.863004 -363.728)
		(width 0.508)
		(layer "F.Cu")
		(net "P12V_IN")
	)
	(segment
		(start 321.684396 -377.5202)
		(end 321.684396 -377.825)
		(width 0.508)
		(layer "F.Cu")
		(net "P12V_IN")
	)
	(segment
		(start 182.2958 -373.7864)
		(end 182.6006 -374.0912)
		(width 0.508)
		(layer "F.Cu")
		(net "P12V_IN")
	)
	(segment
		(start 321.684396 -377.825)
		(end 321.735196 -377.8758)
		(width 0.4064)
		(layer "F.Cu")
		(net "P12V_IN")
	)
	(segment
		(start 459.149704 -375.49074)
		(end 459.685644 -374.9548)
		(width 0.508)
		(layer "F.Cu")
		(net "P12V_IN")
	)
	(segment
		(start 185.986928 -375.181876)
		(end 187.095638 -375.181876)
		(width 0.4064)
		(layer "F.Cu")
		(net "P12V_IN")
	)
	(segment
		(start 135.9408 -371.1575)
		(end 135.9408 -372.3894)
		(width 0.508)
		(layer "F.Cu")
		(net "P12V_IN")
	)
	(segment
		(start 133.3373 -368.8334)
		(end 132.969 -369.2017)
		(width 0.508)
		(layer "F.Cu")
		(net "P12V_IN")
	)
	(segment
		(start 188.653928 -372.423436)
		(end 189.238128 -373.007636)
		(width 0.508)
		(layer "F.Cu")
		(net "P12V_IN")
	)
	(segment
		(start 321.735196 -378.4346)
		(end 321.496436 -378.67336)
		(width 0.4064)
		(layer "F.Cu")
		(net "P12V_IN")
	)
	(segment
		(start 425.863004 -368.0714)
		(end 425.431204 -367.6396)
		(width 0.508)
		(layer "F.Cu")
		(net "P12V_IN")
	)
	(segment
		(start 326.954896 -371.856)
		(end 325.722996 -371.856)
		(width 0.508)
		(layer "F.Cu")
		(net "P12V_IN")
	)
	(segment
		(start 321.328796 -377.1646)
		(end 321.684396 -377.5202)
		(width 0.508)
		(layer "F.Cu")
		(net "P12V_IN")
	)
	(segment
		(start 461.946244 -377.12269)
		(end 462.404714 -377.12269)
		(width 0.4064)
		(layer "F.Cu")
		(net "P12V_IN")
	)
	(segment
		(start 26.907236 -378.75464)
		(end 26.866596 -378.714)
		(width 0.4064)
		(layer "F.Cu")
		(net "P12V_IN")
	)
	(segment
		(start 463.455004 -373.6086)
		(end 462.604104 -373.6086)
		(width 0.508)
		(layer "F.Cu")
		(net "P12V_IN")
	)
	(via
		(at 340.682072 -336.988658)
		(size 0.6604)
		(drill 0.3302)
		(layers "F.Cu" "B.Cu")
		(net "P12V_IN")
	)
	(via
		(at 34.384996 -367.157)
		(size 0.5588)
		(drill 0.3048)
		(layers "F.Cu" "B.Cu")
		(net "P12V_IN")
	)
	(via
		(at 422.307004 -371.856)
		(size 0.5588)
		(drill 0.3048)
		(layers "F.Cu" "B.Cu")
		(net "P12V_IN")
	)
	(via
		(at 225.1456 -347.4974)
		(size 0.8636)
		(drill 0.508)
		(layers "F.Cu" "B.Cu")
		(net "P12V_IN")
	)
	(via
		(at 244.382544 -363.685074)
		(size 0.5588)
		(drill 0.3048)
		(layers "F.Cu" "B.Cu")
		(net "P12V_IN")
	)
	(via
		(at 229.3874 -343.2048)
		(size 0.8636)
		(drill 0.508)
		(layers "F.Cu" "B.Cu")
		(net "P12V_IN")
	)
	(via
		(at 233.172 -349.504)
		(size 0.8636)
		(drill 0.508)
		(layers "F.Cu" "B.Cu")
		(net "P12V_IN")
	)
	(via
		(at 208.28 -350.266)
		(size 0.8636)
		(drill 0.508)
		(layers "F.Cu" "B.Cu")
		(net "P12V_IN")
	)
	(via
		(at 210.058 -340.868)
		(size 0.8636)
		(drill 0.508)
		(layers "F.Cu" "B.Cu")
		(net "P12V_IN")
	)
	(via
		(at 241.3762 -335.2038)
		(size 0.8636)
		(drill 0.508)
		(layers "F.Cu" "B.Cu")
		(net "P12V_IN")
	)
	(via
		(at 211.836 -342.646)
		(size 0.8636)
		(drill 0.508)
		(layers "F.Cu" "B.Cu")
		(net "P12V_IN")
	)
	(via
		(at 425.863004 -363.728)
		(size 0.5588)
		(drill 0.3048)
		(layers "F.Cu" "B.Cu")
		(net "P12V_IN")
	)
	(via
		(at 329.460606 -368.377978)
		(size 0.5588)
		(drill 0.3048)
		(layers "F.Cu" "B.Cu")
		(net "P12V_IN")
	)
	(via
		(at 273.209258 -95.243142)
		(size 0.7112)
		(drill 0.4064)
		(layers "F.Cu" "B.Cu")
		(net "P12V_IN")
	)
	(via
		(at 47.244 -361.696)
		(size 0.7112)
		(drill 0.4064)
		(layers "F.Cu" "B.Cu")
		(net "P12V_IN")
	)
	(via
		(at 233.3498 -335.2038)
		(size 0.8636)
		(drill 0.508)
		(layers "F.Cu" "B.Cu")
		(net "P12V_IN")
	)
	(via
		(at 231.394 -339.1916)
		(size 0.8636)
		(drill 0.508)
		(layers "F.Cu" "B.Cu")
		(net "P12V_IN")
	)
	(via
		(at 210.058 -334.645)
		(size 0.8636)
		(drill 0.508)
		(layers "F.Cu" "B.Cu")
		(net "P12V_IN")
	)
	(via
		(at 210.058 -331.089)
		(size 0.8636)
		(drill 0.508)
		(layers "F.Cu" "B.Cu")
		(net "P12V_IN")
	)
	(via
		(at 226.1616 -345.1606)
		(size 0.8636)
		(drill 0.508)
		(layers "F.Cu" "B.Cu")
		(net "P12V_IN")
	)
	(via
		(at 135.9408 -372.3894)
		(size 0.5588)
		(drill 0.3048)
		(layers "F.Cu" "B.Cu")
		(net "P12V_IN")
	)
	(via
		(at 210.058 -342.646)
		(size 0.8636)
		(drill 0.508)
		(layers "F.Cu" "B.Cu")
		(net "P12V_IN")
	)
	(via
		(at 208.28 -344.424)
		(size 0.8636)
		(drill 0.508)
		(layers "F.Cu" "B.Cu")
		(net "P12V_IN")
	)
	(via
		(at 237.4138 -341.1982)
		(size 0.8636)
		(drill 0.508)
		(layers "F.Cu" "B.Cu")
		(net "P12V_IN")
	)
	(via
		(at 233.4006 -343.2048)
		(size 0.8636)
		(drill 0.508)
		(layers "F.Cu" "B.Cu")
		(net "P12V_IN")
	)
	(via
		(at 235.4072 -343.2048)
		(size 0.8636)
		(drill 0.508)
		(layers "F.Cu" "B.Cu")
		(net "P12V_IN")
	)
	(via
		(at 237.363 -331.1906)
		(size 0.8636)
		(drill 0.508)
		(layers "F.Cu" "B.Cu")
		(net "P12V_IN")
	)
	(via
		(at 210.058 -353.822)
		(size 0.8636)
		(drill 0.508)
		(layers "F.Cu" "B.Cu")
		(net "P12V_IN")
	)
	(via
		(at 211.836 -340.868)
		(size 0.8636)
		(drill 0.508)
		(layers "F.Cu" "B.Cu")
		(net "P12V_IN")
	)
	(via
		(at 47.244 -363.22)
		(size 0.7112)
		(drill 0.4064)
		(layers "F.Cu" "B.Cu")
		(net "P12V_IN")
	)
	(via
		(at 325.722996 -371.856)
		(size 0.5588)
		(drill 0.3048)
		(layers "F.Cu" "B.Cu")
		(net "P12V_IN")
	)
	(via
		(at 436.810404 -356.2858)
		(size 0.5588)
		(drill 0.3048)
		(layers "F.Cu" "B.Cu")
		(net "P12V_IN")
	)
	(via
		(at 225.5012 -343.1032)
		(size 0.8636)
		(drill 0.508)
		(layers "F.Cu" "B.Cu")
		(net "P12V_IN")
	)
	(via
		(at 231.394 -341.1982)
		(size 0.8636)
		(drill 0.508)
		(layers "F.Cu" "B.Cu")
		(net "P12V_IN")
	)
	(via
		(at 208.28 -353.822)
		(size 0.8636)
		(drill 0.508)
		(layers "F.Cu" "B.Cu")
		(net "P12V_IN")
	)
	(via
		(at 38.08857 -363.619542)
		(size 0.5588)
		(drill 0.3048)
		(layers "F.Cu" "B.Cu")
		(net "P12V_IN")
	)
	(via
		(at 237.4138 -337.185)
		(size 0.8636)
		(drill 0.508)
		(layers "F.Cu" "B.Cu")
		(net "P12V_IN")
	)
	(via
		(at 227.3808 -341.1982)
		(size 0.8636)
		(drill 0.508)
		(layers "F.Cu" "B.Cu")
		(net "P12V_IN")
	)
	(via
		(at 211.836 -350.266)
		(size 0.8636)
		(drill 0.508)
		(layers "F.Cu" "B.Cu")
		(net "P12V_IN")
	)
	(via
		(at 210.058 -332.867)
		(size 0.8636)
		(drill 0.508)
		(layers "F.Cu" "B.Cu")
		(net "P12V_IN")
	)
	(via
		(at 185.986928 -375.181876)
		(size 0.5588)
		(drill 0.3048)
		(layers "F.Cu" "B.Cu")
		(net "P12V_IN")
	)
	(via
		(at 237.363 -335.2038)
		(size 0.8636)
		(drill 0.508)
		(layers "F.Cu" "B.Cu")
		(net "P12V_IN")
	)
	(via
		(at 182.6006 -374.0912)
		(size 0.5588)
		(drill 0.3048)
		(layers "F.Cu" "B.Cu")
		(net "P12V_IN")
	)
	(via
		(at 127.762254 -369.550188)
		(size 0.5588)
		(drill 0.3048)
		(layers "F.Cu" "B.Cu")
		(net "P12V_IN")
	)
	(via
		(at 325.722996 -367.157)
		(size 0.5588)
		(drill 0.3048)
		(layers "F.Cu" "B.Cu")
		(net "P12V_IN")
	)
	(via
		(at 230.0478 -345.2622)
		(size 0.8636)
		(drill 0.508)
		(layers "F.Cu" "B.Cu")
		(net "P12V_IN")
	)
	(via
		(at 439.293 -333.248)
		(size 0.6604)
		(drill 0.3302)
		(layers "F.Cu" "B.Cu")
		(net "P12V_IN")
	)
	(via
		(at 235.3564 -335.2038)
		(size 0.8636)
		(drill 0.508)
		(layers "F.Cu" "B.Cu")
		(net "P12V_IN")
	)
	(via
		(at 462.870804 -376.3264)
		(size 0.5588)
		(drill 0.3048)
		(layers "F.Cu" "B.Cu")
		(net "P12V_IN")
	)
	(via
		(at 225.1456 -349.504)
		(size 0.8636)
		(drill 0.508)
		(layers "F.Cu" "B.Cu")
		(net "P12V_IN")
	)
	(via
		(at 233.4006 -339.1916)
		(size 0.8636)
		(drill 0.508)
		(layers "F.Cu" "B.Cu")
		(net "P12V_IN")
	)
	(via
		(at 422.307004 -367.157)
		(size 0.5588)
		(drill 0.3048)
		(layers "F.Cu" "B.Cu")
		(net "P12V_IN")
	)
	(via
		(at 425.431204 -367.6396)
		(size 0.5588)
		(drill 0.3048)
		(layers "F.Cu" "B.Cu")
		(net "P12V_IN")
	)
	(via
		(at 463.505804 -373.6086)
		(size 0.5588)
		(drill 0.3048)
		(layers "F.Cu" "B.Cu")
		(net "P12V_IN")
	)
	(via
		(at 208.28 -334.645)
		(size 0.8636)
		(drill 0.508)
		(layers "F.Cu" "B.Cu")
		(net "P12V_IN")
	)
	(via
		(at 273.260566 -96.74479)
		(size 0.7112)
		(drill 0.4064)
		(layers "F.Cu" "B.Cu")
		(net "P12V_IN")
	)
	(via
		(at 211.836 -334.645)
		(size 0.8636)
		(drill 0.508)
		(layers "F.Cu" "B.Cu")
		(net "P12V_IN")
	)
	(via
		(at 240.135156 -358.855772)
		(size 0.5588)
		(drill 0.3048)
		(layers "F.Cu" "B.Cu")
		(net "P12V_IN")
	)
	(via
		(at 243.3828 -335.2038)
		(size 0.8636)
		(drill 0.508)
		(layers "F.Cu" "B.Cu")
		(net "P12V_IN")
	)
	(via
		(at 211.836 -352.044)
		(size 0.8636)
		(drill 0.508)
		(layers "F.Cu" "B.Cu")
		(net "P12V_IN")
	)
	(via
		(at 235.4072 -339.1916)
		(size 0.8636)
		(drill 0.508)
		(layers "F.Cu" "B.Cu")
		(net "P12V_IN")
	)
	(via
		(at 189.323218 -314.736988)
		(size 0.6604)
		(drill 0.3302)
		(layers "F.Cu" "B.Cu")
		(net "P12V_IN")
	)
	(via
		(at 172.6692 -376.809)
		(size 0.5588)
		(drill 0.3048)
		(layers "F.Cu" "B.Cu")
		(net "P12V_IN")
	)
	(via
		(at 210.058 -352.044)
		(size 0.8636)
		(drill 0.508)
		(layers "F.Cu" "B.Cu")
		(net "P12V_IN")
	)
	(via
		(at 225.5012 -339.09)
		(size 0.8636)
		(drill 0.508)
		(layers "F.Cu" "B.Cu")
		(net "P12V_IN")
	)
	(via
		(at 231.1654 -347.4974)
		(size 0.8636)
		(drill 0.508)
		(layers "F.Cu" "B.Cu")
		(net "P12V_IN")
	)
	(via
		(at 283.7688 -342.0618)
		(size 0.7112)
		(drill 0.4064)
		(layers "F.Cu" "B.Cu")
		(net "P12V_IN")
	)
	(via
		(at 189.238128 -373.007636)
		(size 0.5588)
		(drill 0.3048)
		(layers "F.Cu" "B.Cu")
		(net "P12V_IN")
	)
	(via
		(at 237.4138 -339.1916)
		(size 0.8636)
		(drill 0.508)
		(layers "F.Cu" "B.Cu")
		(net "P12V_IN")
	)
	(via
		(at 192.108328 -372.347236)
		(size 0.5588)
		(drill 0.3048)
		(layers "F.Cu" "B.Cu")
		(net "P12V_IN")
	)
	(via
		(at 208.28 -331.089)
		(size 0.8636)
		(drill 0.508)
		(layers "F.Cu" "B.Cu")
		(net "P12V_IN")
	)
	(via
		(at 243.3828 -333.1972)
		(size 0.8636)
		(drill 0.508)
		(layers "F.Cu" "B.Cu")
		(net "P12V_IN")
	)
	(via
		(at 227.3808 -343.2048)
		(size 0.8636)
		(drill 0.508)
		(layers "F.Cu" "B.Cu")
		(net "P12V_IN")
	)
	(via
		(at 264.1346 -359.918)
		(size 0.5588)
		(drill 0.3048)
		(layers "F.Cu" "B.Cu")
		(net "P12V_IN")
	)
	(via
		(at 236.0676 -345.2622)
		(size 0.8636)
		(drill 0.508)
		(layers "F.Cu" "B.Cu")
		(net "P12V_IN")
	)
	(via
		(at 229.1588 -347.4974)
		(size 0.8636)
		(drill 0.508)
		(layers "F.Cu" "B.Cu")
		(net "P12V_IN")
	)
	(via
		(at 211.836 -336.423)
		(size 0.8636)
		(drill 0.508)
		(layers "F.Cu" "B.Cu")
		(net "P12V_IN")
	)
	(via
		(at 233.172 -347.4974)
		(size 0.8636)
		(drill 0.508)
		(layers "F.Cu" "B.Cu")
		(net "P12V_IN")
	)
	(via
		(at 321.684396 -377.825)
		(size 0.5588)
		(drill 0.3048)
		(layers "F.Cu" "B.Cu")
		(net "P12V_IN")
	)
	(via
		(at 225.5012 -341.0966)
		(size 0.8636)
		(drill 0.508)
		(layers "F.Cu" "B.Cu")
		(net "P12V_IN")
	)
	(via
		(at 38.608 -349.758)
		(size 0.7112)
		(drill 0.4064)
		(layers "F.Cu" "B.Cu")
		(net "P12V_IN")
	)
	(via
		(at 229.489 -335.1276)
		(size 0.8636)
		(drill 0.508)
		(layers "F.Cu" "B.Cu")
		(net "P12V_IN")
	)
	(via
		(at 210.058 -336.423)
		(size 0.8636)
		(drill 0.508)
		(layers "F.Cu" "B.Cu")
		(net "P12V_IN")
	)
	(via
		(at 62.186566 -315.316362)
		(size 0.6604)
		(drill 0.3302)
		(layers "F.Cu" "B.Cu")
		(net "P12V_IN")
	)
	(via
		(at 26.866596 -378.714)
		(size 0.5588)
		(drill 0.3048)
		(layers "F.Cu" "B.Cu")
		(net "P12V_IN")
	)
	(via
		(at 208.28 -342.646)
		(size 0.8636)
		(drill 0.508)
		(layers "F.Cu" "B.Cu")
		(net "P12V_IN")
	)
	(via
		(at 225.5012 -337.0834)
		(size 0.8636)
		(drill 0.508)
		(layers "F.Cu" "B.Cu")
		(net "P12V_IN")
	)
	(via
		(at 231.1654 -349.504)
		(size 0.8636)
		(drill 0.508)
		(layers "F.Cu" "B.Cu")
		(net "P12V_IN")
	)
	(via
		(at 232.0544 -345.2622)
		(size 0.8636)
		(drill 0.508)
		(layers "F.Cu" "B.Cu")
		(net "P12V_IN")
	)
	(via
		(at 208.28 -346.202)
		(size 0.8636)
		(drill 0.508)
		(layers "F.Cu" "B.Cu")
		(net "P12V_IN")
	)
	(via
		(at 208.28 -352.044)
		(size 0.8636)
		(drill 0.508)
		(layers "F.Cu" "B.Cu")
		(net "P12V_IN")
	)
	(via
		(at 237.4138 -343.2048)
		(size 0.8636)
		(drill 0.508)
		(layers "F.Cu" "B.Cu")
		(net "P12V_IN")
	)
	(via
		(at 30.600396 -376.6312)
		(size 0.5588)
		(drill 0.3048)
		(layers "F.Cu" "B.Cu")
		(net "P12V_IN")
	)
	(via
		(at 243.3828 -331.1906)
		(size 0.8636)
		(drill 0.508)
		(layers "F.Cu" "B.Cu")
		(net "P12V_IN")
	)
	(via
		(at 227.3808 -339.1916)
		(size 0.8636)
		(drill 0.508)
		(layers "F.Cu" "B.Cu")
		(net "P12V_IN")
	)
	(via
		(at 241.3762 -331.1906)
		(size 0.8636)
		(drill 0.508)
		(layers "F.Cu" "B.Cu")
		(net "P12V_IN")
	)
	(via
		(at 265.938 -361.1372)
		(size 0.5588)
		(drill 0.3048)
		(layers "F.Cu" "B.Cu")
		(net "P12V_IN")
	)
	(via
		(at 40.132 -351.282)
		(size 0.7112)
		(drill 0.4064)
		(layers "F.Cu" "B.Cu")
		(net "P12V_IN")
	)
	(via
		(at 210.058 -344.424)
		(size 0.8636)
		(drill 0.508)
		(layers "F.Cu" "B.Cu")
		(net "P12V_IN")
	)
	(via
		(at 459.848204 -374.9548)
		(size 0.5588)
		(drill 0.3048)
		(layers "F.Cu" "B.Cu")
		(net "P12V_IN")
	)
	(via
		(at 34.384996 -371.856)
		(size 0.5588)
		(drill 0.3048)
		(layers "F.Cu" "B.Cu")
		(net "P12V_IN")
	)
	(via
		(at 376.841766 -314.96889)
		(size 0.6604)
		(drill 0.3302)
		(layers "F.Cu" "B.Cu")
		(net "P12V_IN")
	)
	(via
		(at 132.969 -369.6716)
		(size 0.5588)
		(drill 0.3048)
		(layers "F.Cu" "B.Cu")
		(net "P12V_IN")
	)
	(via
		(at 45.72 -361.696)
		(size 0.7112)
		(drill 0.4064)
		(layers "F.Cu" "B.Cu")
		(net "P12V_IN")
	)
	(via
		(at 208.28 -340.868)
		(size 0.8636)
		(drill 0.508)
		(layers "F.Cu" "B.Cu")
		(net "P12V_IN")
	)
	(via
		(at 132.008118 -367.613438)
		(size 0.7112)
		(drill 0.4064)
		(layers "F.Cu" "B.Cu")
		(net "P12V_IN")
	)
	(via
		(at 211.836 -332.867)
		(size 0.8636)
		(drill 0.508)
		(layers "F.Cu" "B.Cu")
		(net "P12V_IN")
	)
	(via
		(at 43.18 -351.282)
		(size 0.7112)
		(drill 0.4064)
		(layers "F.Cu" "B.Cu")
		(net "P12V_IN")
	)
	(via
		(at 41.656 -349.758)
		(size 0.7112)
		(drill 0.4064)
		(layers "F.Cu" "B.Cu")
		(net "P12V_IN")
	)
	(via
		(at 265.075924 -365.228124)
		(size 0.5588)
		(drill 0.3048)
		(layers "F.Cu" "B.Cu")
		(net "P12V_IN")
	)
	(via
		(at 210.058 -346.202)
		(size 0.8636)
		(drill 0.508)
		(layers "F.Cu" "B.Cu")
		(net "P12V_IN")
	)
	(via
		(at 229.3874 -339.1916)
		(size 0.8636)
		(drill 0.508)
		(layers "F.Cu" "B.Cu")
		(net "P12V_IN")
	)
	(via
		(at 329.278996 -363.3978)
		(size 0.5588)
		(drill 0.3048)
		(layers "F.Cu" "B.Cu")
		(net "P12V_IN")
	)
	(via
		(at 208.28 -336.423)
		(size 0.8636)
		(drill 0.508)
		(layers "F.Cu" "B.Cu")
		(net "P12V_IN")
	)
	(via
		(at 318.179196 -380.1872)
		(size 0.5588)
		(drill 0.3048)
		(layers "F.Cu" "B.Cu")
		(net "P12V_IN")
	)
	(via
		(at 41.656 -351.282)
		(size 0.7112)
		(drill 0.4064)
		(layers "F.Cu" "B.Cu")
		(net "P12V_IN")
	)
	(via
		(at 211.836 -344.424)
		(size 0.8636)
		(drill 0.508)
		(layers "F.Cu" "B.Cu")
		(net "P12V_IN")
	)
	(via
		(at 241.3762 -333.1972)
		(size 0.8636)
		(drill 0.508)
		(layers "F.Cu" "B.Cu")
		(net "P12V_IN")
	)
	(via
		(at 229.1588 -349.504)
		(size 0.8636)
		(drill 0.508)
		(layers "F.Cu" "B.Cu")
		(net "P12V_IN")
	)
	(via
		(at 237.363 -333.1972)
		(size 0.8636)
		(drill 0.508)
		(layers "F.Cu" "B.Cu")
		(net "P12V_IN")
	)
	(via
		(at 121.524776 -314.968636)
		(size 0.6604)
		(drill 0.3302)
		(layers "F.Cu" "B.Cu")
		(net "P12V_IN")
	)
	(via
		(at 227.3808 -337.185)
		(size 0.8636)
		(drill 0.508)
		(layers "F.Cu" "B.Cu")
		(net "P12V_IN")
	)
	(via
		(at 128.016 -373.507)
		(size 0.5588)
		(drill 0.3048)
		(layers "F.Cu" "B.Cu")
		(net "P12V_IN")
	)
	(via
		(at 219.964 -355.092)
		(size 0.5588)
		(drill 0.3048)
		(layers "F.Cu" "B.Cu")
		(net "P12V_IN")
	)
	(via
		(at 335.788 -363.3978)
		(size 0.5588)
		(drill 0.3048)
		(layers "F.Cu" "B.Cu")
		(net "P12V_IN")
	)
	(via
		(at 33.699196 -376.9868)
		(size 0.5588)
		(drill 0.3048)
		(layers "F.Cu" "B.Cu")
		(net "P12V_IN")
	)
	(via
		(at 235.3564 -331.1906)
		(size 0.8636)
		(drill 0.508)
		(layers "F.Cu" "B.Cu")
		(net "P12V_IN")
	)
	(via
		(at 231.394 -343.2048)
		(size 0.8636)
		(drill 0.508)
		(layers "F.Cu" "B.Cu")
		(net "P12V_IN")
	)
	(via
		(at 239.3696 -333.1972)
		(size 0.8636)
		(drill 0.508)
		(layers "F.Cu" "B.Cu")
		(net "P12V_IN")
	)
	(via
		(at 227.1522 -347.4974)
		(size 0.8636)
		(drill 0.508)
		(layers "F.Cu" "B.Cu")
		(net "P12V_IN")
	)
	(via
		(at 231.3432 -335.2038)
		(size 0.8636)
		(drill 0.508)
		(layers "F.Cu" "B.Cu")
		(net "P12V_IN")
	)
	(via
		(at 247.734328 -314.852812)
		(size 0.6604)
		(drill 0.3302)
		(layers "F.Cu" "B.Cu")
		(net "P12V_IN")
	)
	(via
		(at 38.575996 -368.2492)
		(size 0.5588)
		(drill 0.3048)
		(layers "F.Cu" "B.Cu")
		(net "P12V_IN")
	)
	(via
		(at 211.836 -331.089)
		(size 0.8636)
		(drill 0.508)
		(layers "F.Cu" "B.Cu")
		(net "P12V_IN")
	)
	(via
		(at 40.132 -349.758)
		(size 0.7112)
		(drill 0.4064)
		(layers "F.Cu" "B.Cu")
		(net "P12V_IN")
	)
	(via
		(at 208.28 -332.867)
		(size 0.8636)
		(drill 0.508)
		(layers "F.Cu" "B.Cu")
		(net "P12V_IN")
	)
	(via
		(at 233.4006 -341.1982)
		(size 0.8636)
		(drill 0.508)
		(layers "F.Cu" "B.Cu")
		(net "P12V_IN")
	)
	(via
		(at 130.534918 -367.613438)
		(size 0.7112)
		(drill 0.4064)
		(layers "F.Cu" "B.Cu")
		(net "P12V_IN")
	)
	(via
		(at 309.506366 -315.548264)
		(size 0.6604)
		(drill 0.3302)
		(layers "F.Cu" "B.Cu")
		(net "P12V_IN")
	)
	(via
		(at 130.460496 -370.490496)
		(size 0.5588)
		(drill 0.3048)
		(layers "F.Cu" "B.Cu")
		(net "P12V_IN")
	)
	(via
		(at 239.3696 -335.2038)
		(size 0.8636)
		(drill 0.508)
		(layers "F.Cu" "B.Cu")
		(net "P12V_IN")
	)
	(via
		(at 45.72 -363.22)
		(size 0.7112)
		(drill 0.4064)
		(layers "F.Cu" "B.Cu")
		(net "P12V_IN")
	)
	(via
		(at 229.3874 -341.1982)
		(size 0.8636)
		(drill 0.508)
		(layers "F.Cu" "B.Cu")
		(net "P12V_IN")
	)
	(via
		(at 238.0742 -345.2622)
		(size 0.8636)
		(drill 0.508)
		(layers "F.Cu" "B.Cu")
		(net "P12V_IN")
	)
	(via
		(at 231.394 -337.185)
		(size 0.8636)
		(drill 0.508)
		(layers "F.Cu" "B.Cu")
		(net "P12V_IN")
	)
	(via
		(at 234.061 -345.2622)
		(size 0.8636)
		(drill 0.508)
		(layers "F.Cu" "B.Cu")
		(net "P12V_IN")
	)
	(via
		(at 229.3874 -337.185)
		(size 0.8636)
		(drill 0.508)
		(layers "F.Cu" "B.Cu")
		(net "P12V_IN")
	)
	(via
		(at 273.340068 -98.257106)
		(size 0.7112)
		(drill 0.4064)
		(layers "F.Cu" "B.Cu")
		(net "P12V_IN")
	)
	(via
		(at 239.3696 -331.1906)
		(size 0.8636)
		(drill 0.508)
		(layers "F.Cu" "B.Cu")
		(net "P12V_IN")
	)
	(via
		(at 235.4072 -341.1982)
		(size 0.8636)
		(drill 0.508)
		(layers "F.Cu" "B.Cu")
		(net "P12V_IN")
	)
	(via
		(at 210.058 -350.266)
		(size 0.8636)
		(drill 0.508)
		(layers "F.Cu" "B.Cu")
		(net "P12V_IN")
	)
	(via
		(at 324.757796 -378.1298)
		(size 0.5588)
		(drill 0.3048)
		(layers "F.Cu" "B.Cu")
		(net "P12V_IN")
	)
	(via
		(at 228.0412 -345.2622)
		(size 0.8636)
		(drill 0.508)
		(layers "F.Cu" "B.Cu")
		(net "P12V_IN")
	)
	(via
		(at 235.3564 -333.1972)
		(size 0.8636)
		(drill 0.508)
		(layers "F.Cu" "B.Cu")
		(net "P12V_IN")
	)
	(via
		(at 129.010918 -367.613438)
		(size 0.7112)
		(drill 0.4064)
		(layers "F.Cu" "B.Cu")
		(net "P12V_IN")
	)
	(via
		(at 43.18 -349.758)
		(size 0.7112)
		(drill 0.4064)
		(layers "F.Cu" "B.Cu")
		(net "P12V_IN")
	)
	(via
		(at 240.13541 -363.046772)
		(size 0.5588)
		(drill 0.3048)
		(layers "F.Cu" "B.Cu")
		(net "P12V_IN")
	)
	(via
		(at 227.1522 -349.504)
		(size 0.8636)
		(drill 0.508)
		(layers "F.Cu" "B.Cu")
		(net "P12V_IN")
	)
	(via
		(at 235.4072 -337.185)
		(size 0.8636)
		(drill 0.508)
		(layers "F.Cu" "B.Cu")
		(net "P12V_IN")
	)
	(via
		(at 233.4006 -337.185)
		(size 0.8636)
		(drill 0.508)
		(layers "F.Cu" "B.Cu")
		(net "P12V_IN")
	)
	(via
		(at 38.608 -351.282)
		(size 0.7112)
		(drill 0.4064)
		(layers "F.Cu" "B.Cu")
		(net "P12V_IN")
	)
	(via
		(at 211.836 -346.202)
		(size 0.8636)
		(drill 0.508)
		(layers "F.Cu" "B.Cu")
		(net "P12V_IN")
	)
	(segment
		(start 264.1346 -359.918)
		(end 264.1727 -359.918)
		(width 1.016)
		(layer "B.Cu")
		(net "P12V_IN")
	)
	(segment
		(start 265.938 -361.1372)
		(end 265.938 -364.366048)
		(width 1.016)
		(layer "B.Cu")
		(net "P12V_IN")
	)
	(segment
		(start 271.30375 -353.467924)
		(end 271.304258 -353.468432)
		(width 1.016)
		(layer "B.Cu")
		(net "P12V_IN")
	)
	(segment
		(start 266.432284 -357.21671)
		(end 270.18107 -353.467924)
		(width 1.016)
		(layer "B.Cu")
		(net "P12V_IN")
	)
	(segment
		(start 270.18107 -353.467924)
		(end 271.30375 -353.467924)
		(width 1.016)
		(layer "B.Cu")
		(net "P12V_IN")
	)
	(segment
		(start 279.18283 -345.921076)
		(end 281.966924 -345.921076)
		(width 1.016)
		(layer "B.Cu")
		(net "P12V_IN")
	)
	(segment
		(start 266.432284 -360.642916)
		(end 266.432284 -357.21671)
		(width 1.016)
		(layer "B.Cu")
		(net "P12V_IN")
	)
	(segment
		(start 271.635474 -353.468432)
		(end 279.18283 -345.921076)
		(width 1.016)
		(layer "B.Cu")
		(net "P12V_IN")
	)
	(segment
		(start 265.3919 -361.1372)
		(end 265.938 -361.1372)
		(width 1.016)
		(layer "B.Cu")
		(net "P12V_IN")
	)
	(segment
		(start 265.938 -364.366048)
		(end 265.075924 -365.228124)
		(width 1.016)
		(layer "B.Cu")
		(net "P12V_IN")
	)
	(segment
		(start 264.1727 -359.918)
		(end 265.3919 -361.1372)
		(width 1.016)
		(layer "B.Cu")
		(net "P12V_IN")
	)
	(segment
		(start 283.7688 -344.1192)
		(end 283.7688 -342.0618)
		(width 1.016)
		(layer "B.Cu")
		(net "P12V_IN")
	)
	(segment
		(start 265.938 -361.1372)
		(end 266.432284 -360.642916)
		(width 1.016)
		(layer "B.Cu")
		(net "P12V_IN")
	)
	(segment
		(start 281.966924 -345.921076)
		(end 283.7688 -344.1192)
		(width 1.016)
		(layer "B.Cu")
		(net "P12V_IN")
	)
	(segment
		(start 271.304258 -353.468432)
		(end 271.635474 -353.468432)
		(width 1.016)
		(layer "B.Cu")
		(net "P12V_IN")
	)
	(segment
		(start 329.278996 -364.186978)
		(end 329.278996 -363.3978)
		(width 1.016)
		(layer "In2.Cu")
		(net "P12V_IN")
	)
	(segment
		(start 182.6006 -374.0912)
		(end 183.509158 -374.0912)
		(width 0.508)
		(layer "In2.Cu")
		(net "P12V_IN")
	)
	(segment
		(start 461.194404 -373.6086)
		(end 463.505804 -373.6086)
		(width 0.508)
		(layer "In2.Cu")
		(net "P12V_IN")
	)
	(segment
		(start 463.505804 -374.8786)
		(end 463.505804 -373.6086)
		(width 0.508)
		(layer "In2.Cu")
		(net "P12V_IN")
	)
	(segment
		(start 459.035404 -374.9548)
		(end 457.282804 -373.2022)
		(width 0.508)
		(layer "In2.Cu")
		(net "P12V_IN")
	)
	(segment
		(start 435.17058 -357.925624)
		(end 431.671476 -357.925624)
		(width 0.508)
		(layer "In2.Cu")
		(net "P12V_IN")
	)
	(segment
		(start 189.238128 -373.007636)
		(end 189.898528 -372.347236)
		(width 0.508)
		(layer "In2.Cu")
		(net "P12V_IN")
	)
	(segment
		(start 187.063888 -375.181876)
		(end 189.238128 -373.007636)
		(width 0.508)
		(layer "In2.Cu")
		(net "P12V_IN")
	)
	(segment
		(start 330.322682 -365.230664)
		(end 329.278996 -364.186978)
		(width 1.016)
		(layer "In2.Cu")
		(net "P12V_IN")
	)
	(segment
		(start 462.870804 -376.3264)
		(end 462.870804 -375.5136)
		(width 0.508)
		(layer "In2.Cu")
		(net "P12V_IN")
	)
	(segment
		(start 425.863004 -367.2078)
		(end 425.431204 -367.6396)
		(width 0.508)
		(layer "In2.Cu")
		(net "P12V_IN")
	)
	(segment
		(start 183.509158 -374.0912)
		(end 184.599834 -375.181876)
		(width 0.508)
		(layer "In2.Cu")
		(net "P12V_IN")
	)
	(segment
		(start 325.722996 -371.856)
		(end 325.722996 -367.157)
		(width 1.016)
		(layer "In2.Cu")
		(net "P12V_IN")
	)
	(segment
		(start 185.986928 -375.181876)
		(end 187.063888 -375.181876)
		(width 0.508)
		(layer "In2.Cu")
		(net "P12V_IN")
	)
	(segment
		(start 425.863004 -363.728)
		(end 425.863004 -367.2078)
		(width 0.508)
		(layer "In2.Cu")
		(net "P12V_IN")
	)
	(segment
		(start 431.671476 -357.925624)
		(end 425.8691 -363.728)
		(width 0.508)
		(layer "In2.Cu")
		(net "P12V_IN")
	)
	(segment
		(start 438.450228 -357.925624)
		(end 436.810404 -356.2858)
		(width 0.508)
		(layer "In2.Cu")
		(net "P12V_IN")
	)
	(segment
		(start 425.8691 -363.728)
		(end 425.863004 -363.728)
		(width 0.508)
		(layer "In2.Cu")
		(net "P12V_IN")
	)
	(segment
		(start 450.921628 -357.925624)
		(end 438.450228 -357.925624)
		(width 0.508)
		(layer "In2.Cu")
		(net "P12V_IN")
	)
	(segment
		(start 462.870804 -375.5136)
		(end 463.505804 -374.8786)
		(width 0.508)
		(layer "In2.Cu")
		(net "P12V_IN")
	)
	(segment
		(start 457.282804 -373.2022)
		(end 455.708004 -373.2022)
		(width 0.508)
		(layer "In2.Cu")
		(net "P12V_IN")
	)
	(segment
		(start 459.848204 -374.9548)
		(end 461.194404 -373.6086)
		(width 0.508)
		(layer "In2.Cu")
		(net "P12V_IN")
	)
	(segment
		(start 453.777604 -373.888)
		(end 453.066404 -373.1768)
		(width 0.508)
		(layer "In2.Cu")
		(net "P12V_IN")
	)
	(segment
		(start 455.708004 -373.2022)
		(end 455.022204 -373.888)
		(width 0.508)
		(layer "In2.Cu")
		(net "P12V_IN")
	)
	(segment
		(start 453.066404 -373.1768)
		(end 453.066404 -360.0704)
		(width 0.508)
		(layer "In2.Cu")
		(net "P12V_IN")
	)
	(segment
		(start 329.460606 -368.377978)
		(end 330.322682 -367.515902)
		(width 1.016)
		(layer "In2.Cu")
		(net "P12V_IN")
	)
	(segment
		(start 189.898528 -372.347236)
		(end 192.108328 -372.347236)
		(width 0.508)
		(layer "In2.Cu")
		(net "P12V_IN")
	)
	(segment
		(start 184.599834 -375.181876)
		(end 185.986928 -375.181876)
		(width 0.508)
		(layer "In2.Cu")
		(net "P12V_IN")
	)
	(segment
		(start 330.322682 -367.515902)
		(end 330.322682 -365.230664)
		(width 1.016)
		(layer "In2.Cu")
		(net "P12V_IN")
	)
	(segment
		(start 455.022204 -373.888)
		(end 453.777604 -373.888)
		(width 0.508)
		(layer "In2.Cu")
		(net "P12V_IN")
	)
	(segment
		(start 436.810404 -356.2858)
		(end 435.17058 -357.925624)
		(width 0.508)
		(layer "In2.Cu")
		(net "P12V_IN")
	)
	(segment
		(start 459.848204 -374.9548)
		(end 459.035404 -374.9548)
		(width 0.508)
		(layer "In2.Cu")
		(net "P12V_IN")
	)
	(segment
		(start 453.066404 -360.0704)
		(end 450.921628 -357.925624)
		(width 0.508)
		(layer "In2.Cu")
		(net "P12V_IN")
	)
	(segment
		(start 422.307004 -367.157)
		(end 422.307004 -371.856)
		(width 0.508)
		(layer "In2.Cu")
		(net "P12V_IN")
	)
	(segment
		(start 240.773712 -363.685074)
		(end 240.13541 -363.046772)
		(width 1.016)
		(layer "In5.Cu")
		(net "P12V_IN")
	)
	(segment
		(start 425.177204 -367.3856)
		(end 422.535604 -367.3856)
		(width 0.508)
		(layer "In5.Cu")
		(net "P12V_IN")
	)
	(segment
		(start 335.788 -363.3978)
		(end 332.7908 -363.3978)
		(width 1.016)
		(layer "In5.Cu")
		(net "P12V_IN")
	)
	(segment
		(start 240.13541 -363.046772)
		(end 240.13541 -358.856026)
		(width 1.016)
		(layer "In5.Cu")
		(net "P12V_IN")
	)
	(segment
		(start 325.722996 -372.8212)
		(end 324.757796 -373.7864)
		(width 1.016)
		(layer "In5.Cu")
		(net "P12V_IN")
	)
	(segment
		(start 234.4674 -356.0572)
		(end 234.4674 -350.7994)
		(width 1.016)
		(layer "In5.Cu")
		(net "P12V_IN")
	)
	(segment
		(start 257.716782 -362.094526)
		(end 245.973092 -362.094526)
		(width 1.016)
		(layer "In5.Cu")
		(net "P12V_IN")
	)
	(segment
		(start 182.6006 -377.30938)
		(end 180.91658 -378.9934)
		(width 0.508)
		(layer "In5.Cu")
		(net "P12V_IN")
	)
	(segment
		(start 319.322196 -380.1872)
		(end 318.179196 -380.1872)
		(width 1.016)
		(layer "In5.Cu")
		(net "P12V_IN")
	)
	(segment
		(start 240.135156 -358.855772)
		(end 237.265972 -358.855772)
		(width 1.016)
		(layer "In5.Cu")
		(net "P12V_IN")
	)
	(segment
		(start 322.903596 -377.825)
		(end 321.684396 -377.825)
		(width 1.016)
		(layer "In5.Cu")
		(net "P12V_IN")
	)
	(segment
		(start 331.851 -362.458)
		(end 330.218796 -362.458)
		(width 1.016)
		(layer "In5.Cu")
		(net "P12V_IN")
	)
	(segment
		(start 245.973092 -362.094526)
		(end 244.382544 -363.685074)
		(width 1.016)
		(layer "In5.Cu")
		(net "P12V_IN")
	)
	(segment
		(start 234.4674 -350.7994)
		(end 233.172 -349.504)
		(width 1.016)
		(layer "In5.Cu")
		(net "P12V_IN")
	)
	(segment
		(start 330.218796 -362.458)
		(end 329.278996 -363.3978)
		(width 1.016)
		(layer "In5.Cu")
		(net "P12V_IN")
	)
	(segment
		(start 325.722996 -367.157)
		(end 328.239628 -367.157)
		(width 1.016)
		(layer "In5.Cu")
		(net "P12V_IN")
	)
	(segment
		(start 182.6006 -374.0912)
		(end 182.6006 -377.30938)
		(width 0.508)
		(layer "In5.Cu")
		(net "P12V_IN")
	)
	(segment
		(start 425.431204 -367.6396)
		(end 425.177204 -367.3856)
		(width 0.508)
		(layer "In5.Cu")
		(net "P12V_IN")
	)
	(segment
		(start 325.722996 -371.856)
		(end 325.722996 -372.8212)
		(width 1.016)
		(layer "In5.Cu")
		(net "P12V_IN")
	)
	(segment
		(start 422.535604 -367.3856)
		(end 422.307004 -367.157)
		(width 0.508)
		(layer "In5.Cu")
		(net "P12V_IN")
	)
	(segment
		(start 180.91658 -378.9934)
		(end 174.8536 -378.9934)
		(width 0.508)
		(layer "In5.Cu")
		(net "P12V_IN")
	)
	(segment
		(start 244.382544 -363.685074)
		(end 240.773712 -363.685074)
		(width 1.016)
		(layer "In5.Cu")
		(net "P12V_IN")
	)
	(segment
		(start 237.265972 -358.855772)
		(end 234.4674 -356.0572)
		(width 1.016)
		(layer "In5.Cu")
		(net "P12V_IN")
	)
	(segment
		(start 324.757796 -373.7864)
		(end 324.757796 -378.1298)
		(width 1.016)
		(layer "In5.Cu")
		(net "P12V_IN")
	)
	(segment
		(start 321.684396 -377.825)
		(end 319.322196 -380.1872)
		(width 1.016)
		(layer "In5.Cu")
		(net "P12V_IN")
	)
	(segment
		(start 332.7908 -363.3978)
		(end 331.851 -362.458)
		(width 1.016)
		(layer "In5.Cu")
		(net "P12V_IN")
	)
	(segment
		(start 174.8536 -378.9934)
		(end 172.6692 -376.809)
		(width 0.508)
		(layer "In5.Cu")
		(net "P12V_IN")
	)
	(segment
		(start 328.239628 -367.157)
		(end 329.460606 -368.377978)
		(width 1.016)
		(layer "In5.Cu")
		(net "P12V_IN")
	)
	(segment
		(start 264.1346 -359.918)
		(end 259.893308 -359.918)
		(width 1.016)
		(layer "In5.Cu")
		(net "P12V_IN")
	)
	(segment
		(start 240.13541 -358.856026)
		(end 240.135156 -358.855772)
		(width 1.016)
		(layer "In5.Cu")
		(net "P12V_IN")
	)
	(segment
		(start 323.208396 -378.1298)
		(end 322.903596 -377.825)
		(width 1.016)
		(layer "In5.Cu")
		(net "P12V_IN")
	)
	(segment
		(start 324.757796 -378.1298)
		(end 323.208396 -378.1298)
		(width 1.016)
		(layer "In5.Cu")
		(net "P12V_IN")
	)
	(segment
		(start 259.893308 -359.918)
		(end 257.716782 -362.094526)
		(width 1.016)
		(layer "In5.Cu")
		(net "P12V_IN")
	)
	(via
		(at 17.526 -267.589)
		(size 0.6604)
		(drill 0.3302)
		(layers "F.Cu" "B.Cu")
		(net "P12V_HDD0")
	)
	(segment
		(start 53.56098 -367.09985)
		(end 55.199788 -367.09985)
		(width 0.508)
		(layer "F.Cu")
		(net "P12V_FAN0")
	)
	(segment
		(start 55.199788 -367.09985)
		(end 55.199788 -368.738658)
		(width 0.508)
		(layer "F.Cu")
		(net "P12V_FAN0")
	)
	(segment
		(start 55.199788 -372.599966)
		(end 56.838596 -372.599966)
		(width 0.508)
		(layer "F.Cu")
		(net "P12V_FAN0")
	)
	(segment
		(start 55.199788 -365.461042)
		(end 55.199788 -367.09985)
		(width 0.508)
		(layer "F.Cu")
		(net "P12V_FAN0")
	)
	(segment
		(start 55.199788 -367.09985)
		(end 56.838596 -367.09985)
		(width 0.508)
		(layer "F.Cu")
		(net "P12V_FAN0")
	)
	(segment
		(start 55.199788 -370.961158)
		(end 55.199788 -372.599966)
		(width 0.508)
		(layer "F.Cu")
		(net "P12V_FAN0")
	)
	(segment
		(start 55.199788 -372.599966)
		(end 55.199788 -374.238774)
		(width 0.508)
		(layer "F.Cu")
		(net "P12V_FAN0")
	)
	(segment
		(start 53.56098 -372.599966)
		(end 55.199788 -372.599966)
		(width 0.508)
		(layer "F.Cu")
		(net "P12V_FAN0")
	)
	(via
		(at 55.469536 -358.521)
		(size 0.6604)
		(drill 0.3302)
		(layers "F.Cu" "B.Cu")
		(net "P12V_FAN0")
	)
	(segment
		(start 162.12566 -362.132626)
		(end 162.044634 -362.0516)
		(width 0.508)
		(layer "F.Cu")
		(net "P12V_CLIP")
	)
	(segment
		(start 105.156 -357.632)
		(end 103.0605 -357.632)
		(width 0.508)
		(layer "F.Cu")
		(net "P12V_CLIP")
	)
	(segment
		(start 184.928764 -368.046)
		(end 184.7215 -368.046)
		(width 0.508)
		(layer "F.Cu")
		(net "P12V_CLIP")
	)
	(segment
		(start 105.2322 -357.5558)
		(end 105.156 -357.632)
		(width 0.508)
		(layer "F.Cu")
		(net "P12V_CLIP")
	)
	(segment
		(start 163.43503 -362.132626)
		(end 162.12566 -362.132626)
		(width 0.508)
		(layer "F.Cu")
		(net "P12V_CLIP")
	)
	(segment
		(start 168.0845 -366.776)
		(end 167.132 -366.776)
		(width 0.508)
		(layer "F.Cu")
		(net "P12V_CLIP")
	)
	(segment
		(start 185.506614 -367.46815)
		(end 184.928764 -368.046)
		(width 0.508)
		(layer "F.Cu")
		(net "P12V_CLIP")
	)
	(segment
		(start 163.46043 -366.120426)
		(end 162.044888 -366.120426)
		(width 0.508)
		(layer "F.Cu")
		(net "P12V_CLIP")
	)
	(via
		(at 149.7838 -347.6244)
		(size 0.8636)
		(drill 0.508)
		(layers "F.Cu" "B.Cu")
		(net "P12V_CLIP")
	)
	(via
		(at 132.588 -346.57919)
		(size 0.8636)
		(drill 0.508)
		(layers "F.Cu" "B.Cu")
		(net "P12V_CLIP")
	)
	(via
		(at 132.588 -344.03919)
		(size 0.8636)
		(drill 0.508)
		(layers "F.Cu" "B.Cu")
		(net "P12V_CLIP")
	)
	(via
		(at 157.8102 -337.5914)
		(size 0.8636)
		(drill 0.508)
		(layers "F.Cu" "B.Cu")
		(net "P12V_CLIP")
	)
	(via
		(at 153.797 -357.6574)
		(size 0.8636)
		(drill 0.508)
		(layers "F.Cu" "B.Cu")
		(net "P12V_CLIP")
	)
	(via
		(at 126.492 -338.57819)
		(size 0.8636)
		(drill 0.508)
		(layers "F.Cu" "B.Cu")
		(net "P12V_CLIP")
	)
	(via
		(at 151.7904 -349.631)
		(size 0.8636)
		(drill 0.508)
		(layers "F.Cu" "B.Cu")
		(net "P12V_CLIP")
	)
	(via
		(at 111.252 -348.73819)
		(size 0.8636)
		(drill 0.508)
		(layers "F.Cu" "B.Cu")
		(net "P12V_CLIP")
	)
	(via
		(at 151.7904 -339.598)
		(size 0.8636)
		(drill 0.508)
		(layers "F.Cu" "B.Cu")
		(net "P12V_CLIP")
	)
	(via
		(at 108.204 -346.19819)
		(size 0.8636)
		(drill 0.508)
		(layers "F.Cu" "B.Cu")
		(net "P12V_CLIP")
	)
	(via
		(at 155.8036 -349.631)
		(size 0.8636)
		(drill 0.508)
		(layers "F.Cu" "B.Cu")
		(net "P12V_CLIP")
	)
	(via
		(at 108.204 -348.73819)
		(size 0.8636)
		(drill 0.508)
		(layers "F.Cu" "B.Cu")
		(net "P12V_CLIP")
	)
	(via
		(at 123.444 -346.19819)
		(size 0.8636)
		(drill 0.508)
		(layers "F.Cu" "B.Cu")
		(net "P12V_CLIP")
	)
	(via
		(at 117.348 -346.19819)
		(size 0.8636)
		(drill 0.508)
		(layers "F.Cu" "B.Cu")
		(net "P12V_CLIP")
	)
	(via
		(at 151.0792 -333.629)
		(size 0.8636)
		(drill 0.508)
		(layers "F.Cu" "B.Cu")
		(net "P12V_CLIP")
	)
	(via
		(at 108.204 -351.27819)
		(size 0.8636)
		(drill 0.508)
		(layers "F.Cu" "B.Cu")
		(net "P12V_CLIP")
	)
	(via
		(at 151.7904 -347.6244)
		(size 0.8636)
		(drill 0.508)
		(layers "F.Cu" "B.Cu")
		(net "P12V_CLIP")
	)
	(via
		(at 155.8036 -341.6046)
		(size 0.8636)
		(drill 0.508)
		(layers "F.Cu" "B.Cu")
		(net "P12V_CLIP")
	)
	(via
		(at 153.0858 -331.6224)
		(size 0.8636)
		(drill 0.508)
		(layers "F.Cu" "B.Cu")
		(net "P12V_CLIP")
	)
	(via
		(at 153.797 -343.6112)
		(size 0.8636)
		(drill 0.508)
		(layers "F.Cu" "B.Cu")
		(net "P12V_CLIP")
	)
	(via
		(at 157.8102 -343.6112)
		(size 0.8636)
		(drill 0.508)
		(layers "F.Cu" "B.Cu")
		(net "P12V_CLIP")
	)
	(via
		(at 120.396 -348.73819)
		(size 0.8636)
		(drill 0.508)
		(layers "F.Cu" "B.Cu")
		(net "P12V_CLIP")
	)
	(via
		(at 157.8102 -341.6046)
		(size 0.8636)
		(drill 0.508)
		(layers "F.Cu" "B.Cu")
		(net "P12V_CLIP")
	)
	(via
		(at 153.797 -341.6046)
		(size 0.8636)
		(drill 0.508)
		(layers "F.Cu" "B.Cu")
		(net "P12V_CLIP")
	)
	(via
		(at 149.7838 -353.6442)
		(size 0.8636)
		(drill 0.508)
		(layers "F.Cu" "B.Cu")
		(net "P12V_CLIP")
	)
	(via
		(at 149.7838 -339.598)
		(size 0.8636)
		(drill 0.508)
		(layers "F.Cu" "B.Cu")
		(net "P12V_CLIP")
	)
	(via
		(at 155.8036 -351.6376)
		(size 0.8636)
		(drill 0.508)
		(layers "F.Cu" "B.Cu")
		(net "P12V_CLIP")
	)
	(via
		(at 126.492 -343.65819)
		(size 0.8636)
		(drill 0.508)
		(layers "F.Cu" "B.Cu")
		(net "P12V_CLIP")
	)
	(via
		(at 159.8168 -337.5914)
		(size 0.8636)
		(drill 0.508)
		(layers "F.Cu" "B.Cu")
		(net "P12V_CLIP")
	)
	(via
		(at 151.7904 -343.6112)
		(size 0.8636)
		(drill 0.508)
		(layers "F.Cu" "B.Cu")
		(net "P12V_CLIP")
	)
	(via
		(at 162.044888 -366.120426)
		(size 0.5588)
		(drill 0.3048)
		(layers "F.Cu" "B.Cu")
		(net "P12V_CLIP")
	)
	(via
		(at 108.839 -361.569)
		(size 0.6604)
		(drill 0.3302)
		(layers "F.Cu" "B.Cu")
		(net "P12V_CLIP")
	)
	(via
		(at 147.7772 -351.6376)
		(size 0.8636)
		(drill 0.508)
		(layers "F.Cu" "B.Cu")
		(net "P12V_CLIP")
	)
	(via
		(at 149.7838 -355.6508)
		(size 0.8636)
		(drill 0.508)
		(layers "F.Cu" "B.Cu")
		(net "P12V_CLIP")
	)
	(via
		(at 153.0858 -333.629)
		(size 0.8636)
		(drill 0.508)
		(layers "F.Cu" "B.Cu")
		(net "P12V_CLIP")
	)
	(via
		(at 155.0924 -331.6224)
		(size 0.8636)
		(drill 0.508)
		(layers "F.Cu" "B.Cu")
		(net "P12V_CLIP")
	)
	(via
		(at 123.444 -348.73819)
		(size 0.8636)
		(drill 0.508)
		(layers "F.Cu" "B.Cu")
		(net "P12V_CLIP")
	)
	(via
		(at 167.132 -366.776)
		(size 0.5588)
		(drill 0.3048)
		(layers "F.Cu" "B.Cu")
		(net "P12V_CLIP")
	)
	(via
		(at 147.7772 -345.6178)
		(size 0.8636)
		(drill 0.508)
		(layers "F.Cu" "B.Cu")
		(net "P12V_CLIP")
	)
	(via
		(at 126.492 -351.27819)
		(size 0.8636)
		(drill 0.508)
		(layers "F.Cu" "B.Cu")
		(net "P12V_CLIP")
	)
	(via
		(at 149.7838 -337.5914)
		(size 0.8636)
		(drill 0.508)
		(layers "F.Cu" "B.Cu")
		(net "P12V_CLIP")
	)
	(via
		(at 151.7904 -355.6508)
		(size 0.8636)
		(drill 0.508)
		(layers "F.Cu" "B.Cu")
		(net "P12V_CLIP")
	)
	(via
		(at 185.506614 -367.46815)
		(size 0.5588)
		(drill 0.3048)
		(layers "F.Cu" "B.Cu")
		(net "P12V_CLIP")
	)
	(via
		(at 129.54 -346.57919)
		(size 0.8636)
		(drill 0.508)
		(layers "F.Cu" "B.Cu")
		(net "P12V_CLIP")
	)
	(via
		(at 159.8168 -347.6244)
		(size 0.8636)
		(drill 0.508)
		(layers "F.Cu" "B.Cu")
		(net "P12V_CLIP")
	)
	(via
		(at 155.8036 -357.6574)
		(size 0.8636)
		(drill 0.508)
		(layers "F.Cu" "B.Cu")
		(net "P12V_CLIP")
	)
	(via
		(at 155.8036 -353.6442)
		(size 0.8636)
		(drill 0.508)
		(layers "F.Cu" "B.Cu")
		(net "P12V_CLIP")
	)
	(via
		(at 108.839 -363.347)
		(size 0.6604)
		(drill 0.3302)
		(layers "F.Cu" "B.Cu")
		(net "P12V_CLIP")
	)
	(via
		(at 129.54 -349.11919)
		(size 0.8636)
		(drill 0.508)
		(layers "F.Cu" "B.Cu")
		(net "P12V_CLIP")
	)
	(via
		(at 140.589 -357.632)
		(size 0.6604)
		(drill 0.3302)
		(layers "F.Cu" "B.Cu")
		(net "P12V_CLIP")
	)
	(via
		(at 149.7838 -335.5848)
		(size 0.8636)
		(drill 0.508)
		(layers "F.Cu" "B.Cu")
		(net "P12V_CLIP")
	)
	(via
		(at 151.7904 -351.6376)
		(size 0.8636)
		(drill 0.508)
		(layers "F.Cu" "B.Cu")
		(net "P12V_CLIP")
	)
	(via
		(at 153.797 -355.6508)
		(size 0.8636)
		(drill 0.508)
		(layers "F.Cu" "B.Cu")
		(net "P12V_CLIP")
	)
	(via
		(at 147.7772 -343.6112)
		(size 0.8636)
		(drill 0.508)
		(layers "F.Cu" "B.Cu")
		(net "P12V_CLIP")
	)
	(via
		(at 157.8102 -339.598)
		(size 0.8636)
		(drill 0.508)
		(layers "F.Cu" "B.Cu")
		(net "P12V_CLIP")
	)
	(via
		(at 149.7838 -349.631)
		(size 0.8636)
		(drill 0.508)
		(layers "F.Cu" "B.Cu")
		(net "P12V_CLIP")
	)
	(via
		(at 114.3 -351.27819)
		(size 0.8636)
		(drill 0.508)
		(layers "F.Cu" "B.Cu")
		(net "P12V_CLIP")
	)
	(via
		(at 126.492 -341.11819)
		(size 0.8636)
		(drill 0.508)
		(layers "F.Cu" "B.Cu")
		(net "P12V_CLIP")
	)
	(via
		(at 153.797 -337.5914)
		(size 0.8636)
		(drill 0.508)
		(layers "F.Cu" "B.Cu")
		(net "P12V_CLIP")
	)
	(via
		(at 154.178 -328.041)
		(size 0.6604)
		(drill 0.3302)
		(layers "F.Cu" "B.Cu")
		(net "P12V_CLIP")
	)
	(via
		(at 129.54 -341.49919)
		(size 0.8636)
		(drill 0.508)
		(layers "F.Cu" "B.Cu")
		(net "P12V_CLIP")
	)
	(via
		(at 126.492 -346.19819)
		(size 0.8636)
		(drill 0.508)
		(layers "F.Cu" "B.Cu")
		(net "P12V_CLIP")
	)
	(via
		(at 155.8036 -337.5914)
		(size 0.8636)
		(drill 0.508)
		(layers "F.Cu" "B.Cu")
		(net "P12V_CLIP")
	)
	(via
		(at 117.348 -351.27819)
		(size 0.8636)
		(drill 0.508)
		(layers "F.Cu" "B.Cu")
		(net "P12V_CLIP")
	)
	(via
		(at 159.8168 -339.598)
		(size 0.8636)
		(drill 0.508)
		(layers "F.Cu" "B.Cu")
		(net "P12V_CLIP")
	)
	(via
		(at 155.8036 -347.6244)
		(size 0.8636)
		(drill 0.508)
		(layers "F.Cu" "B.Cu")
		(net "P12V_CLIP")
	)
	(via
		(at 155.0924 -329.5904)
		(size 0.8636)
		(drill 0.508)
		(layers "F.Cu" "B.Cu")
		(net "P12V_CLIP")
	)
	(via
		(at 123.444 -351.27819)
		(size 0.8636)
		(drill 0.508)
		(layers "F.Cu" "B.Cu")
		(net "P12V_CLIP")
	)
	(via
		(at 114.3 -346.19819)
		(size 0.8636)
		(drill 0.508)
		(layers "F.Cu" "B.Cu")
		(net "P12V_CLIP")
	)
	(via
		(at 114.3 -348.73819)
		(size 0.8636)
		(drill 0.508)
		(layers "F.Cu" "B.Cu")
		(net "P12V_CLIP")
	)
	(via
		(at 157.8102 -349.631)
		(size 0.8636)
		(drill 0.508)
		(layers "F.Cu" "B.Cu")
		(net "P12V_CLIP")
	)
	(via
		(at 132.588 -349.11919)
		(size 0.8636)
		(drill 0.508)
		(layers "F.Cu" "B.Cu")
		(net "P12V_CLIP")
	)
	(via
		(at 153.797 -345.6178)
		(size 0.8636)
		(drill 0.508)
		(layers "F.Cu" "B.Cu")
		(net "P12V_CLIP")
	)
	(via
		(at 153.797 -339.598)
		(size 0.8636)
		(drill 0.508)
		(layers "F.Cu" "B.Cu")
		(net "P12V_CLIP")
	)
	(via
		(at 111.252 -351.27819)
		(size 0.8636)
		(drill 0.508)
		(layers "F.Cu" "B.Cu")
		(net "P12V_CLIP")
	)
	(via
		(at 159.8168 -345.6178)
		(size 0.8636)
		(drill 0.508)
		(layers "F.Cu" "B.Cu")
		(net "P12V_CLIP")
	)
	(via
		(at 153.0858 -329.5904)
		(size 0.8636)
		(drill 0.508)
		(layers "F.Cu" "B.Cu")
		(net "P12V_CLIP")
	)
	(via
		(at 149.7838 -351.6376)
		(size 0.8636)
		(drill 0.508)
		(layers "F.Cu" "B.Cu")
		(net "P12V_CLIP")
	)
	(via
		(at 149.987 -357.759)
		(size 0.6604)
		(drill 0.3302)
		(layers "F.Cu" "B.Cu")
		(net "P12V_CLIP")
	)
	(via
		(at 126.238 -357.759)
		(size 0.6604)
		(drill 0.3302)
		(layers "F.Cu" "B.Cu")
		(net "P12V_CLIP")
	)
	(via
		(at 105.156 -346.19819)
		(size 0.8636)
		(drill 0.508)
		(layers "F.Cu" "B.Cu")
		(net "P12V_CLIP")
	)
	(via
		(at 159.8168 -349.631)
		(size 0.8636)
		(drill 0.508)
		(layers "F.Cu" "B.Cu")
		(net "P12V_CLIP")
	)
	(via
		(at 155.8036 -339.598)
		(size 0.8636)
		(drill 0.508)
		(layers "F.Cu" "B.Cu")
		(net "P12V_CLIP")
	)
	(via
		(at 155.0924 -333.629)
		(size 0.8636)
		(drill 0.508)
		(layers "F.Cu" "B.Cu")
		(net "P12V_CLIP")
	)
	(via
		(at 151.7904 -345.6178)
		(size 0.8636)
		(drill 0.508)
		(layers "F.Cu" "B.Cu")
		(net "P12V_CLIP")
	)
	(via
		(at 155.8036 -343.6112)
		(size 0.8636)
		(drill 0.508)
		(layers "F.Cu" "B.Cu")
		(net "P12V_CLIP")
	)
	(via
		(at 145.288 -357.632)
		(size 0.6604)
		(drill 0.3302)
		(layers "F.Cu" "B.Cu")
		(net "P12V_CLIP")
	)
	(via
		(at 153.797 -347.6244)
		(size 0.8636)
		(drill 0.508)
		(layers "F.Cu" "B.Cu")
		(net "P12V_CLIP")
	)
	(via
		(at 105.156 -348.73819)
		(size 0.8636)
		(drill 0.508)
		(layers "F.Cu" "B.Cu")
		(net "P12V_CLIP")
	)
	(via
		(at 153.797 -353.6442)
		(size 0.8636)
		(drill 0.508)
		(layers "F.Cu" "B.Cu")
		(net "P12V_CLIP")
	)
	(via
		(at 157.8102 -347.6244)
		(size 0.8636)
		(drill 0.508)
		(layers "F.Cu" "B.Cu")
		(net "P12V_CLIP")
	)
	(via
		(at 147.7772 -339.598)
		(size 0.8636)
		(drill 0.508)
		(layers "F.Cu" "B.Cu")
		(net "P12V_CLIP")
	)
	(via
		(at 120.396 -351.27819)
		(size 0.8636)
		(drill 0.508)
		(layers "F.Cu" "B.Cu")
		(net "P12V_CLIP")
	)
	(via
		(at 105.156 -351.27819)
		(size 0.8636)
		(drill 0.508)
		(layers "F.Cu" "B.Cu")
		(net "P12V_CLIP")
	)
	(via
		(at 149.7838 -343.6112)
		(size 0.8636)
		(drill 0.508)
		(layers "F.Cu" "B.Cu")
		(net "P12V_CLIP")
	)
	(via
		(at 126.492 -348.73819)
		(size 0.8636)
		(drill 0.508)
		(layers "F.Cu" "B.Cu")
		(net "P12V_CLIP")
	)
	(via
		(at 147.7772 -349.631)
		(size 0.8636)
		(drill 0.508)
		(layers "F.Cu" "B.Cu")
		(net "P12V_CLIP")
	)
	(via
		(at 151.7904 -335.5848)
		(size 0.8636)
		(drill 0.508)
		(layers "F.Cu" "B.Cu")
		(net "P12V_CLIP")
	)
	(via
		(at 151.7904 -337.5914)
		(size 0.8636)
		(drill 0.508)
		(layers "F.Cu" "B.Cu")
		(net "P12V_CLIP")
	)
	(via
		(at 132.588 -341.49919)
		(size 0.8636)
		(drill 0.508)
		(layers "F.Cu" "B.Cu")
		(net "P12V_CLIP")
	)
	(via
		(at 155.8036 -345.6178)
		(size 0.8636)
		(drill 0.508)
		(layers "F.Cu" "B.Cu")
		(net "P12V_CLIP")
	)
	(via
		(at 155.8036 -335.5848)
		(size 0.8636)
		(drill 0.508)
		(layers "F.Cu" "B.Cu")
		(net "P12V_CLIP")
	)
	(via
		(at 137.033 -357.632)
		(size 0.6604)
		(drill 0.3302)
		(layers "F.Cu" "B.Cu")
		(net "P12V_CLIP")
	)
	(via
		(at 157.8102 -345.6178)
		(size 0.8636)
		(drill 0.508)
		(layers "F.Cu" "B.Cu")
		(net "P12V_CLIP")
	)
	(via
		(at 155.8036 -355.6508)
		(size 0.8636)
		(drill 0.508)
		(layers "F.Cu" "B.Cu")
		(net "P12V_CLIP")
	)
	(via
		(at 162.044634 -362.0516)
		(size 0.5588)
		(drill 0.3048)
		(layers "F.Cu" "B.Cu")
		(net "P12V_CLIP")
	)
	(via
		(at 147.7772 -337.5914)
		(size 0.8636)
		(drill 0.508)
		(layers "F.Cu" "B.Cu")
		(net "P12V_CLIP")
	)
	(via
		(at 132.588 -351.65919)
		(size 0.8636)
		(drill 0.508)
		(layers "F.Cu" "B.Cu")
		(net "P12V_CLIP")
	)
	(via
		(at 149.7838 -341.6046)
		(size 0.8636)
		(drill 0.508)
		(layers "F.Cu" "B.Cu")
		(net "P12V_CLIP")
	)
	(via
		(at 147.7772 -347.6244)
		(size 0.8636)
		(drill 0.508)
		(layers "F.Cu" "B.Cu")
		(net "P12V_CLIP")
	)
	(via
		(at 111.252 -346.19819)
		(size 0.8636)
		(drill 0.508)
		(layers "F.Cu" "B.Cu")
		(net "P12V_CLIP")
	)
	(via
		(at 117.348 -348.73819)
		(size 0.8636)
		(drill 0.508)
		(layers "F.Cu" "B.Cu")
		(net "P12V_CLIP")
	)
	(via
		(at 159.8168 -341.6046)
		(size 0.8636)
		(drill 0.508)
		(layers "F.Cu" "B.Cu")
		(net "P12V_CLIP")
	)
	(via
		(at 147.7772 -341.6046)
		(size 0.8636)
		(drill 0.508)
		(layers "F.Cu" "B.Cu")
		(net "P12V_CLIP")
	)
	(via
		(at 153.797 -349.631)
		(size 0.8636)
		(drill 0.508)
		(layers "F.Cu" "B.Cu")
		(net "P12V_CLIP")
	)
	(via
		(at 149.7838 -345.6178)
		(size 0.8636)
		(drill 0.508)
		(layers "F.Cu" "B.Cu")
		(net "P12V_CLIP")
	)
	(via
		(at 159.8168 -343.6112)
		(size 0.8636)
		(drill 0.508)
		(layers "F.Cu" "B.Cu")
		(net "P12V_CLIP")
	)
	(via
		(at 151.7904 -341.6046)
		(size 0.8636)
		(drill 0.508)
		(layers "F.Cu" "B.Cu")
		(net "P12V_CLIP")
	)
	(via
		(at 120.396 -346.19819)
		(size 0.8636)
		(drill 0.508)
		(layers "F.Cu" "B.Cu")
		(net "P12V_CLIP")
	)
	(via
		(at 153.797 -335.5848)
		(size 0.8636)
		(drill 0.508)
		(layers "F.Cu" "B.Cu")
		(net "P12V_CLIP")
	)
	(via
		(at 147.7772 -335.5848)
		(size 0.8636)
		(drill 0.508)
		(layers "F.Cu" "B.Cu")
		(net "P12V_CLIP")
	)
	(via
		(at 151.7904 -353.6442)
		(size 0.8636)
		(drill 0.508)
		(layers "F.Cu" "B.Cu")
		(net "P12V_CLIP")
	)
	(via
		(at 129.54 -351.65919)
		(size 0.8636)
		(drill 0.508)
		(layers "F.Cu" "B.Cu")
		(net "P12V_CLIP")
	)
	(via
		(at 153.797 -351.6376)
		(size 0.8636)
		(drill 0.508)
		(layers "F.Cu" "B.Cu")
		(net "P12V_CLIP")
	)
	(via
		(at 129.54 -344.03919)
		(size 0.8636)
		(drill 0.508)
		(layers "F.Cu" "B.Cu")
		(net "P12V_CLIP")
	)
	(via
		(at 147.7772 -353.6442)
		(size 0.8636)
		(drill 0.508)
		(layers "F.Cu" "B.Cu")
		(net "P12V_CLIP")
	)
	(via
		(at 151.7904 -357.6574)
		(size 0.8636)
		(drill 0.508)
		(layers "F.Cu" "B.Cu")
		(net "P12V_CLIP")
	)
	(segment
		(start 182.93715 -367.46815)
		(end 182.245 -366.776)
		(width 0.508)
		(layer "B.Cu")
		(net "P12V_CLIP")
	)
	(segment
		(start 167.132 -366.776)
		(end 162.700462 -366.776)
		(width 0.508)
		(layer "B.Cu")
		(net "P12V_CLIP")
	)
	(segment
		(start 182.245 -366.776)
		(end 167.132 -366.776)
		(width 0.508)
		(layer "B.Cu")
		(net "P12V_CLIP")
	)
	(segment
		(start 162.700462 -366.776)
		(end 162.044888 -366.120426)
		(width 0.508)
		(layer "B.Cu")
		(net "P12V_CLIP")
	)
	(segment
		(start 185.506614 -367.46815)
		(end 182.93715 -367.46815)
		(width 0.508)
		(layer "B.Cu")
		(net "P12V_CLIP")
	)
	(segment
		(start 155.8036 -357.6574)
		(end 155.8036 -360.639868)
		(width 0.508)
		(layer "In5.Cu")
		(net "P12V_CLIP")
	)
	(segment
		(start 162.044888 -366.120426)
		(end 162.044634 -366.120172)
		(width 0.508)
		(layer "In5.Cu")
		(net "P12V_CLIP")
	)
	(segment
		(start 162.044634 -366.120172)
		(end 162.044634 -362.0516)
		(width 0.508)
		(layer "In5.Cu")
		(net "P12V_CLIP")
	)
	(segment
		(start 155.8036 -360.639868)
		(end 157.093158 -361.929426)
		(width 0.508)
		(layer "In5.Cu")
		(net "P12V_CLIP")
	)
	(segment
		(start 157.093158 -361.929426)
		(end 161.92246 -361.929426)
		(width 0.508)
		(layer "In5.Cu")
		(net "P12V_CLIP")
	)
	(segment
		(start 161.92246 -361.929426)
		(end 162.044634 -362.0516)
		(width 0.508)
		(layer "In5.Cu")
		(net "P12V_CLIP")
	)
	(segment
		(start 174.28972 -119.29872)
		(end 124.525278 -119.29872)
		(width 0.254)
		(layer "F.Cu")
		(net "P12V_B_PGOOD")
	)
	(segment
		(start 257.217672 -372.12651)
		(end 257.458972 -371.88521)
		(width 0.254)
		(layer "F.Cu")
		(net "P12V_B_PGOOD")
	)
	(segment
		(start 466.4964 -232.5878)
		(end 467.04885 -232.03535)
		(width 0.254)
		(layer "F.Cu")
		(net "P12V_B_PGOOD")
	)
	(segment
		(start 444.91021 -122.096784)
		(end 444.603886 -121.79046)
		(width 0.254)
		(layer "F.Cu")
		(net "P12V_B_PGOOD")
	)
	(segment
		(start 470.555066 -116.966492)
		(end 462.001108 -116.966492)
		(width 0.254)
		(layer "F.Cu")
		(net "P12V_B_PGOOD")
	)
	(segment
		(start 81.595214 -114.05235)
		(end 75.645518 -120.002046)
		(width 0.254)
		(layer "F.Cu")
		(net "P12V_B_PGOOD")
	)
	(segment
		(start 487.79303 -118.98503)
		(end 472.573604 -118.98503)
		(width 0.254)
		(layer "F.Cu")
		(net "P12V_B_PGOOD")
	)
	(segment
		(start 463.502502 -231.62895)
		(end 464.461352 -232.5878)
		(width 0.254)
		(layer "F.Cu")
		(net "P12V_B_PGOOD")
	)
	(segment
		(start 124.525278 -119.29872)
		(end 119.278908 -114.05235)
		(width 0.254)
		(layer "F.Cu")
		(net "P12V_B_PGOOD")
	)
	(segment
		(start 4.797298 -128.016)
		(end 4.797298 -232.946702)
		(width 0.254)
		(layer "F.Cu")
		(net "P12V_B_PGOOD")
	)
	(segment
		(start 254.600456 -368.591846)
		(end 254.600456 -369.52428)
		(width 0.254)
		(layer "F.Cu")
		(net "P12V_B_PGOOD")
	)
	(segment
		(start 460.7814 -118.1862)
		(end 448.91071 -118.1862)
		(width 0.254)
		(layer "F.Cu")
		(net "P12V_B_PGOOD")
	)
	(segment
		(start 54.304438 -121.476516)
		(end 53.271928 -120.444006)
		(width 0.254)
		(layer "F.Cu")
		(net "P12V_B_PGOOD")
	)
	(segment
		(start 4.797298 -232.946702)
		(end 6.089396 -234.2388)
		(width 0.254)
		(layer "F.Cu")
		(net "P12V_B_PGOOD")
	)
	(segment
		(start 75.645518 -120.002046)
		(end 56.223154 -120.002046)
		(width 0.254)
		(layer "F.Cu")
		(net "P12V_B_PGOOD")
	)
	(segment
		(start 256.77114 -278.384)
		(end 262.02894 -273.1262)
		(width 0.254)
		(layer "F.Cu")
		(net "P12V_B_PGOOD")
	)
	(segment
		(start 467.04885 -232.03535)
		(end 488.5944 -232.03535)
		(width 0.254)
		(layer "F.Cu")
		(net "P12V_B_PGOOD")
	)
	(segment
		(start 56.223154 -120.002046)
		(end 54.748684 -121.476516)
		(width 0.254)
		(layer "F.Cu")
		(net "P12V_B_PGOOD")
	)
	(segment
		(start 119.278908 -114.05235)
		(end 81.595214 -114.05235)
		(width 0.254)
		(layer "F.Cu")
		(net "P12V_B_PGOOD")
	)
	(segment
		(start 51.746658 -122.926856)
		(end 37.050726 -122.926856)
		(width 0.254)
		(layer "F.Cu")
		(net "P12V_B_PGOOD")
	)
	(segment
		(start 472.573604 -118.98503)
		(end 470.555066 -116.966492)
		(width 0.254)
		(layer "F.Cu")
		(net "P12V_B_PGOOD")
	)
	(segment
		(start 27.892502 -233.625898)
		(end 27.892502 -231.62895)
		(width 0.254)
		(layer "F.Cu")
		(net "P12V_B_PGOOD")
	)
	(segment
		(start 256.219706 -278.384)
		(end 256.77114 -278.384)
		(width 0.254)
		(layer "F.Cu")
		(net "P12V_B_PGOOD")
	)
	(segment
		(start 258.474972 -371.88521)
		(end 257.458972 -371.88521)
		(width 0.254)
		(layer "F.Cu")
		(net "P12V_B_PGOOD")
	)
	(segment
		(start 52.74056 -120.444006)
		(end 52.74056 -121.932954)
		(width 0.254)
		(layer "F.Cu")
		(net "P12V_B_PGOOD")
	)
	(segment
		(start 37.050726 -122.926856)
		(end 30.86227 -116.7384)
		(width 0.254)
		(layer "F.Cu")
		(net "P12V_B_PGOOD")
	)
	(segment
		(start 462.001108 -116.966492)
		(end 460.7814 -118.1862)
		(width 0.254)
		(layer "F.Cu")
		(net "P12V_B_PGOOD")
	)
	(segment
		(start 52.74056 -121.932954)
		(end 51.746658 -122.926856)
		(width 0.254)
		(layer "F.Cu")
		(net "P12V_B_PGOOD")
	)
	(segment
		(start 447.121534 -122.096784)
		(end 444.91021 -122.096784)
		(width 0.254)
		(layer "F.Cu")
		(net "P12V_B_PGOOD")
	)
	(segment
		(start 181.5084 -126.5174)
		(end 174.28972 -119.29872)
		(width 0.254)
		(layer "F.Cu")
		(net "P12V_B_PGOOD")
	)
	(segment
		(start 262.02894 -273.1262)
		(end 293.3192 -273.1262)
		(width 0.254)
		(layer "F.Cu")
		(net "P12V_B_PGOOD")
	)
	(segment
		(start 444.603886 -121.79046)
		(end 444.603886 -121.312178)
		(width 0.254)
		(layer "F.Cu")
		(net "P12V_B_PGOOD")
	)
	(segment
		(start 27.2796 -234.2388)
		(end 27.892502 -233.625898)
		(width 0.254)
		(layer "F.Cu")
		(net "P12V_B_PGOOD")
	)
	(segment
		(start 488.2896 -119.4816)
		(end 487.79303 -118.98503)
		(width 0.254)
		(layer "F.Cu")
		(net "P12V_B_PGOOD")
	)
	(segment
		(start 258.474972 -371.05971)
		(end 258.474972 -371.88521)
		(width 0.254)
		(layer "F.Cu")
		(net "P12V_B_PGOOD")
	)
	(segment
		(start 30.86227 -116.7384)
		(end 16.074898 -116.7384)
		(width 0.254)
		(layer "F.Cu")
		(net "P12V_B_PGOOD")
	)
	(segment
		(start 54.748684 -121.476516)
		(end 54.304438 -121.476516)
		(width 0.254)
		(layer "F.Cu")
		(net "P12V_B_PGOOD")
	)
	(segment
		(start 254.600456 -369.52428)
		(end 255.934972 -370.858796)
		(width 0.254)
		(layer "F.Cu")
		(net "P12V_B_PGOOD")
	)
	(segment
		(start 255.934972 -372.12651)
		(end 257.217672 -372.12651)
		(width 0.254)
		(layer "F.Cu")
		(net "P12V_B_PGOOD")
	)
	(segment
		(start 16.074898 -116.7384)
		(end 4.797298 -128.016)
		(width 0.254)
		(layer "F.Cu")
		(net "P12V_B_PGOOD")
	)
	(segment
		(start 464.461352 -232.5878)
		(end 466.4964 -232.5878)
		(width 0.254)
		(layer "F.Cu")
		(net "P12V_B_PGOOD")
	)
	(segment
		(start 447.487294 -119.609616)
		(end 447.487294 -121.731024)
		(width 0.254)
		(layer "F.Cu")
		(net "P12V_B_PGOOD")
	)
	(segment
		(start 448.91071 -118.1862)
		(end 447.487294 -119.609616)
		(width 0.254)
		(layer "F.Cu")
		(net "P12V_B_PGOOD")
	)
	(segment
		(start 447.487294 -121.731024)
		(end 447.121534 -122.096784)
		(width 0.254)
		(layer "F.Cu")
		(net "P12V_B_PGOOD")
	)
	(segment
		(start 6.089396 -234.2388)
		(end 27.2796 -234.2388)
		(width 0.254)
		(layer "F.Cu")
		(net "P12V_B_PGOOD")
	)
	(segment
		(start 255.934972 -370.858796)
		(end 255.934972 -372.12651)
		(width 0.254)
		(layer "F.Cu")
		(net "P12V_B_PGOOD")
	)
	(segment
		(start 293.3192 -273.1262)
		(end 293.5224 -272.923)
		(width 0.254)
		(layer "F.Cu")
		(net "P12V_B_PGOOD")
	)
	(segment
		(start 53.271928 -120.444006)
		(end 52.74056 -120.444006)
		(width 0.254)
		(layer "F.Cu")
		(net "P12V_B_PGOOD")
	)
	(via
		(at 181.5084 -126.5174)
		(size 0.5588)
		(drill 0.3048)
		(layers "F.Cu" "B.Cu")
		(net "P12V_B_PGOOD")
	)
	(via
		(at 214.0458 -272.2626)
		(size 0.5588)
		(drill 0.3048)
		(layers "F.Cu" "B.Cu")
		(net "P12V_B_PGOOD")
	)
	(via
		(at 293.5224 -272.923)
		(size 0.5588)
		(drill 0.3048)
		(layers "F.Cu" "B.Cu")
		(net "P12V_B_PGOOD")
	)
	(via
		(at 273.05762 -336.061812)
		(size 0.5588)
		(drill 0.3048)
		(layers "F.Cu" "B.Cu")
		(net "P12V_B_PGOOD")
	)
	(via
		(at 258.474972 -371.05971)
		(size 0.5588)
		(drill 0.3048)
		(layers "F.Cu" "B.Cu")
		(net "P12V_B_PGOOD")
	)
	(via
		(at 488.2896 -119.4816)
		(size 0.5588)
		(drill 0.3048)
		(layers "F.Cu" "B.Cu")
		(net "P12V_B_PGOOD")
	)
	(via
		(at 487.3752 -282.4734)
		(size 0.5588)
		(drill 0.3048)
		(layers "F.Cu" "B.Cu")
		(net "P12V_B_PGOOD")
	)
	(via
		(at 256.219706 -278.384)
		(size 0.6604)
		(drill 0.3048)
		(layers "F.Cu" "B.Cu")
		(net "P12V_B_PGOOD")
	)
	(via
		(at 218.53144 -153.8986)
		(size 0.5588)
		(drill 0.3048)
		(layers "F.Cu" "B.Cu")
		(net "P12V_B_PGOOD")
	)
	(via
		(at 488.5944 -232.03535)
		(size 0.5588)
		(drill 0.3048)
		(layers "F.Cu" "B.Cu")
		(net "P12V_B_PGOOD")
	)
	(segment
		(start 214.0458 -272.2626)
		(end 253.54534 -272.2626)
		(width 0.254)
		(layer "B.Cu")
		(net "P12V_B_PGOOD")
	)
	(segment
		(start 261.88035 -367.045748)
		(end 261.88035 -363.640878)
		(width 0.254)
		(layer "B.Cu")
		(net "P12V_B_PGOOD")
	)
	(segment
		(start 253.54534 -272.2626)
		(end 256.219706 -274.936966)
		(width 0.254)
		(layer "B.Cu")
		(net "P12V_B_PGOOD")
	)
	(segment
		(start 258.484878 -371.049804)
		(end 258.484878 -370.44122)
		(width 0.254)
		(layer "B.Cu")
		(net "P12V_B_PGOOD")
	)
	(segment
		(start 262.547354 -362.973874)
		(end 262.547354 -359.84434)
		(width 0.254)
		(layer "B.Cu")
		(net "P12V_B_PGOOD")
	)
	(segment
		(start 256.219706 -274.936966)
		(end 256.219706 -277.451312)
		(width 0.254)
		(layer "B.Cu")
		(net "P12V_B_PGOOD")
	)
	(segment
		(start 258.484878 -370.44122)
		(end 261.88035 -367.045748)
		(width 0.254)
		(layer "B.Cu")
		(net "P12V_B_PGOOD")
	)
	(segment
		(start 258.474972 -371.05971)
		(end 258.484878 -371.049804)
		(width 0.254)
		(layer "B.Cu")
		(net "P12V_B_PGOOD")
	)
	(segment
		(start 261.88035 -363.640878)
		(end 262.547354 -362.973874)
		(width 0.254)
		(layer "B.Cu")
		(net "P12V_B_PGOOD")
	)
	(segment
		(start 256.219706 -277.451312)
		(end 256.219706 -278.384)
		(width 0.254)
		(layer "B.Cu")
		(net "P12V_B_PGOOD")
	)
	(segment
		(start 271.388586 -352.45802)
		(end 273.05762 -350.788986)
		(width 0.254)
		(layer "B.Cu")
		(net "P12V_B_PGOOD")
	)
	(segment
		(start 262.547354 -359.84434)
		(end 269.933674 -352.45802)
		(width 0.254)
		(layer "B.Cu")
		(net "P12V_B_PGOOD")
	)
	(segment
		(start 273.05762 -350.788986)
		(end 273.05762 -336.061812)
		(width 0.254)
		(layer "B.Cu")
		(net "P12V_B_PGOOD")
	)
	(segment
		(start 269.933674 -352.45802)
		(end 271.388586 -352.45802)
		(width 0.254)
		(layer "B.Cu")
		(net "P12V_B_PGOOD")
	)
	(segment
		(start 224.795842 -84.56295)
		(end 223.206056 -86.152736)
		(width 0.254)
		(layer "In2.Cu")
		(net "P12V_B_PGOOD")
	)
	(segment
		(start 217.383106 -152.750266)
		(end 218.53144 -153.8986)
		(width 0.254)
		(layer "In2.Cu")
		(net "P12V_B_PGOOD")
	)
	(segment
		(start 276.352 -305.4096)
		(end 276.352 -332.767432)
		(width 0.254)
		(layer "In2.Cu")
		(net "P12V_B_PGOOD")
	)
	(segment
		(start 216.080594 -222.594932)
		(end 218.954096 -219.72143)
		(width 0.254)
		(layer "In2.Cu")
		(net "P12V_B_PGOOD")
	)
	(segment
		(start 220.35008 -170.069002)
		(end 219.252292 -168.971214)
		(width 0.254)
		(layer "In2.Cu")
		(net "P12V_B_PGOOD")
	)
	(segment
		(start 218.53144 -159.7406)
		(end 218.53144 -157.249368)
		(width 0.254)
		(layer "In2.Cu")
		(net "P12V_B_PGOOD")
	)
	(segment
		(start 488.5944 -119.7864)
		(end 488.5944 -232.03535)
		(width 0.254)
		(layer "In2.Cu")
		(net "P12V_B_PGOOD")
	)
	(segment
		(start 218.661742 -118.249954)
		(end 217.383106 -119.52859)
		(width 0.254)
		(layer "In2.Cu")
		(net "P12V_B_PGOOD")
	)
	(segment
		(start 219.836746 -215.937846)
		(end 219.837 -215.937846)
		(width 0.254)
		(layer "In2.Cu")
		(net "P12V_B_PGOOD")
	)
	(segment
		(start 213.972394 -272.189194)
		(end 213.972394 -248.719594)
		(width 0.254)
		(layer "In2.Cu")
		(net "P12V_B_PGOOD")
	)
	(segment
		(start 282.1432 -299.6184)
		(end 276.352 -305.4096)
		(width 0.254)
		(layer "In2.Cu")
		(net "P12V_B_PGOOD")
	)
	(segment
		(start 213.972394 -248.719594)
		(end 213.37778 -248.12498)
		(width 0.254)
		(layer "In2.Cu")
		(net "P12V_B_PGOOD")
	)
	(segment
		(start 216.080594 -228.306884)
		(end 216.080594 -222.594932)
		(width 0.254)
		(layer "In2.Cu")
		(net "P12V_B_PGOOD")
	)
	(segment
		(start 223.206056 -86.152736)
		(end 223.206056 -105.778046)
		(width 0.254)
		(layer "In2.Cu")
		(net "P12V_B_PGOOD")
	)
	(segment
		(start 224.795842 -75.404218)
		(end 224.795842 -84.56295)
		(width 0.254)
		(layer "In2.Cu")
		(net "P12V_B_PGOOD")
	)
	(segment
		(start 214.0458 -272.2626)
		(end 213.972394 -272.189194)
		(width 0.254)
		(layer "In2.Cu")
		(net "P12V_B_PGOOD")
	)
	(segment
		(start 218.493086 -155.08986)
		(end 218.53144 -155.051506)
		(width 0.254)
		(layer "In2.Cu")
		(net "P12V_B_PGOOD")
	)
	(segment
		(start 488.2896 -119.4816)
		(end 488.5944 -119.7864)
		(width 0.254)
		(layer "In2.Cu")
		(net "P12V_B_PGOOD")
	)
	(segment
		(start 218.53144 -155.051506)
		(end 218.53144 -153.8986)
		(width 0.254)
		(layer "In2.Cu")
		(net "P12V_B_PGOOD")
	)
	(segment
		(start 214.264748 -236.407452)
		(end 214.264748 -230.12273)
		(width 0.254)
		(layer "In2.Cu")
		(net "P12V_B_PGOOD")
	)
	(segment
		(start 293.5732 -292.8112)
		(end 286.766 -299.6184)
		(width 0.254)
		(layer "In2.Cu")
		(net "P12V_B_PGOOD")
	)
	(segment
		(start 219.252292 -168.971214)
		(end 219.252292 -160.461452)
		(width 0.254)
		(layer "In2.Cu")
		(net "P12V_B_PGOOD")
	)
	(segment
		(start 219.252292 -160.461452)
		(end 218.53144 -159.7406)
		(width 0.254)
		(layer "In2.Cu")
		(net "P12V_B_PGOOD")
	)
	(segment
		(start 214.264748 -230.12273)
		(end 216.080594 -228.306884)
		(width 0.254)
		(layer "In2.Cu")
		(net "P12V_B_PGOOD")
	)
	(segment
		(start 286.766 -299.6184)
		(end 282.1432 -299.6184)
		(width 0.254)
		(layer "In2.Cu")
		(net "P12V_B_PGOOD")
	)
	(segment
		(start 293.5732 -272.9738)
		(end 293.5732 -292.8112)
		(width 0.254)
		(layer "In2.Cu")
		(net "P12V_B_PGOOD")
	)
	(segment
		(start 293.5224 -272.923)
		(end 293.5732 -272.9738)
		(width 0.254)
		(layer "In2.Cu")
		(net "P12V_B_PGOOD")
	)
	(segment
		(start 276.352 -332.767432)
		(end 273.05762 -336.061812)
		(width 0.254)
		(layer "In2.Cu")
		(net "P12V_B_PGOOD")
	)
	(segment
		(start 487.3752 -282.4734)
		(end 488.5944 -281.2542)
		(width 0.254)
		(layer "In2.Cu")
		(net "P12V_B_PGOOD")
	)
	(segment
		(start 218.53144 -157.249368)
		(end 218.493086 -157.211014)
		(width 0.254)
		(layer "In2.Cu")
		(net "P12V_B_PGOOD")
	)
	(segment
		(start 218.493086 -157.211014)
		(end 218.493086 -155.08986)
		(width 0.254)
		(layer "In2.Cu")
		(net "P12V_B_PGOOD")
	)
	(segment
		(start 488.5944 -281.2542)
		(end 488.5944 -232.03535)
		(width 0.254)
		(layer "In2.Cu")
		(net "P12V_B_PGOOD")
	)
	(segment
		(start 218.954096 -219.72143)
		(end 218.954096 -216.820496)
		(width 0.254)
		(layer "In2.Cu")
		(net "P12V_B_PGOOD")
	)
	(segment
		(start 217.383106 -119.52859)
		(end 217.383106 -152.750266)
		(width 0.254)
		(layer "In2.Cu")
		(net "P12V_B_PGOOD")
	)
	(segment
		(start 213.37778 -248.12498)
		(end 213.37778 -237.29442)
		(width 0.254)
		(layer "In2.Cu")
		(net "P12V_B_PGOOD")
	)
	(segment
		(start 226.200208 -73.999852)
		(end 224.795842 -75.404218)
		(width 0.254)
		(layer "In2.Cu")
		(net "P12V_B_PGOOD")
	)
	(segment
		(start 218.954096 -216.820496)
		(end 219.836746 -215.937846)
		(width 0.254)
		(layer "In2.Cu")
		(net "P12V_B_PGOOD")
	)
	(segment
		(start 219.837 -215.937846)
		(end 220.35008 -215.424766)
		(width 0.254)
		(layer "In2.Cu")
		(net "P12V_B_PGOOD")
	)
	(segment
		(start 223.206056 -105.778046)
		(end 220.411802 -108.5723)
		(width 0.254)
		(layer "In2.Cu")
		(net "P12V_B_PGOOD")
	)
	(segment
		(start 220.35008 -215.424766)
		(end 220.35008 -170.069002)
		(width 0.254)
		(layer "In2.Cu")
		(net "P12V_B_PGOOD")
	)
	(segment
		(start 218.661742 -111.87938)
		(end 218.661742 -118.249954)
		(width 0.254)
		(layer "In2.Cu")
		(net "P12V_B_PGOOD")
	)
	(segment
		(start 213.37778 -237.29442)
		(end 214.264748 -236.407452)
		(width 0.254)
		(layer "In2.Cu")
		(net "P12V_B_PGOOD")
	)
	(segment
		(start 220.411802 -108.5723)
		(end 220.411802 -110.12932)
		(width 0.254)
		(layer "In2.Cu")
		(net "P12V_B_PGOOD")
	)
	(segment
		(start 220.411802 -110.12932)
		(end 218.661742 -111.87938)
		(width 0.254)
		(layer "In2.Cu")
		(net "P12V_B_PGOOD")
	)
	(segment
		(start 185.4962 -136.509506)
		(end 185.4962 -130.5052)
		(width 0.254)
		(layer "In5.Cu")
		(net "P12V_B_PGOOD")
	)
	(segment
		(start 185.4962 -130.5052)
		(end 181.5084 -126.5174)
		(width 0.254)
		(layer "In5.Cu")
		(net "P12V_B_PGOOD")
	)
	(segment
		(start 303.0728 -282.4734)
		(end 293.5224 -272.923)
		(width 0.254)
		(layer "In5.Cu")
		(net "P12V_B_PGOOD")
	)
	(segment
		(start 218.53144 -153.8986)
		(end 218.15044 -153.8986)
		(width 0.254)
		(layer "In5.Cu")
		(net "P12V_B_PGOOD")
	)
	(segment
		(start 201.642726 -152.656032)
		(end 185.4962 -136.509506)
		(width 0.254)
		(layer "In5.Cu")
		(net "P12V_B_PGOOD")
	)
	(segment
		(start 487.3752 -282.4734)
		(end 303.0728 -282.4734)
		(width 0.254)
		(layer "In5.Cu")
		(net "P12V_B_PGOOD")
	)
	(segment
		(start 216.907872 -152.656032)
		(end 201.642726 -152.656032)
		(width 0.254)
		(layer "In5.Cu")
		(net "P12V_B_PGOOD")
	)
	(segment
		(start 218.15044 -153.8986)
		(end 216.907872 -152.656032)
		(width 0.254)
		(layer "In5.Cu")
		(net "P12V_B_PGOOD")
	)
	(segment
		(start 431.546 -16.3195)
		(end 431.546 -15.494)
		(width 0.508)
		(layer "F.Cu")
		(net "P12V_B")
	)
	(segment
		(start 456.8698 -134.6454)
		(end 456.5396 -134.3152)
		(width 0.508)
		(layer "F.Cu")
		(net "P12V_B")
	)
	(segment
		(start 140.6525 -16.637)
		(end 139.7635 -16.637)
		(width 0.508)
		(layer "F.Cu")
		(net "P12V_B")
	)
	(segment
		(start 260.6294 -289.2044)
		(end 260.6294 -291.082984)
		(width 0.508)
		(layer "F.Cu")
		(net "P12V_B")
	)
	(segment
		(start 171.9072 -246.634)
		(end 171.5516 -246.9896)
		(width 0.508)
		(layer "F.Cu")
		(net "P12V_B")
	)
	(segment
		(start 177.6984 -9.4869)
		(end 177.6984 -8.728964)
		(width 0.508)
		(layer "F.Cu")
		(net "P12V_B")
	)
	(segment
		(start 393.26058 -17.6022)
		(end 393.262866 -17.604486)
		(width 0.508)
		(layer "F.Cu")
		(net "P12V_B")
	)
	(segment
		(start 79.4385 -138.049)
		(end 79.4385 -136.2202)
		(width 0.508)
		(layer "F.Cu")
		(net "P12V_B")
	)
	(segment
		(start 331.3049 -249.4788)
		(end 330.5302 -249.4788)
		(width 0.508)
		(layer "F.Cu")
		(net "P12V_B")
	)
	(segment
		(start 50.4952 -9.5123)
		(end 50.4952 -8.636)
		(width 0.508)
		(layer "F.Cu")
		(net "P12V_B")
	)
	(segment
		(start 140.6525 -246.634)
		(end 140.6525 -247.0023)
		(width 0.508)
		(layer "F.Cu")
		(net "P12V_B")
	)
	(segment
		(start 362.6739 -134.5946)
		(end 362.0262 -134.5946)
		(width 0.508)
		(layer "F.Cu")
		(net "P12V_B")
	)
	(segment
		(start 112.8776 -9.0805)
		(end 112.8776 -8.30072)
		(width 0.508)
		(layer "F.Cu")
		(net "P12V_B")
	)
	(segment
		(start 425.2722 -134.6454)
		(end 424.9928 -134.366)
		(width 0.508)
		(layer "F.Cu")
		(net "P12V_B")
	)
	(segment
		(start 79.4385 -253.111)
		(end 79.4385 -252.222)
		(width 0.508)
		(layer "F.Cu")
		(net "P12V_B")
	)
	(segment
		(start 16.3195 -23.114)
		(end 16.3195 -22.225)
		(width 0.508)
		(layer "F.Cu")
		(net "P12V_B")
	)
	(segment
		(start 400.05 -246.3165)
		(end 400.05 -245.491)
		(width 0.508)
		(layer "F.Cu")
		(net "P12V_B")
	)
	(segment
		(start 172.1485 -131.572)
		(end 171.2595 -131.572)
		(width 0.508)
		(layer "F.Cu")
		(net "P12V_B")
	)
	(segment
		(start 45.4914 -131.572)
		(end 44.815506 -132.247894)
		(width 0.508)
		(layer "F.Cu")
		(net "P12V_B")
	)
	(segment
		(start 140.6525 -131.572)
		(end 139.7635 -131.572)
		(width 0.508)
		(layer "F.Cu")
		(net "P12V_B")
	)
	(segment
		(start 51.581812 -9.441688)
		(end 51.581812 -8.628888)
		(width 0.508)
		(layer "F.Cu")
		(net "P12V_B")
	)
	(segment
		(start 425.8437 -134.6454)
		(end 425.2722 -134.6454)
		(width 0.508)
		(layer "F.Cu")
		(net "P12V_B")
	)
	(segment
		(start 77.5335 -131.572)
		(end 76.6445 -131.572)
		(width 0.508)
		(layer "F.Cu")
		(net "P12V_B")
	)
	(segment
		(start 109.241082 -31.078678)
		(end 110.513622 -31.078678)
		(width 0.508)
		(layer "F.Cu")
		(net "P12V_B")
	)
	(segment
		(start 256.6416 -286.8422)
		(end 258.2672 -286.8422)
		(width 0.508)
		(layer "F.Cu")
		(net "P12V_B")
	)
	(segment
		(start 140.6525 -24.511)
		(end 140.6525 -25.527)
		(width 0.508)
		(layer "F.Cu")
		(net "P12V_B")
	)
	(segment
		(start 77.4954 -246.634)
		(end 76.7334 -247.396)
		(width 0.508)
		(layer "F.Cu")
		(net "P12V_B")
	)
	(segment
		(start 16.3195 -138.049)
		(end 16.3195 -137.16)
		(width 0.508)
		(layer "F.Cu")
		(net "P12V_B")
	)
	(segment
		(start 14.4145 -16.637)
		(end 14.4145 -15.748)
		(width 0.508)
		(layer "F.Cu")
		(net "P12V_B")
	)
	(segment
		(start 364.6805 -19.558)
		(end 364.6805 -18.7325)
		(width 0.508)
		(layer "F.Cu")
		(net "P12V_B")
	)
	(segment
		(start 55.118 -10.6045)
		(end 55.118 -9.7155)
		(width 0.508)
		(layer "F.Cu")
		(net "P12V_B")
	)
	(segment
		(start 181.356 -10.6045)
		(end 181.356 -9.7155)
		(width 0.508)
		(layer "F.Cu")
		(net "P12V_B")
	)
	(segment
		(start 14.4145 -24.511)
		(end 14.4145 -25.527)
		(width 0.508)
		(layer "F.Cu")
		(net "P12V_B")
	)
	(segment
		(start 361.8992 -249.5296)
		(end 361.7976 -249.428)
		(width 0.508)
		(layer "F.Cu")
		(net "P12V_B")
	)
	(segment
		(start 172.1485 -246.634)
		(end 171.9072 -246.634)
		(width 0.508)
		(layer "F.Cu")
		(net "P12V_B")
	)
	(segment
		(start 394.2715 -249.5804)
		(end 393.7 -249.5804)
		(width 0.508)
		(layer "F.Cu")
		(net "P12V_B")
	)
	(segment
		(start 79.4385 -23.114)
		(end 79.4385 -21.5011)
		(width 0.508)
		(layer "F.Cu")
		(net "P12V_B")
	)
	(segment
		(start 46.0375 -246.634)
		(end 45.7962 -246.634)
		(width 0.508)
		(layer "F.Cu")
		(net "P12V_B")
	)
	(segment
		(start 118.237 -10.6045)
		(end 118.237 -9.7155)
		(width 0.508)
		(layer "F.Cu")
		(net "P12V_B")
	)
	(segment
		(start 50.82286 -122.247406)
		(end 50.82286 -121.421906)
		(width 0.508)
		(layer "F.Cu")
		(net "P12V_B")
	)
	(segment
		(start 25.974802 -233.43235)
		(end 25.974802 -232.60685)
		(width 0.508)
		(layer "F.Cu")
		(net "P12V_B")
	)
	(segment
		(start 368.427 -16.3195)
		(end 368.427 -15.494)
		(width 0.508)
		(layer "F.Cu")
		(net "P12V_B")
	)
	(segment
		(start 336.931 -246.3165)
		(end 336.931 -245.491)
		(width 0.508)
		(layer "F.Cu")
		(net "P12V_B")
	)
	(segment
		(start 260.991096 -241.034316)
		(end 260.991096 -238.583724)
		(width 0.508)
		(layer "F.Cu")
		(net "P12V_B")
	)
	(segment
		(start 77.5335 -139.446)
		(end 77.5335 -140.462)
		(width 0.508)
		(layer "F.Cu")
		(net "P12V_B")
	)
	(segment
		(start 368.427 -131.3815)
		(end 368.427 -130.556)
		(width 0.508)
		(layer "F.Cu")
		(net "P12V_B")
	)
	(segment
		(start 45.2628 -247.1674)
		(end 45.2628 -248.3358)
		(width 0.508)
		(layer "F.Cu")
		(net "P12V_B")
	)
	(segment
		(start 77.5335 -246.634)
		(end 77.4954 -246.634)
		(width 0.508)
		(layer "F.Cu")
		(net "P12V_B")
	)
	(segment
		(start 431.546 -131.3815)
		(end 431.546 -130.556)
		(width 0.508)
		(layer "F.Cu")
		(net "P12V_B")
	)
	(segment
		(start 475.134178 -19.277838)
		(end 474.561662 -19.277838)
		(width 0.508)
		(layer "F.Cu")
		(net "P12V_B")
	)
	(segment
		(start 174.0535 -138.049)
		(end 174.0535 -137.16)
		(width 0.508)
		(layer "F.Cu")
		(net "P12V_B")
	)
	(segment
		(start 456.692 -249.4788)
		(end 456.4126 -249.1994)
		(width 0.508)
		(layer "F.Cu")
		(net "P12V_B")
	)
	(segment
		(start 393.5476 -134.5692)
		(end 393.2936 -134.3152)
		(width 0.508)
		(layer "F.Cu")
		(net "P12V_B")
	)
	(segment
		(start 14.4145 -131.572)
		(end 13.5255 -131.572)
		(width 0.508)
		(layer "F.Cu")
		(net "P12V_B")
	)
	(segment
		(start 394.1953 -134.5692)
		(end 393.5476 -134.5692)
		(width 0.508)
		(layer "F.Cu")
		(net "P12V_B")
	)
	(segment
		(start 109.0295 -246.634)
		(end 108.839 -246.634)
		(width 0.508)
		(layer "F.Cu")
		(net "P12V_B")
	)
	(segment
		(start 431.546 -246.3165)
		(end 431.546 -245.491)
		(width 0.508)
		(layer "F.Cu")
		(net "P12V_B")
	)
	(segment
		(start 77.5335 -254.508)
		(end 77.5335 -255.524)
		(width 0.508)
		(layer "F.Cu")
		(net "P12V_B")
	)
	(segment
		(start 461.584802 -233.43235)
		(end 461.584802 -232.60685)
		(width 0.508)
		(layer "F.Cu")
		(net "P12V_B")
	)
	(segment
		(start 142.5575 -138.049)
		(end 142.5575 -137.16)
		(width 0.508)
		(layer "F.Cu")
		(net "P12V_B")
	)
	(segment
		(start 442.686186 -123.115578)
		(end 442.686186 -122.290078)
		(width 0.508)
		(layer "F.Cu")
		(net "P12V_B")
	)
	(segment
		(start 139.8778 -247.777)
		(end 139.8778 -248.793)
		(width 0.508)
		(layer "F.Cu")
		(net "P12V_B")
	)
	(segment
		(start 334.7212 -12.3698)
		(end 335.0514 -12.0396)
		(width 0.508)
		(layer "F.Cu")
		(net "P12V_B")
	)
	(segment
		(start 462.896712 -22.282912)
		(end 463.1182 -22.5044)
		(width 0.508)
		(layer "F.Cu")
		(net "P12V_B")
	)
	(segment
		(start 425.1706 -249.5042)
		(end 424.8912 -249.2248)
		(width 0.508)
		(layer "F.Cu")
		(net "P12V_B")
	)
	(segment
		(start 47.9425 -253.111)
		(end 47.9425 -252.222)
		(width 0.508)
		(layer "F.Cu")
		(net "P12V_B")
	)
	(segment
		(start 456.9714 -19.9517)
		(end 456.9714 -20.834858)
		(width 0.508)
		(layer "F.Cu")
		(net "P12V_B")
	)
	(segment
		(start 109.0295 -139.446)
		(end 109.0295 -140.462)
		(width 0.508)
		(layer "F.Cu")
		(net "P12V_B")
	)
	(segment
		(start 110.9345 -253.111)
		(end 110.9345 -252.222)
		(width 0.508)
		(layer "F.Cu")
		(net "P12V_B")
	)
	(segment
		(start 329.438 -17.399)
		(end 329.5396 -17.5006)
		(width 0.508)
		(layer "F.Cu")
		(net "P12V_B")
	)
	(segment
		(start 46.0375 -254.508)
		(end 46.0375 -255.524)
		(width 0.508)
		(layer "F.Cu")
		(net "P12V_B")
	)
	(segment
		(start 330.5302 -249.4788)
		(end 330.4286 -249.3772)
		(width 0.508)
		(layer "F.Cu")
		(net "P12V_B")
	)
	(segment
		(start 77.5335 -24.511)
		(end 77.5335 -25.527)
		(width 0.508)
		(layer "F.Cu")
		(net "P12V_B")
	)
	(segment
		(start 336.931 -131.3815)
		(end 336.931 -130.556)
		(width 0.508)
		(layer "F.Cu")
		(net "P12V_B")
	)
	(segment
		(start 109.0295 -131.572)
		(end 109.0295 -130.310128)
		(width 0.508)
		(layer "F.Cu")
		(net "P12V_B")
	)
	(segment
		(start 471.3605 -138.049)
		(end 471.3605 -137.16)
		(width 0.508)
		(layer "F.Cu")
		(net "P12V_B")
	)
	(segment
		(start 457.3397 -134.6454)
		(end 456.8698 -134.6454)
		(width 0.508)
		(layer "F.Cu")
		(net "P12V_B")
	)
	(segment
		(start 14.4145 -254.508)
		(end 14.4145 -255.524)
		(width 0.508)
		(layer "F.Cu")
		(net "P12V_B")
	)
	(segment
		(start 474.561662 -19.277838)
		(end 474.0275 -19.812)
		(width 0.508)
		(layer "F.Cu")
		(net "P12V_B")
	)
	(segment
		(start 176.7205 -19.939)
		(end 177.237898 -19.421602)
		(width 0.508)
		(layer "F.Cu")
		(net "P12V_B")
	)
	(segment
		(start 109.0295 -130.310128)
		(end 109.01934 -130.299968)
		(width 0.508)
		(layer "F.Cu")
		(net "P12V_B")
	)
	(segment
		(start 399.288 -12.8905)
		(end 400.1516 -12.8905)
		(width 0.508)
		(layer "F.Cu")
		(net "P12V_B")
	)
	(segment
		(start 14.4145 -246.634)
		(end 13.5255 -246.634)
		(width 0.508)
		(layer "F.Cu")
		(net "P12V_B")
	)
	(segment
		(start 258.474972 -372.77421)
		(end 258.474972 -373.59971)
		(width 0.508)
		(layer "F.Cu")
		(net "P12V_B")
	)
	(segment
		(start 473.4433 -10.6934)
		(end 473.4433 -11.5316)
		(width 0.508)
		(layer "F.Cu")
		(net "P12V_B")
	)
	(segment
		(start 109.0295 -254.508)
		(end 109.0295 -255.524)
		(width 0.508)
		(layer "F.Cu")
		(net "P12V_B")
	)
	(segment
		(start 425.069 -19.558)
		(end 424.9166 -19.4056)
		(width 0.508)
		(layer "F.Cu")
		(net "P12V_B")
	)
	(segment
		(start 469.4555 -139.446)
		(end 469.4555 -140.462)
		(width 0.508)
		(layer "F.Cu")
		(net "P12V_B")
	)
	(segment
		(start 463.042 -246.3165)
		(end 463.042 -245.491)
		(width 0.508)
		(layer "F.Cu")
		(net "P12V_B")
	)
	(segment
		(start 45.7962 -246.634)
		(end 45.2628 -247.1674)
		(width 0.508)
		(layer "F.Cu")
		(net "P12V_B")
	)
	(segment
		(start 467.2965 -250.571)
		(end 467.2965 -249.682)
		(width 0.508)
		(layer "F.Cu")
		(net "P12V_B")
	)
	(segment
		(start 329.5396 -17.5006)
		(end 330.5937 -17.5006)
		(width 0.508)
		(layer "F.Cu")
		(net "P12V_B")
	)
	(segment
		(start 471.3605 -253.111)
		(end 471.3605 -252.222)
		(width 0.508)
		(layer "F.Cu")
		(net "P12V_B")
	)
	(segment
		(start 174.0535 -253.111)
		(end 174.0535 -252.222)
		(width 0.508)
		(layer "F.Cu")
		(net "P12V_B")
	)
	(segment
		(start 51.008026 -19.413474)
		(end 51.008026 -19.004026)
		(width 0.508)
		(layer "F.Cu")
		(net "P12V_B")
	)
	(segment
		(start 47.8155 -138.049)
		(end 47.8155 -137.16)
		(width 0.508)
		(layer "F.Cu")
		(net "P12V_B")
	)
	(segment
		(start 171.5516 -246.9896)
		(end 171.5516 -249.047)
		(width 0.508)
		(layer "F.Cu")
		(net "P12V_B")
	)
	(segment
		(start 176.6824 -9.4869)
		(end 176.6824 -8.636)
		(width 0.508)
		(layer "F.Cu")
		(net "P12V_B")
	)
	(segment
		(start 140.6525 -254.508)
		(end 140.6525 -255.524)
		(width 0.508)
		(layer "F.Cu")
		(net "P12V_B")
	)
	(segment
		(start 362.6739 -249.5296)
		(end 361.8992 -249.5296)
		(width 0.508)
		(layer "F.Cu")
		(net "P12V_B")
	)
	(segment
		(start 177.237898 -19.421602)
		(end 177.237898 -18.919952)
		(width 0.508)
		(layer "F.Cu")
		(net "P12V_B")
	)
	(segment
		(start 172.1485 -254.508)
		(end 172.1485 -255.524)
		(width 0.508)
		(layer "F.Cu")
		(net "P12V_B")
	)
	(segment
		(start 469.4555 -254.508)
		(end 469.4555 -255.524)
		(width 0.508)
		(layer "F.Cu")
		(net "P12V_B")
	)
	(segment
		(start 457.2635 -249.4788)
		(end 456.692 -249.4788)
		(width 0.508)
		(layer "F.Cu")
		(net "P12V_B")
	)
	(segment
		(start 112.8776 -8.30072)
		(end 112.944402 -8.233918)
		(width 0.508)
		(layer "F.Cu")
		(net "P12V_B")
	)
	(segment
		(start 252.544834 -372.787418)
		(end 252.544834 -373.614442)
		(width 0.508)
		(layer "F.Cu")
		(net "P12V_B")
	)
	(segment
		(start 16.3195 -253.111)
		(end 16.3195 -252.222)
		(width 0.508)
		(layer "F.Cu")
		(net "P12V_B")
	)
	(segment
		(start 142.5575 -253.111)
		(end 142.5575 -252.222)
		(width 0.508)
		(layer "F.Cu")
		(net "P12V_B")
	)
	(segment
		(start 463.042 -131.3815)
		(end 463.042 -130.556)
		(width 0.508)
		(layer "F.Cu")
		(net "P12V_B")
	)
	(segment
		(start 111.8616 -9.0805)
		(end 111.8616 -8.2296)
		(width 0.508)
		(layer "F.Cu")
		(net "P12V_B")
	)
	(segment
		(start 108.839 -246.634)
		(end 108.2802 -247.1928)
		(width 0.508)
		(layer "F.Cu")
		(net "P12V_B")
	)
	(segment
		(start 45.9105 -139.446)
		(end 45.9105 -140.462)
		(width 0.508)
		(layer "F.Cu")
		(net "P12V_B")
	)
	(segment
		(start 45.9105 -131.572)
		(end 45.4914 -131.572)
		(width 0.508)
		(layer "F.Cu")
		(net "P12V_B")
	)
	(segment
		(start 393.7 -249.5804)
		(end 393.4206 -249.301)
		(width 0.508)
		(layer "F.Cu")
		(net "P12V_B")
	)
	(segment
		(start 110.513622 -31.078678)
		(end 110.5154 -31.0769)
		(width 0.508)
		(layer "F.Cu")
		(net "P12V_B")
	)
	(segment
		(start 425.7421 -249.5042)
		(end 425.1706 -249.5042)
		(width 0.508)
		(layer "F.Cu")
		(net "P12V_B")
	)
	(segment
		(start 108.2802 -247.1928)
		(end 108.2802 -248.1072)
		(width 0.508)
		(layer "F.Cu")
		(net "P12V_B")
	)
	(segment
		(start 472.1987 -5.6642)
		(end 472.1987 -4.826)
		(width 0.508)
		(layer "F.Cu")
		(net "P12V_B")
	)
	(segment
		(start 142.5575 -23.114)
		(end 142.5575 -22.225)
		(width 0.508)
		(layer "F.Cu")
		(net "P12V_B")
	)
	(segment
		(start 79.4385 -21.5011)
		(end 79.1972 -21.2598)
		(width 0.508)
		(layer "F.Cu")
		(net "P12V_B")
	)
	(segment
		(start 76.7334 -247.396)
		(end 76.7334 -248.4628)
		(width 0.508)
		(layer "F.Cu")
		(net "P12V_B")
	)
	(segment
		(start 77.5335 -16.637)
		(end 76.6445 -16.637)
		(width 0.508)
		(layer "F.Cu")
		(net "P12V_B")
	)
	(segment
		(start 467.2965 -135.509)
		(end 467.2965 -134.6835)
		(width 0.508)
		(layer "F.Cu")
		(net "P12V_B")
	)
	(segment
		(start 172.1485 -139.446)
		(end 172.1485 -140.462)
		(width 0.508)
		(layer "F.Cu")
		(net "P12V_B")
	)
	(segment
		(start 140.6525 -247.0023)
		(end 139.8778 -247.777)
		(width 0.508)
		(layer "F.Cu")
		(net "P12V_B")
	)
	(segment
		(start 394.1953 -17.6022)
		(end 393.26058 -17.6022)
		(width 0.508)
		(layer "F.Cu")
		(net "P12V_B")
	)
	(segment
		(start 50.4825 -19.939)
		(end 51.008026 -19.413474)
		(width 0.508)
		(layer "F.Cu")
		(net "P12V_B")
	)
	(segment
		(start 252.544834 -373.614442)
		(end 252.43282 -373.726456)
		(width 0.508)
		(layer "F.Cu")
		(net "P12V_B")
	)
	(segment
		(start 330.2254 -134.62)
		(end 331.0509 -134.62)
		(width 0.508)
		(layer "F.Cu")
		(net "P12V_B")
	)
	(segment
		(start 456.9714 -20.834858)
		(end 456.969876 -20.836382)
		(width 0.508)
		(layer "F.Cu")
		(net "P12V_B")
	)
	(segment
		(start 110.9345 -138.049)
		(end 110.9345 -136.7536)
		(width 0.508)
		(layer "F.Cu")
		(net "P12V_B")
	)
	(segment
		(start 425.7421 -19.558)
		(end 425.069 -19.558)
		(width 0.508)
		(layer "F.Cu")
		(net "P12V_B")
	)
	(segment
		(start 462.896712 -21.599906)
		(end 462.896712 -22.282912)
		(width 0.508)
		(layer "F.Cu")
		(net "P12V_B")
	)
	(segment
		(start 334.7212 -12.8397)
		(end 334.7212 -12.3698)
		(width 0.508)
		(layer "F.Cu")
		(net "P12V_B")
	)
	(segment
		(start 362.0262 -134.5946)
		(end 361.823 -134.3914)
		(width 0.508)
		(layer "F.Cu")
		(net "P12V_B")
	)
	(segment
		(start 473.4433 -9.6774)
		(end 472.567 -9.6774)
		(width 0.508)
		(layer "F.Cu")
		(net "P12V_B")
	)
	(segment
		(start 14.4145 -139.446)
		(end 14.4145 -140.462)
		(width 0.508)
		(layer "F.Cu")
		(net "P12V_B")
	)
	(segment
		(start 51.5112 -9.5123)
		(end 51.581812 -9.441688)
		(width 0.508)
		(layer "F.Cu")
		(net "P12V_B")
	)
	(segment
		(start 44.815506 -132.247894)
		(end 44.815506 -133.347968)
		(width 0.508)
		(layer "F.Cu")
		(net "P12V_B")
	)
	(segment
		(start 400.05 -131.3815)
		(end 400.05 -130.556)
		(width 0.508)
		(layer "F.Cu")
		(net "P12V_B")
	)
	(segment
		(start 177.6984 -8.728964)
		(end 177.782728 -8.644636)
		(width 0.508)
		(layer "F.Cu")
		(net "P12V_B")
	)
	(segment
		(start 258.2672 -286.8422)
		(end 260.6294 -289.2044)
		(width 0.508)
		(layer "F.Cu")
		(net "P12V_B")
	)
	(segment
		(start 140.6525 -139.446)
		(end 140.6525 -140.462)
		(width 0.508)
		(layer "F.Cu")
		(net "P12V_B")
	)
	(segment
		(start 368.427 -246.3165)
		(end 368.427 -245.491)
		(width 0.508)
		(layer "F.Cu")
		(net "P12V_B")
	)
	(via
		(at 207.6704 -147.972272)
		(size 0.7112)
		(drill 0.4064)
		(layers "F.Cu" "B.Cu")
		(net "P12V_B")
	)
	(via
		(at 468.884 -256.794)
		(size 0.5588)
		(drill 0.3048)
		(layers "F.Cu" "B.Cu")
		(net "P12V_B")
	)
	(via
		(at 108.2802 -248.1072)
		(size 0.5588)
		(drill 0.3048)
		(layers "F.Cu" "B.Cu")
		(net "P12V_B")
	)
	(via
		(at 473.4433 -11.5316)
		(size 0.5588)
		(drill 0.3048)
		(layers "F.Cu" "B.Cu")
		(net "P12V_B")
	)
	(via
		(at 269.514574 -349.595186)
		(size 0.8636)
		(drill 0.508)
		(layers "F.Cu" "B.Cu")
		(net "P12V_B")
	)
	(via
		(at 270.886174 -345.480386)
		(size 0.8636)
		(drill 0.508)
		(layers "F.Cu" "B.Cu")
		(net "P12V_B")
	)
	(via
		(at 263.4488 -339.09)
		(size 0.8636)
		(drill 0.508)
		(layers "F.Cu" "B.Cu")
		(net "P12V_B")
	)
	(via
		(at 268.279372 -334.413606)
		(size 0.8636)
		(drill 0.508)
		(layers "F.Cu" "B.Cu")
		(net "P12V_B")
	)
	(via
		(at 264.156952 -347.307408)
		(size 0.8636)
		(drill 0.508)
		(layers "F.Cu" "B.Cu")
		(net "P12V_B")
	)
	(via
		(at 32.4104 -111.125)
		(size 0.7112)
		(drill 0.4064)
		(layers "F.Cu" "B.Cu")
		(net "P12V_B")
	)
	(via
		(at 271.0688 -201.041)
		(size 0.7112)
		(drill 0.4064)
		(layers "F.Cu" "B.Cu")
		(net "P12V_B")
	)
	(via
		(at 423.509186 -111.558578)
		(size 0.7112)
		(drill 0.4064)
		(layers "F.Cu" "B.Cu")
		(net "P12V_B")
	)
	(via
		(at 14.986 -141.732)
		(size 0.5588)
		(drill 0.3048)
		(layers "F.Cu" "B.Cu")
		(net "P12V_B")
	)
	(via
		(at 399.161 -258.826)
		(size 0.5588)
		(drill 0.3048)
		(layers "F.Cu" "B.Cu")
		(net "P12V_B")
	)
	(via
		(at 177.237898 -18.919952)
		(size 0.5588)
		(drill 0.3048)
		(layers "F.Cu" "B.Cu")
		(net "P12V_B")
	)
	(via
		(at 14.986 -26.797)
		(size 0.5588)
		(drill 0.3048)
		(layers "F.Cu" "B.Cu")
		(net "P12V_B")
	)
	(via
		(at 257.946398 -92.941394)
		(size 0.7112)
		(drill 0.4064)
		(layers "F.Cu" "B.Cu")
		(net "P12V_B")
	)
	(via
		(at 200.4822 -311.700672)
		(size 0.7112)
		(drill 0.4064)
		(layers "F.Cu" "B.Cu")
		(net "P12V_B")
	)
	(via
		(at 140.081 -256.794)
		(size 0.5588)
		(drill 0.3048)
		(layers "F.Cu" "B.Cu")
		(net "P12V_B")
	)
	(via
		(at 203.922122 -109.033056)
		(size 0.7112)
		(drill 0.4064)
		(layers "F.Cu" "B.Cu")
		(net "P12V_B")
	)
	(via
		(at 280.791158 -106.33456)
		(size 0.7112)
		(drill 0.4064)
		(layers "F.Cu" "B.Cu")
		(net "P12V_B")
	)
	(via
		(at 336.042 -143.891)
		(size 0.5588)
		(drill 0.3048)
		(layers "F.Cu" "B.Cu")
		(net "P12V_B")
	)
	(via
		(at 405.4856 -34.4424)
		(size 0.5588)
		(drill 0.3048)
		(layers "F.Cu" "B.Cu")
		(net "P12V_B")
	)
	(via
		(at 286.639 -310.1086)
		(size 0.7112)
		(drill 0.4064)
		(layers "F.Cu" "B.Cu")
		(net "P12V_B")
	)
	(via
		(at 399.800826 -257.866134)
		(size 0.6604)
		(drill 0.3302)
		(layers "F.Cu" "B.Cu")
		(net "P12V_B")
	)
	(via
		(at 118.237 -9.7155)
		(size 0.5588)
		(drill 0.3048)
		(layers "F.Cu" "B.Cu")
		(net "P12V_B")
	)
	(via
		(at 13.843 -256.794)
		(size 0.5588)
		(drill 0.3048)
		(layers "F.Cu" "B.Cu")
		(net "P12V_B")
	)
	(via
		(at 442.254386 -219.483178)
		(size 0.7112)
		(drill 0.4064)
		(layers "F.Cu" "B.Cu")
		(net "P12V_B")
	)
	(via
		(at 44.815506 -133.347968)
		(size 0.5588)
		(drill 0.3048)
		(layers "F.Cu" "B.Cu")
		(net "P12V_B")
	)
	(via
		(at 400.1516 -12.8905)
		(size 0.5588)
		(drill 0.3048)
		(layers "F.Cu" "B.Cu")
		(net "P12V_B")
	)
	(via
		(at 462.026 -28.829)
		(size 0.5588)
		(drill 0.3048)
		(layers "F.Cu" "B.Cu")
		(net "P12V_B")
	)
	(via
		(at 431.927 -143.891)
		(size 0.5588)
		(drill 0.3048)
		(layers "F.Cu" "B.Cu")
		(net "P12V_B")
	)
	(via
		(at 471.3605 -252.222)
		(size 0.5588)
		(drill 0.3048)
		(layers "F.Cu" "B.Cu")
		(net "P12V_B")
	)
	(via
		(at 76.6445 -131.572)
		(size 0.5588)
		(drill 0.3048)
		(layers "F.Cu" "B.Cu")
		(net "P12V_B")
	)
	(via
		(at 266.2936 -340.2838)
		(size 0.6604)
		(drill 0.3302)
		(layers "F.Cu" "B.Cu")
		(net "P12V_B")
	)
	(via
		(at 206.5274 -311.700672)
		(size 0.7112)
		(drill 0.4064)
		(layers "F.Cu" "B.Cu")
		(net "P12V_B")
	)
	(via
		(at 429.3616 -28.9814)
		(size 0.5588)
		(drill 0.3048)
		(layers "F.Cu" "B.Cu")
		(net "P12V_B")
	)
	(via
		(at 202.7936 -149.166072)
		(size 0.7112)
		(drill 0.4064)
		(layers "F.Cu" "B.Cu")
		(net "P12V_B")
	)
	(via
		(at 423.509186 -109.120178)
		(size 0.7112)
		(drill 0.4064)
		(layers "F.Cu" "B.Cu")
		(net "P12V_B")
	)
	(via
		(at 205.3082 -310.481472)
		(size 0.7112)
		(drill 0.4064)
		(layers "F.Cu" "B.Cu")
		(net "P12V_B")
	)
	(via
		(at 361.7976 -249.428)
		(size 0.5588)
		(drill 0.3048)
		(layers "F.Cu" "B.Cu")
		(net "P12V_B")
	)
	(via
		(at 170.525186 -255.616964)
		(size 0.6604)
		(drill 0.3302)
		(layers "F.Cu" "B.Cu")
		(net "P12V_B")
	)
	(via
		(at 139.7635 -16.637)
		(size 0.5588)
		(drill 0.3048)
		(layers "F.Cu" "B.Cu")
		(net "P12V_B")
	)
	(via
		(at 108.458 -256.794)
		(size 0.5588)
		(drill 0.3048)
		(layers "F.Cu" "B.Cu")
		(net "P12V_B")
	)
	(via
		(at 262.792972 -335.785206)
		(size 0.8636)
		(drill 0.508)
		(layers "F.Cu" "B.Cu")
		(net "P12V_B")
	)
	(via
		(at 279.571958 -108.77296)
		(size 0.7112)
		(drill 0.4064)
		(layers "F.Cu" "B.Cu")
		(net "P12V_B")
	)
	(via
		(at 463.042 -130.556)
		(size 0.5588)
		(drill 0.3048)
		(layers "F.Cu" "B.Cu")
		(net "P12V_B")
	)
	(via
		(at 262.838946 -340.406482)
		(size 0.8636)
		(drill 0.508)
		(layers "F.Cu" "B.Cu")
		(net "P12V_B")
	)
	(via
		(at 138.938 -256.794)
		(size 0.5588)
		(drill 0.3048)
		(layers "F.Cu" "B.Cu")
		(net "P12V_B")
	)
	(via
		(at 442.686186 -123.115578)
		(size 0.5588)
		(drill 0.3048)
		(layers "F.Cu" "B.Cu")
		(net "P12V_B")
	)
	(via
		(at 206.5274 -310.481472)
		(size 0.7112)
		(drill 0.4064)
		(layers "F.Cu" "B.Cu")
		(net "P12V_B")
	)
	(via
		(at 171.577 -256.794)
		(size 0.5588)
		(drill 0.3048)
		(layers "F.Cu" "B.Cu")
		(net "P12V_B")
	)
	(via
		(at 393.4206 -249.301)
		(size 0.5588)
		(drill 0.3048)
		(layers "F.Cu" "B.Cu")
		(net "P12V_B")
	)
	(via
		(at 205.3082 -309.262272)
		(size 0.7112)
		(drill 0.4064)
		(layers "F.Cu" "B.Cu")
		(net "P12V_B")
	)
	(via
		(at 264.7696 -342.773)
		(size 0.8636)
		(drill 0.508)
		(layers "F.Cu" "B.Cu")
		(net "P12V_B")
	)
	(via
		(at 264.9982 -340.995)
		(size 0.8636)
		(drill 0.508)
		(layers "F.Cu" "B.Cu")
		(net "P12V_B")
	)
	(via
		(at 258.474972 -373.59971)
		(size 0.5588)
		(drill 0.3048)
		(layers "F.Cu" "B.Cu")
		(net "P12V_B")
	)
	(via
		(at 141.224 -256.794)
		(size 0.5588)
		(drill 0.3048)
		(layers "F.Cu" "B.Cu")
		(net "P12V_B")
	)
	(via
		(at 269.650972 -334.413606)
		(size 0.8636)
		(drill 0.508)
		(layers "F.Cu" "B.Cu")
		(net "P12V_B")
	)
	(via
		(at 208.798922 -106.620056)
		(size 0.7112)
		(drill 0.4064)
		(layers "F.Cu" "B.Cu")
		(net "P12V_B")
	)
	(via
		(at 270.888714 -335.275682)
		(size 0.8636)
		(drill 0.508)
		(layers "F.Cu" "B.Cu")
		(net "P12V_B")
	)
	(via
		(at 259.08 -292.989)
		(size 0.5588)
		(drill 0.3048)
		(layers "F.Cu" "B.Cu")
		(net "P12V_B")
	)
	(via
		(at 463.423 -143.891)
		(size 0.5588)
		(drill 0.3048)
		(layers "F.Cu" "B.Cu")
		(net "P12V_B")
	)
	(via
		(at 397.891 -258.826)
		(size 0.5588)
		(drill 0.3048)
		(layers "F.Cu" "B.Cu")
		(net "P12V_B")
	)
	(via
		(at 109.241082 -31.078678)
		(size 0.5588)
		(drill 0.3048)
		(layers "F.Cu" "B.Cu")
		(net "P12V_B")
	)
	(via
		(at 138.811 -145.288)
		(size 0.5588)
		(drill 0.3048)
		(layers "F.Cu" "B.Cu")
		(net "P12V_B")
	)
	(via
		(at 424.8912 -249.2248)
		(size 0.5588)
		(drill 0.3048)
		(layers "F.Cu" "B.Cu")
		(net "P12V_B")
	)
	(via
		(at 461.584802 -233.43235)
		(size 0.5588)
		(drill 0.3048)
		(layers "F.Cu" "B.Cu")
		(net "P12V_B")
	)
	(via
		(at 361.823 -134.3914)
		(size 0.5588)
		(drill 0.3048)
		(layers "F.Cu" "B.Cu")
		(net "P12V_B")
	)
	(via
		(at 252.43282 -373.726456)
		(size 0.5588)
		(drill 0.3048)
		(layers "F.Cu" "B.Cu")
		(net "P12V_B")
	)
	(via
		(at 139.8778 -248.793)
		(size 0.5588)
		(drill 0.3048)
		(layers "F.Cu" "B.Cu")
		(net "P12V_B")
	)
	(via
		(at 78.258416 -141.463522)
		(size 0.5588)
		(drill 0.3048)
		(layers "F.Cu" "B.Cu")
		(net "P12V_B")
	)
	(via
		(at 424.9166 -19.4056)
		(size 0.5588)
		(drill 0.3048)
		(layers "F.Cu" "B.Cu")
		(net "P12V_B")
	)
	(via
		(at 181.356 -9.7155)
		(size 0.5588)
		(drill 0.3048)
		(layers "F.Cu" "B.Cu")
		(net "P12V_B")
	)
	(via
		(at 32.4104 -108.6866)
		(size 0.7112)
		(drill 0.4064)
		(layers "F.Cu" "B.Cu")
		(net "P12V_B")
	)
	(via
		(at 266.039854 -349.271336)
		(size 0.8636)
		(drill 0.508)
		(layers "F.Cu" "B.Cu")
		(net "P12V_B")
	)
	(via
		(at 46.609 -256.794)
		(size 0.5588)
		(drill 0.3048)
		(layers "F.Cu" "B.Cu")
		(net "P12V_B")
	)
	(via
		(at 208.8896 -149.191472)
		(size 0.7112)
		(drill 0.4064)
		(layers "F.Cu" "B.Cu")
		(net "P12V_B")
	)
	(via
		(at 441.035186 -220.702378)
		(size 0.7112)
		(drill 0.4064)
		(layers "F.Cu" "B.Cu")
		(net "P12V_B")
	)
	(via
		(at 172.847 -20.3835)
		(size 0.5588)
		(drill 0.3048)
		(layers "F.Cu" "B.Cu")
		(net "P12V_B")
	)
	(via
		(at 422.289986 -109.120178)
		(size 0.7112)
		(drill 0.4064)
		(layers "F.Cu" "B.Cu")
		(net "P12V_B")
	)
	(via
		(at 75.819 -26.797)
		(size 0.5588)
		(drill 0.3048)
		(layers "F.Cu" "B.Cu")
		(net "P12V_B")
	)
	(via
		(at 470.027 -256.794)
		(size 0.5588)
		(drill 0.3048)
		(layers "F.Cu" "B.Cu")
		(net "P12V_B")
	)
	(via
		(at 265.3538 -339.217)
		(size 0.8636)
		(drill 0.508)
		(layers "F.Cu" "B.Cu")
		(net "P12V_B")
	)
	(via
		(at 337.312 -143.891)
		(size 0.5588)
		(drill 0.3048)
		(layers "F.Cu" "B.Cu")
		(net "P12V_B")
	)
	(via
		(at 280.791158 -108.77296)
		(size 0.7112)
		(drill 0.4064)
		(layers "F.Cu" "B.Cu")
		(net "P12V_B")
	)
	(via
		(at 79.4385 -252.222)
		(size 0.5588)
		(drill 0.3048)
		(layers "F.Cu" "B.Cu")
		(net "P12V_B")
	)
	(via
		(at 334.772 -143.891)
		(size 0.5588)
		(drill 0.3048)
		(layers "F.Cu" "B.Cu")
		(net "P12V_B")
	)
	(via
		(at 176.6824 -8.636)
		(size 0.5588)
		(drill 0.3048)
		(layers "F.Cu" "B.Cu")
		(net "P12V_B")
	)
	(via
		(at 268.6304 -202.311)
		(size 0.7112)
		(drill 0.4064)
		(layers "F.Cu" "B.Cu")
		(net "P12V_B")
	)
	(via
		(at 269.514574 -344.108786)
		(size 0.8636)
		(drill 0.508)
		(layers "F.Cu" "B.Cu")
		(net "P12V_B")
	)
	(via
		(at 470.027 -141.732)
		(size 0.5588)
		(drill 0.3048)
		(layers "F.Cu" "B.Cu")
		(net "P12V_B")
	)
	(via
		(at 262.73252 -347.337126)
		(size 0.8636)
		(drill 0.508)
		(layers "F.Cu" "B.Cu")
		(net "P12V_B")
	)
	(via
		(at 264.164572 -334.413606)
		(size 0.8636)
		(drill 0.508)
		(layers "F.Cu" "B.Cu")
		(net "P12V_B")
	)
	(via
		(at 13.5255 -131.572)
		(size 0.5588)
		(drill 0.3048)
		(layers "F.Cu" "B.Cu")
		(net "P12V_B")
	)
	(via
		(at 462.153 -258.826)
		(size 0.5588)
		(drill 0.3048)
		(layers "F.Cu" "B.Cu")
		(net "P12V_B")
	)
	(via
		(at 429.387 -143.891)
		(size 0.5588)
		(drill 0.3048)
		(layers "F.Cu" "B.Cu")
		(net "P12V_B")
	)
	(via
		(at 109.601 -141.732)
		(size 0.5588)
		(drill 0.3048)
		(layers "F.Cu" "B.Cu")
		(net "P12V_B")
	)
	(via
		(at 271.0688 -202.311)
		(size 0.7112)
		(drill 0.4064)
		(layers "F.Cu" "B.Cu")
		(net "P12V_B")
	)
	(via
		(at 46.609 -19.1643)
		(size 0.5588)
		(drill 0.3048)
		(layers "F.Cu" "B.Cu")
		(net "P12V_B")
	)
	(via
		(at 336.931 -130.556)
		(size 0.5588)
		(drill 0.3048)
		(layers "F.Cu" "B.Cu")
		(net "P12V_B")
	)
	(via
		(at 367.538 -143.891)
		(size 0.5588)
		(drill 0.3048)
		(layers "F.Cu" "B.Cu")
		(net "P12V_B")
	)
	(via
		(at 16.3195 -252.222)
		(size 0.5588)
		(drill 0.3048)
		(layers "F.Cu" "B.Cu")
		(net "P12V_B")
	)
	(via
		(at 368.427 -130.556)
		(size 0.5588)
		(drill 0.3048)
		(layers "F.Cu" "B.Cu")
		(net "P12V_B")
	)
	(via
		(at 77.115416 -141.463522)
		(size 0.5588)
		(drill 0.3048)
		(layers "F.Cu" "B.Cu")
		(net "P12V_B")
	)
	(via
		(at 431.9016 -28.9814)
		(size 0.5588)
		(drill 0.3048)
		(layers "F.Cu" "B.Cu")
		(net "P12V_B")
	)
	(via
		(at 468.884 -141.732)
		(size 0.5588)
		(drill 0.3048)
		(layers "F.Cu" "B.Cu")
		(net "P12V_B")
	)
	(via
		(at 431.546 -15.494)
		(size 0.5588)
		(drill 0.3048)
		(layers "F.Cu" "B.Cu")
		(net "P12V_B")
	)
	(via
		(at 174.0535 -252.222)
		(size 0.5588)
		(drill 0.3048)
		(layers "F.Cu" "B.Cu")
		(net "P12V_B")
	)
	(via
		(at 270.886174 -342.737186)
		(size 0.8636)
		(drill 0.508)
		(layers "F.Cu" "B.Cu")
		(net "P12V_B")
	)
	(via
		(at 270.886174 -341.365586)
		(size 0.8636)
		(drill 0.508)
		(layers "F.Cu" "B.Cu")
		(net "P12V_B")
	)
	(via
		(at 471.3605 -137.16)
		(size 0.5588)
		(drill 0.3048)
		(layers "F.Cu" "B.Cu")
		(net "P12V_B")
	)
	(via
		(at 14.4145 -15.748)
		(size 0.5588)
		(drill 0.3048)
		(layers "F.Cu" "B.Cu")
		(net "P12V_B")
	)
	(via
		(at 200.4822 -310.481472)
		(size 0.7112)
		(drill 0.4064)
		(layers "F.Cu" "B.Cu")
		(net "P12V_B")
	)
	(via
		(at 467.2965 -134.6835)
		(size 0.5588)
		(drill 0.3048)
		(layers "F.Cu" "B.Cu")
		(net "P12V_B")
	)
	(via
		(at 281.7876 -310.1594)
		(size 0.7112)
		(drill 0.4064)
		(layers "F.Cu" "B.Cu")
		(net "P12V_B")
	)
	(via
		(at 270.886174 -344.108786)
		(size 0.8636)
		(drill 0.508)
		(layers "F.Cu" "B.Cu")
		(net "P12V_B")
	)
	(via
		(at 472.567 -9.6774)
		(size 0.5588)
		(drill 0.3048)
		(layers "F.Cu" "B.Cu")
		(net "P12V_B")
	)
	(via
		(at 174.0535 -137.16)
		(size 0.5588)
		(drill 0.3048)
		(layers "F.Cu" "B.Cu")
		(net "P12V_B")
	)
	(via
		(at 368.808 -258.826)
		(size 0.5588)
		(drill 0.3048)
		(layers "F.Cu" "B.Cu")
		(net "P12V_B")
	)
	(via
		(at 205.141322 -107.813856)
		(size 0.7112)
		(drill 0.4064)
		(layers "F.Cu" "B.Cu")
		(net "P12V_B")
	)
	(via
		(at 210.018122 -109.058456)
		(size 0.7112)
		(drill 0.4064)
		(layers "F.Cu" "B.Cu")
		(net "P12V_B")
	)
	(via
		(at 269.514574 -345.480386)
		(size 0.8636)
		(drill 0.508)
		(layers "F.Cu" "B.Cu")
		(net "P12V_B")
	)
	(via
		(at 204.0128 -147.946872)
		(size 0.7112)
		(drill 0.4064)
		(layers "F.Cu" "B.Cu")
		(net "P12V_B")
	)
	(via
		(at 286.639 -311.3278)
		(size 0.7112)
		(drill 0.4064)
		(layers "F.Cu" "B.Cu")
		(net "P12V_B")
	)
	(via
		(at 460.883 -143.891)
		(size 0.5588)
		(drill 0.3048)
		(layers "F.Cu" "B.Cu")
		(net "P12V_B")
	)
	(via
		(at 405.4856 -33.2994)
		(size 0.5588)
		(drill 0.3048)
		(layers "F.Cu" "B.Cu")
		(net "P12V_B")
	)
	(via
		(at 141.224 -26.797)
		(size 0.5588)
		(drill 0.3048)
		(layers "F.Cu" "B.Cu")
		(net "P12V_B")
	)
	(via
		(at 6.6802 -221.9198)
		(size 0.7112)
		(drill 0.4064)
		(layers "F.Cu" "B.Cu")
		(net "P12V_B")
	)
	(via
		(at 400.431 -258.826)
		(size 0.5588)
		(drill 0.3048)
		(layers "F.Cu" "B.Cu")
		(net "P12V_B")
	)
	(via
		(at 171.806108 -141.69644)
		(size 0.5588)
		(drill 0.3048)
		(layers "F.Cu" "B.Cu")
		(net "P12V_B")
	)
	(via
		(at 79.4385 -136.2202)
		(size 0.5588)
		(drill 0.3048)
		(layers "F.Cu" "B.Cu")
		(net "P12V_B")
	)
	(via
		(at 269.514574 -338.622386)
		(size 0.8636)
		(drill 0.508)
		(layers "F.Cu" "B.Cu")
		(net "P12V_B")
	)
	(via
		(at 139.965176 -145.325846)
		(size 0.5588)
		(drill 0.3048)
		(layers "F.Cu" "B.Cu")
		(net "P12V_B")
	)
	(via
		(at 109.601 -256.794)
		(size 0.5588)
		(drill 0.3048)
		(layers "F.Cu" "B.Cu")
		(net "P12V_B")
	)
	(via
		(at 270.886174 -338.622386)
		(size 0.8636)
		(drill 0.508)
		(layers "F.Cu" "B.Cu")
		(net "P12V_B")
	)
	(via
		(at 50.4952 -8.636)
		(size 0.5588)
		(drill 0.3048)
		(layers "F.Cu" "B.Cu")
		(net "P12V_B")
	)
	(via
		(at 107.315 -141.732)
		(size 0.5588)
		(drill 0.3048)
		(layers "F.Cu" "B.Cu")
		(net "P12V_B")
	)
	(via
		(at 263.53516 -341.620856)
		(size 0.8636)
		(drill 0.508)
		(layers "F.Cu" "B.Cu")
		(net "P12V_B")
	)
	(via
		(at 468.8586 -19.6342)
		(size 0.5588)
		(drill 0.3048)
		(layers "F.Cu" "B.Cu")
		(net "P12V_B")
	)
	(via
		(at 266.556998 -347.272102)
		(size 0.6604)
		(drill 0.3302)
		(layers "F.Cu" "B.Cu")
		(net "P12V_B")
	)
	(via
		(at 47.9425 -252.222)
		(size 0.5588)
		(drill 0.3048)
		(layers "F.Cu" "B.Cu")
		(net "P12V_B")
	)
	(via
		(at 424.9928 -134.366)
		(size 0.5588)
		(drill 0.3048)
		(layers "F.Cu" "B.Cu")
		(net "P12V_B")
	)
	(via
		(at 268.6304 -199.771)
		(size 0.7112)
		(drill 0.4064)
		(layers "F.Cu" "B.Cu")
		(net "P12V_B")
	)
	(via
		(at 399.161 -143.891)
		(size 0.5588)
		(drill 0.3048)
		(layers "F.Cu" "B.Cu")
		(net "P12V_B")
	)
	(via
		(at 257.683 -292.989)
		(size 0.5588)
		(drill 0.3048)
		(layers "F.Cu" "B.Cu")
		(net "P12V_B")
	)
	(via
		(at 393.2936 -134.3152)
		(size 0.5588)
		(drill 0.3048)
		(layers "F.Cu" "B.Cu")
		(net "P12V_B")
	)
	(via
		(at 463.042 -245.491)
		(size 0.5588)
		(drill 0.3048)
		(layers "F.Cu" "B.Cu")
		(net "P12V_B")
	)
	(via
		(at 268.6304 -201.041)
		(size 0.7112)
		(drill 0.4064)
		(layers "F.Cu" "B.Cu")
		(net "P12V_B")
	)
	(via
		(at 462.060036 -27.719528)
		(size 0.5588)
		(drill 0.3048)
		(layers "F.Cu" "B.Cu")
		(net "P12V_B")
	)
	(via
		(at 46.609 -20.3835)
		(size 0.5588)
		(drill 0.3048)
		(layers "F.Cu" "B.Cu")
		(net "P12V_B")
	)
	(via
		(at 334.772 -258.826)
		(size 0.5588)
		(drill 0.3048)
		(layers "F.Cu" "B.Cu")
		(net "P12V_B")
	)
	(via
		(at 142.5575 -137.16)
		(size 0.5588)
		(drill 0.3048)
		(layers "F.Cu" "B.Cu")
		(net "P12V_B")
	)
	(via
		(at 112.944402 -8.233918)
		(size 0.5588)
		(drill 0.3048)
		(layers "F.Cu" "B.Cu")
		(net "P12V_B")
	)
	(via
		(at 140.081 -26.797)
		(size 0.5588)
		(drill 0.3048)
		(layers "F.Cu" "B.Cu")
		(net "P12V_B")
	)
	(via
		(at 111.8616 -8.2296)
		(size 0.5588)
		(drill 0.3048)
		(layers "F.Cu" "B.Cu")
		(net "P12V_B")
	)
	(via
		(at 393.262866 -17.604486)
		(size 0.5588)
		(drill 0.3048)
		(layers "F.Cu" "B.Cu")
		(net "P12V_B")
	)
	(via
		(at 284.448758 -108.79836)
		(size 0.7112)
		(drill 0.4064)
		(layers "F.Cu" "B.Cu")
		(net "P12V_B")
	)
	(via
		(at 210.018122 -106.620056)
		(size 0.7112)
		(drill 0.4064)
		(layers "F.Cu" "B.Cu")
		(net "P12V_B")
	)
	(via
		(at 13.5255 -246.634)
		(size 0.5588)
		(drill 0.3048)
		(layers "F.Cu" "B.Cu")
		(net "P12V_B")
	)
	(via
		(at 13.843 -26.797)
		(size 0.5588)
		(drill 0.3048)
		(layers "F.Cu" "B.Cu")
		(net "P12V_B")
	)
	(via
		(at 257.048 -292.1)
		(size 0.5588)
		(drill 0.3048)
		(layers "F.Cu" "B.Cu")
		(net "P12V_B")
	)
	(via
		(at 366.268 -28.829)
		(size 0.5588)
		(drill 0.3048)
		(layers "F.Cu" "B.Cu")
		(net "P12V_B")
	)
	(via
		(at 138.938 -26.797)
		(size 0.5588)
		(drill 0.3048)
		(layers "F.Cu" "B.Cu")
		(net "P12V_B")
	)
	(via
		(at 172.949108 -141.69644)
		(size 0.5588)
		(drill 0.3048)
		(layers "F.Cu" "B.Cu")
		(net "P12V_B")
	)
	(via
		(at 25.974802 -233.43235)
		(size 0.5588)
		(drill 0.3048)
		(layers "F.Cu" "B.Cu")
		(net "P12V_B")
	)
	(via
		(at 170.434 -256.794)
		(size 0.5588)
		(drill 0.3048)
		(layers "F.Cu" "B.Cu")
		(net "P12V_B")
	)
	(via
		(at 5.461 -220.7006)
		(size 0.7112)
		(drill 0.4064)
		(layers "F.Cu" "B.Cu")
		(net "P12V_B")
	)
	(via
		(at 45.2374 -141.8844)
		(size 0.5588)
		(drill 0.3048)
		(layers "F.Cu" "B.Cu")
		(net "P12V_B")
	)
	(via
		(at 269.8496 -202.311)
		(size 0.7112)
		(drill 0.4064)
		(layers "F.Cu" "B.Cu")
		(net "P12V_B")
	)
	(via
		(at 265.536172 -333.042006)
		(size 0.8636)
		(drill 0.508)
		(layers "F.Cu" "B.Cu")
		(net "P12V_B")
	)
	(via
		(at 78.105 -256.794)
		(size 0.5588)
		(drill 0.3048)
		(layers "F.Cu" "B.Cu")
		(net "P12V_B")
	)
	(via
		(at 287.8582 -311.3278)
		(size 0.7112)
		(drill 0.4064)
		(layers "F.Cu" "B.Cu")
		(net "P12V_B")
	)
	(via
		(at 336.931 -245.491)
		(size 0.5588)
		(drill 0.3048)
		(layers "F.Cu" "B.Cu")
		(net "P12V_B")
	)
	(via
		(at 110.9345 -252.222)
		(size 0.5588)
		(drill 0.3048)
		(layers "F.Cu" "B.Cu")
		(net "P12V_B")
	)
	(via
		(at 330.4286 -249.3772)
		(size 0.5588)
		(drill 0.3048)
		(layers "F.Cu" "B.Cu")
		(net "P12V_B")
	)
	(via
		(at 270.886174 -349.595186)
		(size 0.8636)
		(drill 0.508)
		(layers "F.Cu" "B.Cu")
		(net "P12V_B")
	)
	(via
		(at 208.798922 -109.058456)
		(size 0.7112)
		(drill 0.4064)
		(layers "F.Cu" "B.Cu")
		(net "P12V_B")
	)
	(via
		(at 51.008026 -19.004026)
		(size 0.5588)
		(drill 0.3048)
		(layers "F.Cu" "B.Cu")
		(net "P12V_B")
	)
	(via
		(at 172.72 -256.794)
		(size 0.5588)
		(drill 0.3048)
		(layers "F.Cu" "B.Cu")
		(net "P12V_B")
	)
	(via
		(at 6.6802 -219.4814)
		(size 0.7112)
		(drill 0.4064)
		(layers "F.Cu" "B.Cu")
		(net "P12V_B")
	)
	(via
		(at 171.2595 -131.572)
		(size 0.5588)
		(drill 0.3048)
		(layers "F.Cu" "B.Cu")
		(net "P12V_B")
	)
	(via
		(at 422.289986 -110.339378)
		(size 0.7112)
		(drill 0.4064)
		(layers "F.Cu" "B.Cu")
		(net "P12V_B")
	)
	(via
		(at 368.151664 -142.918434)
		(size 0.6604)
		(drill 0.3302)
		(layers "F.Cu" "B.Cu")
		(net "P12V_B")
	)
	(via
		(at 269.514574 -348.223586)
		(size 0.8636)
		(drill 0.508)
		(layers "F.Cu" "B.Cu")
		(net "P12V_B")
	)
	(via
		(at 204.0128 -149.166072)
		(size 0.7112)
		(drill 0.4064)
		(layers "F.Cu" "B.Cu")
		(net "P12V_B")
	)
	(via
		(at 12.7 -256.794)
		(size 0.5588)
		(drill 0.3048)
		(layers "F.Cu" "B.Cu")
		(net "P12V_B")
	)
	(via
		(at 264.6934 -349.7834)
		(size 0.8636)
		(drill 0.508)
		(layers "F.Cu" "B.Cu")
		(net "P12V_B")
	)
	(via
		(at 31.1912 -108.6866)
		(size 0.7112)
		(drill 0.4064)
		(layers "F.Cu" "B.Cu")
		(net "P12V_B")
	)
	(via
		(at 463.1182 -22.5044)
		(size 0.5588)
		(drill 0.3048)
		(layers "F.Cu" "B.Cu")
		(net "P12V_B")
	)
	(via
		(at 269.514574 -339.993986)
		(size 0.8636)
		(drill 0.508)
		(layers "F.Cu" "B.Cu")
		(net "P12V_B")
	)
	(via
		(at 6.6802 -220.7006)
		(size 0.7112)
		(drill 0.4064)
		(layers "F.Cu" "B.Cu")
		(net "P12V_B")
	)
	(via
		(at 262.7884 -342.7984)
		(size 0.8636)
		(drill 0.508)
		(layers "F.Cu" "B.Cu")
		(net "P12V_B")
	)
	(via
		(at 207.6704 -149.191472)
		(size 0.7112)
		(drill 0.4064)
		(layers "F.Cu" "B.Cu")
		(net "P12V_B")
	)
	(via
		(at 76.961746 -26.797254)
		(size 0.5588)
		(drill 0.3048)
		(layers "F.Cu" "B.Cu")
		(net "P12V_B")
	)
	(via
		(at 463.169 -28.829)
		(size 0.5588)
		(drill 0.3048)
		(layers "F.Cu" "B.Cu")
		(net "P12V_B")
	)
	(via
		(at 367.538 -28.829)
		(size 0.5588)
		(drill 0.3048)
		(layers "F.Cu" "B.Cu")
		(net "P12V_B")
	)
	(via
		(at 264.164572 -333.042006)
		(size 0.8636)
		(drill 0.508)
		(layers "F.Cu" "B.Cu")
		(net "P12V_B")
	)
	(via
		(at 260.6294 -291.082984)
		(size 0.5588)
		(drill 0.3048)
		(layers "F.Cu" "B.Cu")
		(net "P12V_B")
	)
	(via
		(at 335.915 -28.829)
		(size 0.5588)
		(drill 0.3048)
		(layers "F.Cu" "B.Cu")
		(net "P12V_B")
	)
	(via
		(at 205.3082 -311.700672)
		(size 0.7112)
		(drill 0.4064)
		(layers "F.Cu" "B.Cu")
		(net "P12V_B")
	)
	(via
		(at 456.969876 -20.836382)
		(size 0.5588)
		(drill 0.3048)
		(layers "F.Cu" "B.Cu")
		(net "P12V_B")
	)
	(via
		(at 171.577 -20.32)
		(size 0.5588)
		(drill 0.3048)
		(layers "F.Cu" "B.Cu")
		(net "P12V_B")
	)
	(via
		(at 265.566144 -334.410812)
		(size 0.6604)
		(drill 0.3302)
		(layers "F.Cu" "B.Cu")
		(net "P12V_B")
	)
	(via
		(at 50.82286 -122.247406)
		(size 0.5588)
		(drill 0.3048)
		(layers "F.Cu" "B.Cu")
		(net "P12V_B")
	)
	(via
		(at 283.0068 -310.1594)
		(size 0.7112)
		(drill 0.4064)
		(layers "F.Cu" "B.Cu")
		(net "P12V_B")
	)
	(via
		(at 79.1972 -21.2598)
		(size 0.5588)
		(drill 0.3048)
		(layers "F.Cu" "B.Cu")
		(net "P12V_B")
	)
	(via
		(at 442.254386 -220.702378)
		(size 0.7112)
		(drill 0.4064)
		(layers "F.Cu" "B.Cu")
		(net "P12V_B")
	)
	(via
		(at 170.7007 -140.348462)
		(size 0.6604)
		(drill 0.3302)
		(layers "F.Cu" "B.Cu")
		(net "P12V_B")
	)
	(via
		(at 431.277268 -27.924252)
		(size 0.6604)
		(drill 0.3302)
		(layers "F.Cu" "B.Cu")
		(net "P12V_B")
	)
	(via
		(at 55.118 -9.7155)
		(size 0.5588)
		(drill 0.3048)
		(layers "F.Cu" "B.Cu")
		(net "P12V_B")
	)
	(via
		(at 279.571958 -107.55376)
		(size 0.7112)
		(drill 0.4064)
		(layers "F.Cu" "B.Cu")
		(net "P12V_B")
	)
	(via
		(at 367.538 -258.826)
		(size 0.5588)
		(drill 0.3048)
		(layers "F.Cu" "B.Cu")
		(net "P12V_B")
	)
	(via
		(at 201.7014 -310.481472)
		(size 0.7112)
		(drill 0.4064)
		(layers "F.Cu" "B.Cu")
		(net "P12V_B")
	)
	(via
		(at 5.461 -219.4814)
		(size 0.7112)
		(drill 0.4064)
		(layers "F.Cu" "B.Cu")
		(net "P12V_B")
	)
	(via
		(at 269.514574 -346.851986)
		(size 0.8636)
		(drill 0.508)
		(layers "F.Cu" "B.Cu")
		(net "P12V_B")
	)
	(via
		(at 475.134178 -19.277838)
		(size 0.5588)
		(drill 0.3048)
		(layers "F.Cu" "B.Cu")
		(net "P12V_B")
	)
	(via
		(at 430.6316 -28.9814)
		(size 0.5588)
		(drill 0.3048)
		(layers "F.Cu" "B.Cu")
		(net "P12V_B")
	)
	(via
		(at 5.461 -221.9198)
		(size 0.7112)
		(drill 0.4064)
		(layers "F.Cu" "B.Cu")
		(net "P12V_B")
	)
	(via
		(at 32.4104 -109.9058)
		(size 0.7112)
		(drill 0.4064)
		(layers "F.Cu" "B.Cu")
		(net "P12V_B")
	)
	(via
		(at 463.423 -258.826)
		(size 0.5588)
		(drill 0.3048)
		(layers "F.Cu" "B.Cu")
		(net "P12V_B")
	)
	(via
		(at 141.051534 -145.38325)
		(size 0.5588)
		(drill 0.3048)
		(layers "F.Cu" "B.Cu")
		(net "P12V_B")
	)
	(via
		(at 442.254386 -221.921578)
		(size 0.7112)
		(drill 0.4064)
		(layers "F.Cu" "B.Cu")
		(net "P12V_B")
	)
	(via
		(at 208.8896 -147.972272)
		(size 0.7112)
		(drill 0.4064)
		(layers "F.Cu" "B.Cu")
		(net "P12V_B")
	)
	(via
		(at 269.514574 -342.737186)
		(size 0.8636)
		(drill 0.508)
		(layers "F.Cu" "B.Cu")
		(net "P12V_B")
	)
	(via
		(at 45.466 -256.794)
		(size 0.5588)
		(drill 0.3048)
		(layers "F.Cu" "B.Cu")
		(net "P12V_B")
	)
	(via
		(at 270.886174 -348.223586)
		(size 0.8636)
		(drill 0.508)
		(layers "F.Cu" "B.Cu")
		(net "P12V_B")
	)
	(via
		(at 16.3195 -22.225)
		(size 0.5588)
		(drill 0.3048)
		(layers "F.Cu" "B.Cu")
		(net "P12V_B")
	)
	(via
		(at 286.639 -308.8894)
		(size 0.7112)
		(drill 0.4064)
		(layers "F.Cu" "B.Cu")
		(net "P12V_B")
	)
	(via
		(at 265.536172 -335.785206)
		(size 0.8636)
		(drill 0.508)
		(layers "F.Cu" "B.Cu")
		(net "P12V_B")
	)
	(via
		(at 75.972416 -141.463522)
		(size 0.5588)
		(drill 0.3048)
		(layers "F.Cu" "B.Cu")
		(net "P12V_B")
	)
	(via
		(at 285.667958 -107.57916)
		(size 0.7112)
		(drill 0.4064)
		(layers "F.Cu" "B.Cu")
		(net "P12V_B")
	)
	(via
		(at 287.8582 -310.1086)
		(size 0.7112)
		(drill 0.4064)
		(layers "F.Cu" "B.Cu")
		(net "P12V_B")
	)
	(via
		(at 202.7936 -146.727672)
		(size 0.7112)
		(drill 0.4064)
		(layers "F.Cu" "B.Cu")
		(net "P12V_B")
	)
	(via
		(at 285.667958 -106.35996)
		(size 0.7112)
		(drill 0.4064)
		(layers "F.Cu" "B.Cu")
		(net "P12V_B")
	)
	(via
		(at 205.141322 -109.033056)
		(size 0.7112)
		(drill 0.4064)
		(layers "F.Cu" "B.Cu")
		(net "P12V_B")
	)
	(via
		(at 268.6304 -198.501)
		(size 0.7112)
		(drill 0.4064)
		(layers "F.Cu" "B.Cu")
		(net "P12V_B")
	)
	(via
		(at 31.1912 -111.125)
		(size 0.7112)
		(drill 0.4064)
		(layers "F.Cu" "B.Cu")
		(net "P12V_B")
	)
	(via
		(at 269.650972 -333.042006)
		(size 0.8636)
		(drill 0.508)
		(layers "F.Cu" "B.Cu")
		(net "P12V_B")
	)
	(via
		(at 431.546 -130.556)
		(size 0.5588)
		(drill 0.3048)
		(layers "F.Cu" "B.Cu")
		(net "P12V_B")
	)
	(via
		(at 460.883 -258.826)
		(size 0.5588)
		(drill 0.3048)
		(layers "F.Cu" "B.Cu")
		(net "P12V_B")
	)
	(via
		(at 204.0128 -146.727672)
		(size 0.7112)
		(drill 0.4064)
		(layers "F.Cu" "B.Cu")
		(net "P12V_B")
	)
	(via
		(at 170.307 -20.32)
		(size 0.5588)
		(drill 0.3048)
		(layers "F.Cu" "B.Cu")
		(net "P12V_B")
	)
	(via
		(at 108.077 -10.4775)
		(size 0.5588)
		(drill 0.3048)
		(layers "F.Cu" "B.Cu")
		(net "P12V_B")
	)
	(via
		(at 44.0944 -141.8844)
		(size 0.5588)
		(drill 0.3048)
		(layers "F.Cu" "B.Cu")
		(net "P12V_B")
	)
	(via
		(at 368.427 -15.494)
		(size 0.5588)
		(drill 0.3048)
		(layers "F.Cu" "B.Cu")
		(net "P12V_B")
	)
	(via
		(at 260.991096 -241.034316)
		(size 0.5588)
		(drill 0.3048)
		(layers "F.Cu" "B.Cu")
		(net "P12V_B")
	)
	(via
		(at 284.448758 -106.35996)
		(size 0.7112)
		(drill 0.4064)
		(layers "F.Cu" "B.Cu")
		(net "P12V_B")
	)
	(via
		(at 74.5998 -26.797)
		(size 0.5588)
		(drill 0.3048)
		(layers "F.Cu" "B.Cu")
		(net "P12V_B")
	)
	(via
		(at 108.458 -141.732)
		(size 0.5588)
		(drill 0.3048)
		(layers "F.Cu" "B.Cu")
		(net "P12V_B")
	)
	(via
		(at 142.5575 -22.225)
		(size 0.5588)
		(drill 0.3048)
		(layers "F.Cu" "B.Cu")
		(net "P12V_B")
	)
	(via
		(at 337.058 -28.829)
		(size 0.5588)
		(drill 0.3048)
		(layers "F.Cu" "B.Cu")
		(net "P12V_B")
	)
	(via
		(at 12.7 -26.797)
		(size 0.5588)
		(drill 0.3048)
		(layers "F.Cu" "B.Cu")
		(net "P12V_B")
	)
	(via
		(at 263.3726 -346.1004)
		(size 0.8636)
		(drill 0.508)
		(layers "F.Cu" "B.Cu")
		(net "P12V_B")
	)
	(via
		(at 262.792972 -334.413606)
		(size 0.8636)
		(drill 0.508)
		(layers "F.Cu" "B.Cu")
		(net "P12V_B")
	)
	(via
		(at 269.8496 -201.041)
		(size 0.7112)
		(drill 0.4064)
		(layers "F.Cu" "B.Cu")
		(net "P12V_B")
	)
	(via
		(at 75.819 -256.794)
		(size 0.5588)
		(drill 0.3048)
		(layers "F.Cu" "B.Cu")
		(net "P12V_B")
	)
	(via
		(at 335.0514 -12.0396)
		(size 0.5588)
		(drill 0.3048)
		(layers "F.Cu" "B.Cu")
		(net "P12V_B")
	)
	(via
		(at 472.1987 -4.826)
		(size 0.5588)
		(drill 0.3048)
		(layers "F.Cu" "B.Cu")
		(net "P12V_B")
	)
	(via
		(at 139.249912 -25.653238)
		(size 0.6604)
		(drill 0.3302)
		(layers "F.Cu" "B.Cu")
		(net "P12V_B")
	)
	(via
		(at 430.657 -143.891)
		(size 0.5588)
		(drill 0.3048)
		(layers "F.Cu" "B.Cu")
		(net "P12V_B")
	)
	(via
		(at 269.514574 -341.365586)
		(size 0.8636)
		(drill 0.508)
		(layers "F.Cu" "B.Cu")
		(net "P12V_B")
	)
	(via
		(at 430.657 -258.826)
		(size 0.5588)
		(drill 0.3048)
		(layers "F.Cu" "B.Cu")
		(net "P12V_B")
	)
	(via
		(at 202.7936 -147.946872)
		(size 0.7112)
		(drill 0.4064)
		(layers "F.Cu" "B.Cu")
		(net "P12V_B")
	)
	(via
		(at 76.962 -256.794)
		(size 0.5588)
		(drill 0.3048)
		(layers "F.Cu" "B.Cu")
		(net "P12V_B")
	)
	(via
		(at 12.7 -141.732)
		(size 0.5588)
		(drill 0.3048)
		(layers "F.Cu" "B.Cu")
		(net "P12V_B")
	)
	(via
		(at 14.986 -256.794)
		(size 0.5588)
		(drill 0.3048)
		(layers "F.Cu" "B.Cu")
		(net "P12V_B")
	)
	(via
		(at 210.018122 -107.839256)
		(size 0.7112)
		(drill 0.4064)
		(layers "F.Cu" "B.Cu")
		(net "P12V_B")
	)
	(via
		(at 266.907772 -334.413606)
		(size 0.8636)
		(drill 0.508)
		(layers "F.Cu" "B.Cu")
		(net "P12V_B")
	)
	(via
		(at 208.8896 -146.753072)
		(size 0.7112)
		(drill 0.4064)
		(layers "F.Cu" "B.Cu")
		(net "P12V_B")
	)
	(via
		(at 44.323 -256.794)
		(size 0.5588)
		(drill 0.3048)
		(layers "F.Cu" "B.Cu")
		(net "P12V_B")
	)
	(via
		(at 368.808 -28.829)
		(size 0.5588)
		(drill 0.3048)
		(layers "F.Cu" "B.Cu")
		(net "P12V_B")
	)
	(via
		(at 177.782728 -8.644636)
		(size 0.5588)
		(drill 0.3048)
		(layers "F.Cu" "B.Cu")
		(net "P12V_B")
	)
	(via
		(at 109.347 -10.4775)
		(size 0.5588)
		(drill 0.3048)
		(layers "F.Cu" "B.Cu")
		(net "P12V_B")
	)
	(via
		(at 467.2965 -249.682)
		(size 0.5588)
		(drill 0.3048)
		(layers "F.Cu" "B.Cu")
		(net "P12V_B")
	)
	(via
		(at 76.7334 -248.4628)
		(size 0.5588)
		(drill 0.3048)
		(layers "F.Cu" "B.Cu")
		(net "P12V_B")
	)
	(via
		(at 270.886174 -337.250786)
		(size 0.8636)
		(drill 0.508)
		(layers "F.Cu" "B.Cu")
		(net "P12V_B")
	)
	(via
		(at 205.141322 -106.594656)
		(size 0.7112)
		(drill 0.4064)
		(layers "F.Cu" "B.Cu")
		(net "P12V_B")
	)
	(via
		(at 262.7122 -349.8088)
		(size 0.8636)
		(drill 0.508)
		(layers "F.Cu" "B.Cu")
		(net "P12V_B")
	)
	(via
		(at 269.514574 -337.250786)
		(size 0.8636)
		(drill 0.508)
		(layers "F.Cu" "B.Cu")
		(net "P12V_B")
	)
	(via
		(at 47.8155 -137.16)
		(size 0.5588)
		(drill 0.3048)
		(layers "F.Cu" "B.Cu")
		(net "P12V_B")
	)
	(via
		(at 264.164572 -335.785206)
		(size 0.8636)
		(drill 0.508)
		(layers "F.Cu" "B.Cu")
		(net "P12V_B")
	)
	(via
		(at 337.312 -258.826)
		(size 0.5588)
		(drill 0.3048)
		(layers "F.Cu" "B.Cu")
		(net "P12V_B")
	)
	(via
		(at 201.7014 -311.700672)
		(size 0.7112)
		(drill 0.4064)
		(layers "F.Cu" "B.Cu")
		(net "P12V_B")
	)
	(via
		(at 258.445 -292.1)
		(size 0.5588)
		(drill 0.3048)
		(layers "F.Cu" "B.Cu")
		(net "P12V_B")
	)
	(via
		(at 366.268 -258.826)
		(size 0.5588)
		(drill 0.3048)
		(layers "F.Cu" "B.Cu")
		(net "P12V_B")
	)
	(via
		(at 467.741 -141.732)
		(size 0.5588)
		(drill 0.3048)
		(layers "F.Cu" "B.Cu")
		(net "P12V_B")
	)
	(via
		(at 262.0264 -339.1154)
		(size 0.8636)
		(drill 0.508)
		(layers "F.Cu" "B.Cu")
		(net "P12V_B")
	)
	(via
		(at 431.257456 -257.85191)
		(size 0.6604)
		(drill 0.3302)
		(layers "F.Cu" "B.Cu")
		(net "P12V_B")
	)
	(via
		(at 422.289986 -111.558578)
		(size 0.7112)
		(drill 0.4064)
		(layers "F.Cu" "B.Cu")
		(net "P12V_B")
	)
	(via
		(at 44.0944 -140.8176)
		(size 0.5588)
		(drill 0.3048)
		(layers "F.Cu" "B.Cu")
		(net "P12V_B")
	)
	(via
		(at 281.7876 -311.3786)
		(size 0.7112)
		(drill 0.4064)
		(layers "F.Cu" "B.Cu")
		(net "P12V_B")
	)
	(via
		(at 31.1912 -109.9058)
		(size 0.7112)
		(drill 0.4064)
		(layers "F.Cu" "B.Cu")
		(net "P12V_B")
	)
	(via
		(at 171.5516 -249.047)
		(size 0.5588)
		(drill 0.3048)
		(layers "F.Cu" "B.Cu")
		(net "P12V_B")
	)
	(via
		(at 107.315 -256.794)
		(size 0.5588)
		(drill 0.3048)
		(layers "F.Cu" "B.Cu")
		(net "P12V_B")
	)
	(via
		(at 467.741 -256.794)
		(size 0.5588)
		(drill 0.3048)
		(layers "F.Cu" "B.Cu")
		(net "P12V_B")
	)
	(via
		(at 76.6445 -16.637)
		(size 0.5588)
		(drill 0.3048)
		(layers "F.Cu" "B.Cu")
		(net "P12V_B")
	)
	(via
		(at 268.279372 -333.042006)
		(size 0.8636)
		(drill 0.508)
		(layers "F.Cu" "B.Cu")
		(net "P12V_B")
	)
	(via
		(at 268.6304 -197.231)
		(size 0.7112)
		(drill 0.4064)
		(layers "F.Cu" "B.Cu")
		(net "P12V_B")
	)
	(via
		(at 13.843 -141.732)
		(size 0.5588)
		(drill 0.3048)
		(layers "F.Cu" "B.Cu")
		(net "P12V_B")
	)
	(via
		(at 206.5274 -309.262272)
		(size 0.7112)
		(drill 0.4064)
		(layers "F.Cu" "B.Cu")
		(net "P12V_B")
	)
	(via
		(at 16.3195 -137.16)
		(size 0.5588)
		(drill 0.3048)
		(layers "F.Cu" "B.Cu")
		(net "P12V_B")
	)
	(via
		(at 45.2628 -248.3358)
		(size 0.5588)
		(drill 0.3048)
		(layers "F.Cu" "B.Cu")
		(net "P12V_B")
	)
	(via
		(at 265.2776 -346.2274)
		(size 0.8636)
		(drill 0.508)
		(layers "F.Cu" "B.Cu")
		(net "P12V_B")
	)
	(via
		(at 431.546 -245.491)
		(size 0.5588)
		(drill 0.3048)
		(layers "F.Cu" "B.Cu")
		(net "P12V_B")
	)
	(via
		(at 400.05 -245.491)
		(size 0.5588)
		(drill 0.3048)
		(layers "F.Cu" "B.Cu")
		(net "P12V_B")
	)
	(via
		(at 366.268 -143.891)
		(size 0.5588)
		(drill 0.3048)
		(layers "F.Cu" "B.Cu")
		(net "P12V_B")
	)
	(via
		(at 283.0068 -308.9402)
		(size 0.7112)
		(drill 0.4064)
		(layers "F.Cu" "B.Cu")
		(net "P12V_B")
	)
	(via
		(at 279.571958 -106.33456)
		(size 0.7112)
		(drill 0.4064)
		(layers "F.Cu" "B.Cu")
		(net "P12V_B")
	)
	(via
		(at 400.431 -143.891)
		(size 0.5588)
		(drill 0.3048)
		(layers "F.Cu" "B.Cu")
		(net "P12V_B")
	)
	(via
		(at 470.1032 -19.6088)
		(size 0.5588)
		(drill 0.3048)
		(layers "F.Cu" "B.Cu")
		(net "P12V_B")
	)
	(via
		(at 266.907772 -335.785206)
		(size 0.8636)
		(drill 0.508)
		(layers "F.Cu" "B.Cu")
		(net "P12V_B")
	)
	(via
		(at 46.3042 -141.8844)
		(size 0.5588)
		(drill 0.3048)
		(layers "F.Cu" "B.Cu")
		(net "P12V_B")
	)
	(via
		(at 467.5886 -19.6342)
		(size 0.5588)
		(drill 0.3048)
		(layers "F.Cu" "B.Cu")
		(net "P12V_B")
	)
	(via
		(at 281.7876 -308.9402)
		(size 0.7112)
		(drill 0.4064)
		(layers "F.Cu" "B.Cu")
		(net "P12V_B")
	)
	(via
		(at 429.387 -258.826)
		(size 0.5588)
		(drill 0.3048)
		(layers "F.Cu" "B.Cu")
		(net "P12V_B")
	)
	(via
		(at 368.427 -245.491)
		(size 0.5588)
		(drill 0.3048)
		(layers "F.Cu" "B.Cu")
		(net "P12V_B")
	)
	(via
		(at 423.509186 -110.339378)
		(size 0.7112)
		(drill 0.4064)
		(layers "F.Cu" "B.Cu")
		(net "P12V_B")
	)
	(via
		(at 262.792972 -333.042006)
		(size 0.8636)
		(drill 0.508)
		(layers "F.Cu" "B.Cu")
		(net "P12V_B")
	)
	(via
		(at 170.692572 -141.481556)
		(size 0.5588)
		(drill 0.3048)
		(layers "F.Cu" "B.Cu")
		(net "P12V_B")
	)
	(via
		(at 200.4822 -309.262272)
		(size 0.7112)
		(drill 0.4064)
		(layers "F.Cu" "B.Cu")
		(net "P12V_B")
	)
	(via
		(at 462.153 -143.891)
		(size 0.5588)
		(drill 0.3048)
		(layers "F.Cu" "B.Cu")
		(net "P12V_B")
	)
	(via
		(at 109.01934 -130.299968)
		(size 0.5588)
		(drill 0.3048)
		(layers "F.Cu" "B.Cu")
		(net "P12V_B")
	)
	(via
		(at 280.791158 -107.55376)
		(size 0.7112)
		(drill 0.4064)
		(layers "F.Cu" "B.Cu")
		(net "P12V_B")
	)
	(via
		(at 441.035186 -219.483178)
		(size 0.7112)
		(drill 0.4064)
		(layers "F.Cu" "B.Cu")
		(net "P12V_B")
	)
	(via
		(at 368.808 -143.891)
		(size 0.5588)
		(drill 0.3048)
		(layers "F.Cu" "B.Cu")
		(net "P12V_B")
	)
	(via
		(at 431.320194 -142.918434)
		(size 0.6604)
		(drill 0.3302)
		(layers "F.Cu" "B.Cu")
		(net "P12V_B")
	)
	(via
		(at 203.922122 -107.813856)
		(size 0.7112)
		(drill 0.4064)
		(layers "F.Cu" "B.Cu")
		(net "P12V_B")
	)
	(via
		(at 441.035186 -221.921578)
		(size 0.7112)
		(drill 0.4064)
		(layers "F.Cu" "B.Cu")
		(net "P12V_B")
	)
	(via
		(at 397.891 -143.891)
		(size 0.5588)
		(drill 0.3048)
		(layers "F.Cu" "B.Cu")
		(net "P12V_B")
	)
	(via
		(at 208.798922 -107.839256)
		(size 0.7112)
		(drill 0.4064)
		(layers "F.Cu" "B.Cu")
		(net "P12V_B")
	)
	(via
		(at 203.922122 -106.594656)
		(size 0.7112)
		(drill 0.4064)
		(layers "F.Cu" "B.Cu")
		(net "P12V_B")
	)
	(via
		(at 269.8496 -199.771)
		(size 0.7112)
		(drill 0.4064)
		(layers "F.Cu" "B.Cu")
		(net "P12V_B")
	)
	(via
		(at 263.426194 -348.58452)
		(size 0.8636)
		(drill 0.508)
		(layers "F.Cu" "B.Cu")
		(net "P12V_B")
	)
	(via
		(at 110.440216 -10.475468)
		(size 0.5588)
		(drill 0.3048)
		(layers "F.Cu" "B.Cu")
		(net "P12V_B")
	)
	(via
		(at 201.7014 -309.262272)
		(size 0.7112)
		(drill 0.4064)
		(layers "F.Cu" "B.Cu")
		(net "P12V_B")
	)
	(via
		(at 266.907772 -333.042006)
		(size 0.8636)
		(drill 0.508)
		(layers "F.Cu" "B.Cu")
		(net "P12V_B")
	)
	(via
		(at 405.4856 -32.0294)
		(size 0.5588)
		(drill 0.3048)
		(layers "F.Cu" "B.Cu")
		(net "P12V_B")
	)
	(via
		(at 400.05 -130.556)
		(size 0.5588)
		(drill 0.3048)
		(layers "F.Cu" "B.Cu")
		(net "P12V_B")
	)
	(via
		(at 51.581812 -8.628888)
		(size 0.5588)
		(drill 0.3048)
		(layers "F.Cu" "B.Cu")
		(net "P12V_B")
	)
	(via
		(at 336.042 -258.826)
		(size 0.5588)
		(drill 0.3048)
		(layers "F.Cu" "B.Cu")
		(net "P12V_B")
	)
	(via
		(at 266.192 -341.9094)
		(size 0.8636)
		(drill 0.508)
		(layers "F.Cu" "B.Cu")
		(net "P12V_B")
	)
	(via
		(at 110.9345 -136.7536)
		(size 0.5588)
		(drill 0.3048)
		(layers "F.Cu" "B.Cu")
		(net "P12V_B")
	)
	(via
		(at 142.5575 -252.222)
		(size 0.5588)
		(drill 0.3048)
		(layers "F.Cu" "B.Cu")
		(net "P12V_B")
	)
	(via
		(at 261.9502 -346.1258)
		(size 0.8636)
		(drill 0.508)
		(layers "F.Cu" "B.Cu")
		(net "P12V_B")
	)
	(via
		(at 139.7635 -131.572)
		(size 0.5588)
		(drill 0.3048)
		(layers "F.Cu" "B.Cu")
		(net "P12V_B")
	)
	(via
		(at 287.8582 -308.8894)
		(size 0.7112)
		(drill 0.4064)
		(layers "F.Cu" "B.Cu")
		(net "P12V_B")
	)
	(via
		(at 283.0068 -311.3786)
		(size 0.7112)
		(drill 0.4064)
		(layers "F.Cu" "B.Cu")
		(net "P12V_B")
	)
	(via
		(at 334.645 -28.829)
		(size 0.5588)
		(drill 0.3048)
		(layers "F.Cu" "B.Cu")
		(net "P12V_B")
	)
	(via
		(at 456.5396 -134.3152)
		(size 0.5588)
		(drill 0.3048)
		(layers "F.Cu" "B.Cu")
		(net "P12V_B")
	)
	(via
		(at 456.4126 -249.1994)
		(size 0.5588)
		(drill 0.3048)
		(layers "F.Cu" "B.Cu")
		(net "P12V_B")
	)
	(via
		(at 330.2254 -134.62)
		(size 0.5588)
		(drill 0.3048)
		(layers "F.Cu" "B.Cu")
		(net "P12V_B")
	)
	(via
		(at 270.886174 -346.851986)
		(size 0.8636)
		(drill 0.508)
		(layers "F.Cu" "B.Cu")
		(net "P12V_B")
	)
	(via
		(at 270.867378 -333.748888)
		(size 0.8636)
		(drill 0.508)
		(layers "F.Cu" "B.Cu")
		(net "P12V_B")
	)
	(via
		(at 45.339 -20.32)
		(size 0.5588)
		(drill 0.3048)
		(layers "F.Cu" "B.Cu")
		(net "P12V_B")
	)
	(via
		(at 271.0688 -199.771)
		(size 0.7112)
		(drill 0.4064)
		(layers "F.Cu" "B.Cu")
		(net "P12V_B")
	)
	(via
		(at 270.886174 -339.993986)
		(size 0.8636)
		(drill 0.508)
		(layers "F.Cu" "B.Cu")
		(net "P12V_B")
	)
	(via
		(at 368.118644 -27.804872)
		(size 0.6604)
		(drill 0.3302)
		(layers "F.Cu" "B.Cu")
		(net "P12V_B")
	)
	(via
		(at 364.6805 -18.7325)
		(size 0.5588)
		(drill 0.3048)
		(layers "F.Cu" "B.Cu")
		(net "P12V_B")
	)
	(via
		(at 269.8496 -198.501)
		(size 0.7112)
		(drill 0.4064)
		(layers "F.Cu" "B.Cu")
		(net "P12V_B")
	)
	(via
		(at 284.448758 -107.57916)
		(size 0.7112)
		(drill 0.4064)
		(layers "F.Cu" "B.Cu")
		(net "P12V_B")
	)
	(via
		(at 329.438 -17.399)
		(size 0.5588)
		(drill 0.3048)
		(layers "F.Cu" "B.Cu")
		(net "P12V_B")
	)
	(via
		(at 269.295372 -335.785206)
		(size 0.8636)
		(drill 0.508)
		(layers "F.Cu" "B.Cu")
		(net "P12V_B")
	)
	(via
		(at 431.927 -258.826)
		(size 0.5588)
		(drill 0.3048)
		(layers "F.Cu" "B.Cu")
		(net "P12V_B")
	)
	(via
		(at 285.667958 -108.79836)
		(size 0.7112)
		(drill 0.4064)
		(layers "F.Cu" "B.Cu")
		(net "P12V_B")
	)
	(via
		(at 207.6704 -146.753072)
		(size 0.7112)
		(drill 0.4064)
		(layers "F.Cu" "B.Cu")
		(net "P12V_B")
	)
	(via
		(at 268.5796 -195.9864)
		(size 0.7112)
		(drill 0.4064)
		(layers "F.Cu" "B.Cu")
		(net "P12V_B")
	)
	(via
		(at 257.048 -94.327726)
		(size 0.7112)
		(drill 0.4064)
		(layers "F.Cu" "B.Cu")
		(net "P12V_B")
	)
	(via
		(at 256.107692 -353.840034)
		(size 0.8636)
		(drill 0.508)
		(layers "F.Cu" "B.Cu")
		(net "MB3_P12V_IN_R")
	)
	(via
		(at 258.172966 -338.820506)
		(size 0.8636)
		(drill 0.508)
		(layers "F.Cu" "B.Cu")
		(net "MB3_P12V_IN_R")
	)
	(via
		(at 256.8194 -331.5462)
		(size 0.8636)
		(drill 0.508)
		(layers "F.Cu" "B.Cu")
		(net "MB3_P12V_IN_R")
	)
	(via
		(at 253.4666 -344.7796)
		(size 0.8636)
		(drill 0.508)
		(layers "F.Cu" "B.Cu")
		(net "MB3_P12V_IN_R")
	)
	(via
		(at 251.9172 -331.0636)
		(size 0.8636)
		(drill 0.508)
		(layers "F.Cu" "B.Cu")
		(net "MB3_P12V_IN_R")
	)
	(via
		(at 252.095 -339.2932)
		(size 0.8636)
		(drill 0.508)
		(layers "F.Cu" "B.Cu")
		(net "MB3_P12V_IN_R")
	)
	(via
		(at 251.2314 -350.9518)
		(size 0.8636)
		(drill 0.508)
		(layers "F.Cu" "B.Cu")
		(net "MB3_P12V_IN_R")
	)
	(via
		(at 252.700536 -353.91598)
		(size 0.6604)
		(drill 0.3302)
		(layers "F.Cu" "B.Cu")
		(net "MB3_P12V_IN_R")
	)
	(via
		(at 251.1806 -347.1926)
		(size 0.8636)
		(drill 0.508)
		(layers "F.Cu" "B.Cu")
		(net "MB3_P12V_IN_R")
	)
	(via
		(at 257.556 -330.3524)
		(size 0.8636)
		(drill 0.508)
		(layers "F.Cu" "B.Cu")
		(net "MB3_P12V_IN_R")
	)
	(via
		(at 259.036566 -352.942906)
		(size 0.8636)
		(drill 0.508)
		(layers "F.Cu" "B.Cu")
		(net "MB3_P12V_IN_R")
	)
	(via
		(at 256.25298 -345.866974)
		(size 0.8636)
		(drill 0.508)
		(layers "F.Cu" "B.Cu")
		(net "MB3_P12V_IN_R")
	)
	(via
		(at 253.0856 -334.2386)
		(size 0.8636)
		(drill 0.508)
		(layers "F.Cu" "B.Cu")
		(net "MB3_P12V_IN_R")
	)
	(via
		(at 252.5268 -346.1258)
		(size 0.8636)
		(drill 0.508)
		(layers "F.Cu" "B.Cu")
		(net "MB3_P12V_IN_R")
	)
	(via
		(at 259.036566 -345.881706)
		(size 0.8636)
		(drill 0.508)
		(layers "F.Cu" "B.Cu")
		(net "MB3_P12V_IN_R")
	)
	(via
		(at 250.6218 -332.1304)
		(size 0.8636)
		(drill 0.508)
		(layers "F.Cu" "B.Cu")
		(net "MB3_P12V_IN_R")
	)
	(via
		(at 251.2568 -349.1992)
		(size 0.8636)
		(drill 0.508)
		(layers "F.Cu" "B.Cu")
		(net "MB3_P12V_IN_R")
	)
	(via
		(at 251.90577 -337.239864)
		(size 0.8636)
		(drill 0.508)
		(layers "F.Cu" "B.Cu")
		(net "MB3_P12V_IN_R")
	)
	(via
		(at 254.6858 -331.6478)
		(size 0.8636)
		(drill 0.508)
		(layers "F.Cu" "B.Cu")
		(net "MB3_P12V_IN_R")
	)
	(via
		(at 259.036566 -331.759306)
		(size 0.8636)
		(drill 0.508)
		(layers "F.Cu" "B.Cu")
		(net "MB3_P12V_IN_R")
	)
	(via
		(at 252.5522 -348.0054)
		(size 0.8636)
		(drill 0.508)
		(layers "F.Cu" "B.Cu")
		(net "MB3_P12V_IN_R")
	)
	(via
		(at 252.095 -344.7796)
		(size 0.8636)
		(drill 0.508)
		(layers "F.Cu" "B.Cu")
		(net "MB3_P12V_IN_R")
	)
	(via
		(at 253.4666 -342.0364)
		(size 0.8636)
		(drill 0.508)
		(layers "F.Cu" "B.Cu")
		(net "MB3_P12V_IN_R")
	)
	(via
		(at 257.633724 -345.87434)
		(size 0.8636)
		(drill 0.508)
		(layers "F.Cu" "B.Cu")
		(net "MB3_P12V_IN_R")
	)
	(via
		(at 259.2832 -330.3016)
		(size 0.8636)
		(drill 0.508)
		(layers "F.Cu" "B.Cu")
		(net "MB3_P12V_IN_R")
	)
	(via
		(at 251.335286 -353.929188)
		(size 0.8636)
		(drill 0.508)
		(layers "F.Cu" "B.Cu")
		(net "MB3_P12V_IN_R")
	)
	(via
		(at 254.0508 -335.407)
		(size 0.8636)
		(drill 0.508)
		(layers "F.Cu" "B.Cu")
		(net "MB3_P12V_IN_R")
	)
	(via
		(at 252.095 -342.0364)
		(size 0.8636)
		(drill 0.508)
		(layers "F.Cu" "B.Cu")
		(net "MB3_P12V_IN_R")
	)
	(via
		(at 252.99797 -336.325464)
		(size 0.8636)
		(drill 0.508)
		(layers "F.Cu" "B.Cu")
		(net "MB3_P12V_IN_R")
	)
	(via
		(at 253.4666 -340.6648)
		(size 0.8636)
		(drill 0.508)
		(layers "F.Cu" "B.Cu")
		(net "MB3_P12V_IN_R")
	)
	(via
		(at 250.63577 -336.249264)
		(size 0.8636)
		(drill 0.508)
		(layers "F.Cu" "B.Cu")
		(net "MB3_P12V_IN_R")
	)
	(via
		(at 259.544566 -338.820506)
		(size 0.8636)
		(drill 0.508)
		(layers "F.Cu" "B.Cu")
		(net "MB3_P12V_IN_R")
	)
	(via
		(at 255.8034 -330.4794)
		(size 0.8636)
		(drill 0.508)
		(layers "F.Cu" "B.Cu")
		(net "MB3_P12V_IN_R")
	)
	(via
		(at 253.9746 -347.1672)
		(size 0.8636)
		(drill 0.508)
		(layers "F.Cu" "B.Cu")
		(net "MB3_P12V_IN_R")
	)
	(via
		(at 249.3518 -334.2386)
		(size 0.6604)
		(drill 0.3302)
		(layers "F.Cu" "B.Cu")
		(net "MB3_P12V_IN_R")
	)
	(via
		(at 254.0508 -333.1718)
		(size 0.8636)
		(drill 0.508)
		(layers "F.Cu" "B.Cu")
		(net "MB3_P12V_IN_R")
	)
	(via
		(at 252.095 -343.408)
		(size 0.8636)
		(drill 0.508)
		(layers "F.Cu" "B.Cu")
		(net "MB3_P12V_IN_R")
	)
	(via
		(at 251.227082 -352.492056)
		(size 0.8636)
		(drill 0.508)
		(layers "F.Cu" "B.Cu")
		(net "MB3_P12V_IN_R")
	)
	(via
		(at 253.98222 -353.83978)
		(size 0.8636)
		(drill 0.508)
		(layers "F.Cu" "B.Cu")
		(net "MB3_P12V_IN_R")
	)
	(via
		(at 254.855218 -345.86037)
		(size 0.8636)
		(drill 0.508)
		(layers "F.Cu" "B.Cu")
		(net "MB3_P12V_IN_R")
	)
	(via
		(at 253.6444 -330.4286)
		(size 0.8636)
		(drill 0.508)
		(layers "F.Cu" "B.Cu")
		(net "MB3_P12V_IN_R")
	)
	(via
		(at 257.477768 -352.980752)
		(size 0.8636)
		(drill 0.508)
		(layers "F.Cu" "B.Cu")
		(net "MB3_P12V_IN_R")
	)
	(via
		(at 252.6538 -351.79)
		(size 0.8636)
		(drill 0.508)
		(layers "F.Cu" "B.Cu")
		(net "MB3_P12V_IN_R")
	)
	(via
		(at 253.9238 -349.123)
		(size 0.8636)
		(drill 0.508)
		(layers "F.Cu" "B.Cu")
		(net "MB3_P12V_IN_R")
	)
	(via
		(at 251.82957 -335.385664)
		(size 0.8636)
		(drill 0.508)
		(layers "F.Cu" "B.Cu")
		(net "MB3_P12V_IN_R")
	)
	(via
		(at 253.4666 -339.2932)
		(size 0.8636)
		(drill 0.508)
		(layers "F.Cu" "B.Cu")
		(net "MB3_P12V_IN_R")
	)
	(via
		(at 255.429766 -338.820506)
		(size 0.8636)
		(drill 0.508)
		(layers "F.Cu" "B.Cu")
		(net "MB3_P12V_IN_R")
	)
	(via
		(at 256.801366 -338.820506)
		(size 0.8636)
		(drill 0.508)
		(layers "F.Cu" "B.Cu")
		(net "MB3_P12V_IN_R")
	)
	(via
		(at 253.9492 -350.9264)
		(size 0.8636)
		(drill 0.508)
		(layers "F.Cu" "B.Cu")
		(net "MB3_P12V_IN_R")
	)
	(via
		(at 253.0348 -332.1812)
		(size 0.8636)
		(drill 0.508)
		(layers "F.Cu" "B.Cu")
		(net "MB3_P12V_IN_R")
	)
	(via
		(at 253.4666 -343.408)
		(size 0.8636)
		(drill 0.508)
		(layers "F.Cu" "B.Cu")
		(net "MB3_P12V_IN_R")
	)
	(via
		(at 252.095 -340.6648)
		(size 0.8636)
		(drill 0.508)
		(layers "F.Cu" "B.Cu")
		(net "MB3_P12V_IN_R")
	)
	(via
		(at 254.0508 -337.3374)
		(size 0.8636)
		(drill 0.508)
		(layers "F.Cu" "B.Cu")
		(net "MB3_P12V_IN_R")
	)
	(via
		(at 252.5776 -349.8342)
		(size 0.8636)
		(drill 0.508)
		(layers "F.Cu" "B.Cu")
		(net "MB3_P12V_IN_R")
	)
	(via
		(at 251.841 -333.2734)
		(size 0.8636)
		(drill 0.508)
		(layers "F.Cu" "B.Cu")
		(net "MB3_P12V_IN_R")
	)
	(via
		(at 255.071118 -352.906076)
		(size 0.8636)
		(drill 0.508)
		(layers "F.Cu" "B.Cu")
		(net "MB3_P12V_IN_R")
	)
	(via
		(at 177.2158 -343.6366)
		(size 0.8636)
		(drill 0.508)
		(layers "F.Cu" "B.Cu")
		(net "MB0_P12V_IN_R")
	)
	(via
		(at 195.292218 -353.34194)
		(size 0.8636)
		(drill 0.508)
		(layers "F.Cu" "B.Cu")
		(net "MB0_P12V_IN_R")
	)
	(via
		(at 197.324218 -333.02194)
		(size 0.8636)
		(drill 0.508)
		(layers "F.Cu" "B.Cu")
		(net "MB0_P12V_IN_R")
	)
	(via
		(at 198.642224 -329.657202)
		(size 0.8636)
		(drill 0.508)
		(layers "F.Cu" "B.Cu")
		(net "MB0_P12V_IN_R")
	)
	(via
		(at 202.748642 -340.34222)
		(size 0.8636)
		(drill 0.508)
		(layers "F.Cu" "B.Cu")
		(net "MB0_P12V_IN_R")
	)
	(via
		(at 177.2158 -347.6498)
		(size 0.8636)
		(drill 0.508)
		(layers "F.Cu" "B.Cu")
		(net "MB0_P12V_IN_R")
	)
	(via
		(at 197.324218 -341.14994)
		(size 0.8636)
		(drill 0.508)
		(layers "F.Cu" "B.Cu")
		(net "MB0_P12V_IN_R")
	)
	(via
		(at 174.2186 -329.692)
		(size 0.8636)
		(drill 0.508)
		(layers "F.Cu" "B.Cu")
		(net "MB0_P12V_IN_R")
	)
	(via
		(at 176.2252 -333.7306)
		(size 0.8636)
		(drill 0.508)
		(layers "F.Cu" "B.Cu")
		(net "MB0_P12V_IN_R")
	)
	(via
		(at 179.2224 -339.6234)
		(size 0.8636)
		(drill 0.508)
		(layers "F.Cu" "B.Cu")
		(net "MB0_P12V_IN_R")
	)
	(via
		(at 197.324218 -349.27794)
		(size 0.8636)
		(drill 0.508)
		(layers "F.Cu" "B.Cu")
		(net "MB0_P12V_IN_R")
	)
	(via
		(at 197.324218 -335.05394)
		(size 0.8636)
		(drill 0.508)
		(layers "F.Cu" "B.Cu")
		(net "MB0_P12V_IN_R")
	)
	(via
		(at 178.666394 -352.348292)
		(size 0.6604)
		(drill 0.3302)
		(layers "F.Cu" "B.Cu")
		(net "MB0_P12V_IN_R")
	)
	(via
		(at 176.2252 -329.692)
		(size 0.8636)
		(drill 0.508)
		(layers "F.Cu" "B.Cu")
		(net "MB0_P12V_IN_R")
	)
	(via
		(at 203.454 -338.7852)
		(size 0.8636)
		(drill 0.508)
		(layers "F.Cu" "B.Cu")
		(net "MB0_P12V_IN_R")
	)
	(via
		(at 195.292218 -355.37394)
		(size 0.8636)
		(drill 0.508)
		(layers "F.Cu" "B.Cu")
		(net "MB0_P12V_IN_R")
	)
	(via
		(at 198.684642 -340.21522)
		(size 0.8636)
		(drill 0.508)
		(layers "F.Cu" "B.Cu")
		(net "MB0_P12V_IN_R")
	)
	(via
		(at 195.292218 -351.30994)
		(size 0.8636)
		(drill 0.508)
		(layers "F.Cu" "B.Cu")
		(net "MB0_P12V_IN_R")
	)
	(via
		(at 169.1894 -343.6366)
		(size 0.8636)
		(drill 0.508)
		(layers "F.Cu" "B.Cu")
		(net "MB0_P12V_IN_R")
	)
	(via
		(at 167.1828 -341.63)
		(size 0.8636)
		(drill 0.508)
		(layers "F.Cu" "B.Cu")
		(net "MB0_P12V_IN_R")
	)
	(via
		(at 173.2026 -337.6168)
		(size 0.8636)
		(drill 0.508)
		(layers "F.Cu" "B.Cu")
		(net "MB0_P12V_IN_R")
	)
	(via
		(at 171.196 -337.6168)
		(size 0.8636)
		(drill 0.508)
		(layers "F.Cu" "B.Cu")
		(net "MB0_P12V_IN_R")
	)
	(via
		(at 201.93 -349.9866)
		(size 0.8636)
		(drill 0.508)
		(layers "F.Cu" "B.Cu")
		(net "MB0_P12V_IN_R")
	)
	(via
		(at 195.292218 -341.14994)
		(size 0.8636)
		(drill 0.508)
		(layers "F.Cu" "B.Cu")
		(net "MB0_P12V_IN_R")
	)
	(via
		(at 175.2092 -335.6102)
		(size 0.8636)
		(drill 0.508)
		(layers "F.Cu" "B.Cu")
		(net "MB0_P12V_IN_R")
	)
	(via
		(at 202.77582 -357.613966)
		(size 0.8636)
		(drill 0.508)
		(layers "F.Cu" "B.Cu")
		(net "MB0_P12V_IN_R")
	)
	(via
		(at 203.454 -336.7532)
		(size 0.8636)
		(drill 0.508)
		(layers "F.Cu" "B.Cu")
		(net "MB0_P12V_IN_R")
	)
	(via
		(at 197.0024 -330.8096)
		(size 0.8636)
		(drill 0.508)
		(layers "F.Cu" "B.Cu")
		(net "MB0_P12V_IN_R")
	)
	(via
		(at 175.2092 -349.6564)
		(size 0.8636)
		(drill 0.508)
		(layers "F.Cu" "B.Cu")
		(net "MB0_P12V_IN_R")
	)
	(via
		(at 195.292218 -333.02194)
		(size 0.8636)
		(drill 0.508)
		(layers "F.Cu" "B.Cu")
		(net "MB0_P12V_IN_R")
	)
	(via
		(at 173.2026 -351.663)
		(size 0.8636)
		(drill 0.508)
		(layers "F.Cu" "B.Cu")
		(net "MB0_P12V_IN_R")
	)
	(via
		(at 173.2026 -343.6366)
		(size 0.8636)
		(drill 0.508)
		(layers "F.Cu" "B.Cu")
		(net "MB0_P12V_IN_R")
	)
	(via
		(at 179.2224 -341.63)
		(size 0.8636)
		(drill 0.508)
		(layers "F.Cu" "B.Cu")
		(net "MB0_P12V_IN_R")
	)
	(via
		(at 171.6786 -355.6762)
		(size 0.8636)
		(drill 0.508)
		(layers "F.Cu" "B.Cu")
		(net "MB0_P12V_IN_R")
	)
	(via
		(at 179.2224 -347.6498)
		(size 0.8636)
		(drill 0.508)
		(layers "F.Cu" "B.Cu")
		(net "MB0_P12V_IN_R")
	)
	(via
		(at 175.2092 -351.663)
		(size 0.8636)
		(drill 0.508)
		(layers "F.Cu" "B.Cu")
		(net "MB0_P12V_IN_R")
	)
	(via
		(at 169.1894 -345.6432)
		(size 0.8636)
		(drill 0.508)
		(layers "F.Cu" "B.Cu")
		(net "MB0_P12V_IN_R")
	)
	(via
		(at 171.196 -341.63)
		(size 0.8636)
		(drill 0.508)
		(layers "F.Cu" "B.Cu")
		(net "MB0_P12V_IN_R")
	)
	(via
		(at 177.0634 -351.6884)
		(size 0.8636)
		(drill 0.508)
		(layers "F.Cu" "B.Cu")
		(net "MB0_P12V_IN_R")
	)
	(via
		(at 175.6918 -357.6828)
		(size 0.8636)
		(drill 0.508)
		(layers "F.Cu" "B.Cu")
		(net "MB0_P12V_IN_R")
	)
	(via
		(at 200.9013 -348.666562)
		(size 0.8636)
		(drill 0.508)
		(layers "F.Cu" "B.Cu")
		(net "MB0_P12V_IN_R")
	)
	(via
		(at 173.6852 -353.6696)
		(size 0.8636)
		(drill 0.508)
		(layers "F.Cu" "B.Cu")
		(net "MB0_P12V_IN_R")
	)
	(via
		(at 195.292218 -347.24594)
		(size 0.8636)
		(drill 0.508)
		(layers "F.Cu" "B.Cu")
		(net "MB0_P12V_IN_R")
	)
	(via
		(at 197.324218 -347.24594)
		(size 0.8636)
		(drill 0.508)
		(layers "F.Cu" "B.Cu")
		(net "MB0_P12V_IN_R")
	)
	(via
		(at 175.2092 -347.6498)
		(size 0.8636)
		(drill 0.508)
		(layers "F.Cu" "B.Cu")
		(net "MB0_P12V_IN_R")
	)
	(via
		(at 171.6786 -353.6696)
		(size 0.8636)
		(drill 0.508)
		(layers "F.Cu" "B.Cu")
		(net "MB0_P12V_IN_R")
	)
	(via
		(at 167.1828 -337.6168)
		(size 0.8636)
		(drill 0.508)
		(layers "F.Cu" "B.Cu")
		(net "MB0_P12V_IN_R")
	)
	(via
		(at 177.2158 -339.6234)
		(size 0.8636)
		(drill 0.508)
		(layers "F.Cu" "B.Cu")
		(net "MB0_P12V_IN_R")
	)
	(via
		(at 197.324218 -339.11794)
		(size 0.8636)
		(drill 0.508)
		(layers "F.Cu" "B.Cu")
		(net "MB0_P12V_IN_R")
	)
	(via
		(at 175.2092 -337.6168)
		(size 0.8636)
		(drill 0.508)
		(layers "F.Cu" "B.Cu")
		(net "MB0_P12V_IN_R")
	)
	(via
		(at 179.2224 -349.6564)
		(size 0.8636)
		(drill 0.508)
		(layers "F.Cu" "B.Cu")
		(net "MB0_P12V_IN_R")
	)
	(via
		(at 171.196 -345.6432)
		(size 0.8636)
		(drill 0.508)
		(layers "F.Cu" "B.Cu")
		(net "MB0_P12V_IN_R")
	)
	(via
		(at 173.2026 -349.6564)
		(size 0.8636)
		(drill 0.508)
		(layers "F.Cu" "B.Cu")
		(net "MB0_P12V_IN_R")
	)
	(via
		(at 195.292218 -343.18194)
		(size 0.8636)
		(drill 0.508)
		(layers "F.Cu" "B.Cu")
		(net "MB0_P12V_IN_R")
	)
	(via
		(at 200.716642 -340.34222)
		(size 0.8636)
		(drill 0.508)
		(layers "F.Cu" "B.Cu")
		(net "MB0_P12V_IN_R")
	)
	(via
		(at 167.1828 -339.6234)
		(size 0.8636)
		(drill 0.508)
		(layers "F.Cu" "B.Cu")
		(net "MB0_P12V_IN_R")
	)
	(via
		(at 171.196 -335.6102)
		(size 0.8636)
		(drill 0.508)
		(layers "F.Cu" "B.Cu")
		(net "MB0_P12V_IN_R")
	)
	(via
		(at 169.1894 -341.63)
		(size 0.8636)
		(drill 0.508)
		(layers "F.Cu" "B.Cu")
		(net "MB0_P12V_IN_R")
	)
	(via
		(at 200.674224 -329.657202)
		(size 0.8636)
		(drill 0.508)
		(layers "F.Cu" "B.Cu")
		(net "MB0_P12V_IN_R")
	)
	(via
		(at 197.324218 -351.30994)
		(size 0.8636)
		(drill 0.508)
		(layers "F.Cu" "B.Cu")
		(net "MB0_P12V_IN_R")
	)
	(via
		(at 202.706224 -329.657202)
		(size 0.8636)
		(drill 0.508)
		(layers "F.Cu" "B.Cu")
		(net "MB0_P12V_IN_R")
	)
	(via
		(at 200.74382 -357.613966)
		(size 0.8636)
		(drill 0.508)
		(layers "F.Cu" "B.Cu")
		(net "MB0_P12V_IN_R")
	)
	(via
		(at 173.2026 -347.6498)
		(size 0.8636)
		(drill 0.508)
		(layers "F.Cu" "B.Cu")
		(net "MB0_P12V_IN_R")
	)
	(via
		(at 177.2158 -349.6564)
		(size 0.8636)
		(drill 0.508)
		(layers "F.Cu" "B.Cu")
		(net "MB0_P12V_IN_R")
	)
	(via
		(at 169.1894 -339.6234)
		(size 0.8636)
		(drill 0.508)
		(layers "F.Cu" "B.Cu")
		(net "MB0_P12V_IN_R")
	)
	(via
		(at 172.212 -331.724)
		(size 0.8636)
		(drill 0.508)
		(layers "F.Cu" "B.Cu")
		(net "MB0_P12V_IN_R")
	)
	(via
		(at 169.1894 -349.6564)
		(size 0.8636)
		(drill 0.508)
		(layers "F.Cu" "B.Cu")
		(net "MB0_P12V_IN_R")
	)
	(via
		(at 177.2158 -345.6432)
		(size 0.8636)
		(drill 0.508)
		(layers "F.Cu" "B.Cu")
		(net "MB0_P12V_IN_R")
	)
	(via
		(at 197.324218 -345.21394)
		(size 0.8636)
		(drill 0.508)
		(layers "F.Cu" "B.Cu")
		(net "MB0_P12V_IN_R")
	)
	(via
		(at 177.6984 -357.6828)
		(size 0.8636)
		(drill 0.508)
		(layers "F.Cu" "B.Cu")
		(net "MB0_P12V_IN_R")
	)
	(via
		(at 171.196 -349.6564)
		(size 0.8636)
		(drill 0.508)
		(layers "F.Cu" "B.Cu")
		(net "MB0_P12V_IN_R")
	)
	(via
		(at 173.2026 -345.6432)
		(size 0.8636)
		(drill 0.508)
		(layers "F.Cu" "B.Cu")
		(net "MB0_P12V_IN_R")
	)
	(via
		(at 167.1828 -349.6564)
		(size 0.8636)
		(drill 0.508)
		(layers "F.Cu" "B.Cu")
		(net "MB0_P12V_IN_R")
	)
	(via
		(at 175.2092 -345.6432)
		(size 0.8636)
		(drill 0.508)
		(layers "F.Cu" "B.Cu")
		(net "MB0_P12V_IN_R")
	)
	(via
		(at 171.196 -339.6234)
		(size 0.8636)
		(drill 0.508)
		(layers "F.Cu" "B.Cu")
		(net "MB0_P12V_IN_R")
	)
	(via
		(at 195.292218 -337.08594)
		(size 0.8636)
		(drill 0.508)
		(layers "F.Cu" "B.Cu")
		(net "MB0_P12V_IN_R")
	)
	(via
		(at 171.196 -351.663)
		(size 0.8636)
		(drill 0.508)
		(layers "F.Cu" "B.Cu")
		(net "MB0_P12V_IN_R")
	)
	(via
		(at 201.7268 -336.8294)
		(size 0.8636)
		(drill 0.508)
		(layers "F.Cu" "B.Cu")
		(net "MB0_P12V_IN_R")
	)
	(via
		(at 167.1828 -343.6366)
		(size 0.8636)
		(drill 0.508)
		(layers "F.Cu" "B.Cu")
		(net "MB0_P12V_IN_R")
	)
	(via
		(at 201.7268 -338.8614)
		(size 0.8636)
		(drill 0.508)
		(layers "F.Cu" "B.Cu")
		(net "MB0_P12V_IN_R")
	)
	(via
		(at 171.196 -347.6498)
		(size 0.8636)
		(drill 0.508)
		(layers "F.Cu" "B.Cu")
		(net "MB0_P12V_IN_R")
	)
	(via
		(at 197.324218 -353.34194)
		(size 0.8636)
		(drill 0.508)
		(layers "F.Cu" "B.Cu")
		(net "MB0_P12V_IN_R")
	)
	(via
		(at 167.1828 -345.6432)
		(size 0.8636)
		(drill 0.508)
		(layers "F.Cu" "B.Cu")
		(net "MB0_P12V_IN_R")
	)
	(via
		(at 177.2158 -337.6168)
		(size 0.8636)
		(drill 0.508)
		(layers "F.Cu" "B.Cu")
		(net "MB0_P12V_IN_R")
	)
	(via
		(at 195.292218 -345.21394)
		(size 0.8636)
		(drill 0.508)
		(layers "F.Cu" "B.Cu")
		(net "MB0_P12V_IN_R")
	)
	(via
		(at 197.324218 -343.18194)
		(size 0.8636)
		(drill 0.508)
		(layers "F.Cu" "B.Cu")
		(net "MB0_P12V_IN_R")
	)
	(via
		(at 171.196 -343.6366)
		(size 0.8636)
		(drill 0.508)
		(layers "F.Cu" "B.Cu")
		(net "MB0_P12V_IN_R")
	)
	(via
		(at 179.2224 -337.6168)
		(size 0.8636)
		(drill 0.508)
		(layers "F.Cu" "B.Cu")
		(net "MB0_P12V_IN_R")
	)
	(via
		(at 169.1894 -337.6168)
		(size 0.8636)
		(drill 0.508)
		(layers "F.Cu" "B.Cu")
		(net "MB0_P12V_IN_R")
	)
	(via
		(at 174.2186 -331.724)
		(size 0.8636)
		(drill 0.508)
		(layers "F.Cu" "B.Cu")
		(net "MB0_P12V_IN_R")
	)
	(via
		(at 174.2186 -333.7306)
		(size 0.8636)
		(drill 0.508)
		(layers "F.Cu" "B.Cu")
		(net "MB0_P12V_IN_R")
	)
	(via
		(at 172.212 -329.692)
		(size 0.8636)
		(drill 0.508)
		(layers "F.Cu" "B.Cu")
		(net "MB0_P12V_IN_R")
	)
	(via
		(at 175.2092 -341.63)
		(size 0.8636)
		(drill 0.508)
		(layers "F.Cu" "B.Cu")
		(net "MB0_P12V_IN_R")
	)
	(via
		(at 173.6852 -357.6828)
		(size 0.8636)
		(drill 0.508)
		(layers "F.Cu" "B.Cu")
		(net "MB0_P12V_IN_R")
	)
	(via
		(at 199.7964 -350.0374)
		(size 0.8636)
		(drill 0.508)
		(layers "F.Cu" "B.Cu")
		(net "MB0_P12V_IN_R")
	)
	(via
		(at 195.292218 -335.05394)
		(size 0.8636)
		(drill 0.508)
		(layers "F.Cu" "B.Cu")
		(net "MB0_P12V_IN_R")
	)
	(via
		(at 197.324218 -337.08594)
		(size 0.8636)
		(drill 0.508)
		(layers "F.Cu" "B.Cu")
		(net "MB0_P12V_IN_R")
	)
	(via
		(at 175.2092 -343.6366)
		(size 0.8636)
		(drill 0.508)
		(layers "F.Cu" "B.Cu")
		(net "MB0_P12V_IN_R")
	)
	(via
		(at 177.6984 -353.6696)
		(size 0.8636)
		(drill 0.508)
		(layers "F.Cu" "B.Cu")
		(net "MB0_P12V_IN_R")
	)
	(via
		(at 177.2158 -341.63)
		(size 0.8636)
		(drill 0.508)
		(layers "F.Cu" "B.Cu")
		(net "MB0_P12V_IN_R")
	)
	(via
		(at 175.2092 -339.6234)
		(size 0.8636)
		(drill 0.508)
		(layers "F.Cu" "B.Cu")
		(net "MB0_P12V_IN_R")
	)
	(via
		(at 195.292218 -339.11794)
		(size 0.8636)
		(drill 0.508)
		(layers "F.Cu" "B.Cu")
		(net "MB0_P12V_IN_R")
	)
	(via
		(at 175.6918 -355.6762)
		(size 0.8636)
		(drill 0.508)
		(layers "F.Cu" "B.Cu")
		(net "MB0_P12V_IN_R")
	)
	(via
		(at 199.6948 -338.8614)
		(size 0.8636)
		(drill 0.508)
		(layers "F.Cu" "B.Cu")
		(net "MB0_P12V_IN_R")
	)
	(via
		(at 177.2158 -335.6102)
		(size 0.8636)
		(drill 0.508)
		(layers "F.Cu" "B.Cu")
		(net "MB0_P12V_IN_R")
	)
	(via
		(at 197.324218 -355.37394)
		(size 0.8636)
		(drill 0.508)
		(layers "F.Cu" "B.Cu")
		(net "MB0_P12V_IN_R")
	)
	(via
		(at 173.2026 -335.6102)
		(size 0.8636)
		(drill 0.508)
		(layers "F.Cu" "B.Cu")
		(net "MB0_P12V_IN_R")
	)
	(via
		(at 171.6786 -357.6828)
		(size 0.8636)
		(drill 0.508)
		(layers "F.Cu" "B.Cu")
		(net "MB0_P12V_IN_R")
	)
	(via
		(at 195.292218 -349.27794)
		(size 0.8636)
		(drill 0.508)
		(layers "F.Cu" "B.Cu")
		(net "MB0_P12V_IN_R")
	)
	(via
		(at 179.2224 -343.6366)
		(size 0.8636)
		(drill 0.508)
		(layers "F.Cu" "B.Cu")
		(net "MB0_P12V_IN_R")
	)
	(via
		(at 202.9333 -348.666562)
		(size 0.8636)
		(drill 0.508)
		(layers "F.Cu" "B.Cu")
		(net "MB0_P12V_IN_R")
	)
	(via
		(at 173.6852 -355.6762)
		(size 0.8636)
		(drill 0.508)
		(layers "F.Cu" "B.Cu")
		(net "MB0_P12V_IN_R")
	)
	(via
		(at 173.2026 -341.63)
		(size 0.8636)
		(drill 0.508)
		(layers "F.Cu" "B.Cu")
		(net "MB0_P12V_IN_R")
	)
	(via
		(at 177.6984 -355.6762)
		(size 0.8636)
		(drill 0.508)
		(layers "F.Cu" "B.Cu")
		(net "MB0_P12V_IN_R")
	)
	(via
		(at 176.2252 -331.724)
		(size 0.8636)
		(drill 0.508)
		(layers "F.Cu" "B.Cu")
		(net "MB0_P12V_IN_R")
	)
	(via
		(at 173.2026 -339.6234)
		(size 0.8636)
		(drill 0.508)
		(layers "F.Cu" "B.Cu")
		(net "MB0_P12V_IN_R")
	)
	(via
		(at 199.6948 -336.8294)
		(size 0.8636)
		(drill 0.508)
		(layers "F.Cu" "B.Cu")
		(net "MB0_P12V_IN_R")
	)
	(via
		(at 167.1828 -347.6498)
		(size 0.8636)
		(drill 0.508)
		(layers "F.Cu" "B.Cu")
		(net "MB0_P12V_IN_R")
	)
	(via
		(at 169.1894 -347.6498)
		(size 0.8636)
		(drill 0.508)
		(layers "F.Cu" "B.Cu")
		(net "MB0_P12V_IN_R")
	)
	(via
		(at 175.6918 -353.6696)
		(size 0.8636)
		(drill 0.508)
		(layers "F.Cu" "B.Cu")
		(net "MB0_P12V_IN_R")
	)
	(via
		(at 179.2224 -345.6432)
		(size 0.8636)
		(drill 0.508)
		(layers "F.Cu" "B.Cu")
		(net "MB0_P12V_IN_R")
	)
	(via
		(at 172.212 -333.7306)
		(size 0.8636)
		(drill 0.508)
		(layers "F.Cu" "B.Cu")
		(net "MB0_P12V_IN_R")
	)
	(via
		(at 198.8693 -348.666562)
		(size 0.8636)
		(drill 0.508)
		(layers "F.Cu" "B.Cu")
		(net "MB0_P12V_IN_R")
	)
	(via
		(at 198.71182 -357.613966)
		(size 0.8636)
		(drill 0.508)
		(layers "F.Cu" "B.Cu")
		(net "MB0_P12V_IN_R")
	)
	(segment
		(start 283.619448 -353.948238)
		(end 283.619448 -354.272342)
		(width 0.17145)
		(layer "F.Cu")
		(net "MAX31790_B_SDA")
	)
	(segment
		(start 282.222448 -355.415342)
		(end 280.888948 -355.415342)
		(width 0.17145)
		(layer "F.Cu")
		(net "MAX31790_B_SDA")
	)
	(segment
		(start 282.476448 -355.415342)
		(end 282.222448 -355.415342)
		(width 0.17145)
		(layer "F.Cu")
		(net "MAX31790_B_SDA")
	)
	(segment
		(start 283.619448 -354.272342)
		(end 282.476448 -355.415342)
		(width 0.17145)
		(layer "F.Cu")
		(net "MAX31790_B_SDA")
	)
	(via
		(at 282.222448 -355.415342)
		(size 0.6604)
		(drill 0.3302)
		(layers "F.Cu" "B.Cu")
		(net "MAX31790_B_SDA")
	)
	(segment
		(start 283.619448 -353.548442)
		(end 283.146754 -353.548442)
		(width 0.17145)
		(layer "F.Cu")
		(net "MAX31790_B_SCL")
	)
	(segment
		(start 282.501848 -354.399342)
		(end 281.841448 -354.399342)
		(width 0.17145)
		(layer "F.Cu")
		(net "MAX31790_B_SCL")
	)
	(segment
		(start 282.818078 -354.083112)
		(end 282.501848 -354.399342)
		(width 0.17145)
		(layer "F.Cu")
		(net "MAX31790_B_SCL")
	)
	(segment
		(start 282.818078 -353.877118)
		(end 282.818078 -354.083112)
		(width 0.17145)
		(layer "F.Cu")
		(net "MAX31790_B_SCL")
	)
	(segment
		(start 283.146754 -353.548442)
		(end 282.818078 -353.877118)
		(width 0.17145)
		(layer "F.Cu")
		(net "MAX31790_B_SCL")
	)
	(segment
		(start 281.841448 -354.399342)
		(end 280.888948 -354.399342)
		(width 0.17145)
		(layer "F.Cu")
		(net "MAX31790_B_SCL")
	)
	(via
		(at 281.841448 -354.399342)
		(size 0.6604)
		(drill 0.3302)
		(layers "F.Cu" "B.Cu")
		(net "MAX31790_B_SCL")
	)
	(segment
		(start 280.8859 -348.2848)
		(end 281.739848 -348.2848)
		(width 0.17145)
		(layer "F.Cu")
		(net "MAX31790_B_FULL_SPEED")
	)
	(segment
		(start 283.111448 -351.948242)
		(end 283.619448 -351.948242)
		(width 0.17145)
		(layer "F.Cu")
		(net "MAX31790_B_FULL_SPEED")
	)
	(segment
		(start 281.841448 -348.3864)
		(end 282.2702 -348.815152)
		(width 0.17145)
		(layer "F.Cu")
		(net "MAX31790_B_FULL_SPEED")
	)
	(segment
		(start 282.857448 -350.218248)
		(end 282.857448 -351.694242)
		(width 0.17145)
		(layer "F.Cu")
		(net "MAX31790_B_FULL_SPEED")
	)
	(segment
		(start 281.739848 -348.2848)
		(end 281.841448 -348.3864)
		(width 0.17145)
		(layer "F.Cu")
		(net "MAX31790_B_FULL_SPEED")
	)
	(segment
		(start 282.857448 -351.694242)
		(end 283.111448 -351.948242)
		(width 0.17145)
		(layer "F.Cu")
		(net "MAX31790_B_FULL_SPEED")
	)
	(segment
		(start 282.2702 -348.815152)
		(end 282.2702 -349.631)
		(width 0.17145)
		(layer "F.Cu")
		(net "MAX31790_B_FULL_SPEED")
	)
	(segment
		(start 282.2702 -349.631)
		(end 282.857448 -350.218248)
		(width 0.17145)
		(layer "F.Cu")
		(net "MAX31790_B_FULL_SPEED")
	)
	(via
		(at 281.841448 -348.3864)
		(size 0.6604)
		(drill 0.3302)
		(layers "F.Cu" "B.Cu")
		(net "MAX31790_B_FULL_SPEED")
	)
	(segment
		(start 280.888948 -353.383342)
		(end 282.197048 -353.383342)
		(width 0.17145)
		(layer "F.Cu")
		(net "MAX31790_B_FAIL")
	)
	(segment
		(start 283.619448 -353.148392)
		(end 282.939998 -353.148392)
		(width 0.17145)
		(layer "F.Cu")
		(net "MAX31790_B_FAIL")
	)
	(segment
		(start 282.705048 -353.383342)
		(end 282.197048 -353.383342)
		(width 0.17145)
		(layer "F.Cu")
		(net "MAX31790_B_FAIL")
	)
	(segment
		(start 282.939998 -353.148392)
		(end 282.705048 -353.383342)
		(width 0.17145)
		(layer "F.Cu")
		(net "MAX31790_B_FAIL")
	)
	(via
		(at 282.197048 -353.383342)
		(size 0.6604)
		(drill 0.3302)
		(layers "F.Cu" "B.Cu")
		(net "MAX31790_B_FAIL")
	)
	(segment
		(start 285.016448 -348.779592)
		(end 285.016448 -347.985842)
		(width 0.17145)
		(layer "F.Cu")
		(net "MAX31790_B_ADD1")
	)
	(segment
		(start 285.016448 -347.985842)
		(end 286.032448 -347.985842)
		(width 0.17145)
		(layer "F.Cu")
		(net "MAX31790_B_ADD1")
	)
	(segment
		(start 285.251398 -349.116142)
		(end 285.251398 -349.014542)
		(width 0.17145)
		(layer "F.Cu")
		(net "MAX31790_B_ADD1")
	)
	(segment
		(start 285.251398 -349.014542)
		(end 285.016448 -348.779592)
		(width 0.17145)
		(layer "F.Cu")
		(net "MAX31790_B_ADD1")
	)
	(segment
		(start 285.251398 -350.716342)
		(end 285.251398 -349.116142)
		(width 0.17145)
		(layer "F.Cu")
		(net "MAX31790_B_ADD1")
	)
	(via
		(at 285.251398 -349.116142)
		(size 0.6604)
		(drill 0.3302)
		(layers "F.Cu" "B.Cu")
		(net "MAX31790_B_ADD1")
	)
	(segment
		(start 288.064448 -347.985842)
		(end 287.048448 -347.985842)
		(width 0.17145)
		(layer "F.Cu")
		(net "MAX31790_B_ADD0")
	)
	(segment
		(start 285.651448 -350.716342)
		(end 285.651448 -350.355408)
		(width 0.17145)
		(layer "F.Cu")
		(net "MAX31790_B_ADD0")
	)
	(segment
		(start 286.032448 -349.192342)
		(end 287.048448 -349.192342)
		(width 0.17145)
		(layer "F.Cu")
		(net "MAX31790_B_ADD0")
	)
	(segment
		(start 285.644844 -350.348804)
		(end 285.644844 -349.9231)
		(width 0.17145)
		(layer "F.Cu")
		(net "MAX31790_B_ADD0")
	)
	(segment
		(start 287.048448 -347.985842)
		(end 287.048448 -349.192342)
		(width 0.17145)
		(layer "F.Cu")
		(net "MAX31790_B_ADD0")
	)
	(segment
		(start 285.835598 -349.732346)
		(end 285.835598 -349.389192)
		(width 0.17145)
		(layer "F.Cu")
		(net "MAX31790_B_ADD0")
	)
	(segment
		(start 285.644844 -349.9231)
		(end 285.835598 -349.732346)
		(width 0.17145)
		(layer "F.Cu")
		(net "MAX31790_B_ADD0")
	)
	(segment
		(start 285.835598 -349.389192)
		(end 286.032448 -349.192342)
		(width 0.17145)
		(layer "F.Cu")
		(net "MAX31790_B_ADD0")
	)
	(segment
		(start 285.651448 -350.355408)
		(end 285.644844 -350.348804)
		(width 0.17145)
		(layer "F.Cu")
		(net "MAX31790_B_ADD0")
	)
	(via
		(at 287.048448 -349.192342)
		(size 0.6604)
		(drill 0.3302)
		(layers "F.Cu" "B.Cu")
		(net "MAX31790_B_ADD0")
	)
	(segment
		(start 246.507 -304.038)
		(end 247.8405 -304.038)
		(width 0.17145)
		(layer "F.Cu")
		(net "MAX31790_A_SDA")
	)
	(segment
		(start 246.253 -304.038)
		(end 246.507 -304.038)
		(width 0.17145)
		(layer "F.Cu")
		(net "MAX31790_A_SDA")
	)
	(segment
		(start 245.11 -305.181)
		(end 246.253 -304.038)
		(width 0.17145)
		(layer "F.Cu")
		(net "MAX31790_A_SDA")
	)
	(segment
		(start 245.11 -305.505104)
		(end 245.11 -305.181)
		(width 0.17145)
		(layer "F.Cu")
		(net "MAX31790_A_SDA")
	)
	(via
		(at 246.507 -304.038)
		(size 0.6604)
		(drill 0.3302)
		(layers "F.Cu" "B.Cu")
		(net "MAX31790_A_SDA")
	)
	(segment
		(start 246.888 -305.054)
		(end 247.8405 -305.054)
		(width 0.17145)
		(layer "F.Cu")
		(net "MAX31790_A_SCL")
	)
	(segment
		(start 245.6561 -305.9049)
		(end 246.507 -305.054)
		(width 0.17145)
		(layer "F.Cu")
		(net "MAX31790_A_SCL")
	)
	(segment
		(start 246.507 -305.054)
		(end 246.888 -305.054)
		(width 0.17145)
		(layer "F.Cu")
		(net "MAX31790_A_SCL")
	)
	(segment
		(start 245.11 -305.9049)
		(end 245.6561 -305.9049)
		(width 0.17145)
		(layer "F.Cu")
		(net "MAX31790_A_SCL")
	)
	(via
		(at 246.888 -305.054)
		(size 0.6604)
		(drill 0.3302)
		(layers "F.Cu" "B.Cu")
		(net "MAX31790_A_SCL")
	)
	(segment
		(start 245.618 -307.5051)
		(end 245.11 -307.5051)
		(width 0.17145)
		(layer "F.Cu")
		(net "MAX31790_A_FULL_SPEED")
	)
	(segment
		(start 245.872 -309.2704)
		(end 245.872 -307.7591)
		(width 0.17145)
		(layer "F.Cu")
		(net "MAX31790_A_FULL_SPEED")
	)
	(segment
		(start 246.888 -310.7436)
		(end 246.888 -310.2864)
		(width 0.17145)
		(layer "F.Cu")
		(net "MAX31790_A_FULL_SPEED")
	)
	(segment
		(start 247.8405 -311.15)
		(end 247.2944 -311.15)
		(width 0.17145)
		(layer "F.Cu")
		(net "MAX31790_A_FULL_SPEED")
	)
	(segment
		(start 245.872 -307.7591)
		(end 245.618 -307.5051)
		(width 0.17145)
		(layer "F.Cu")
		(net "MAX31790_A_FULL_SPEED")
	)
	(segment
		(start 247.2944 -311.15)
		(end 246.888 -310.7436)
		(width 0.17145)
		(layer "F.Cu")
		(net "MAX31790_A_FULL_SPEED")
	)
	(segment
		(start 246.888 -310.2864)
		(end 245.872 -309.2704)
		(width 0.17145)
		(layer "F.Cu")
		(net "MAX31790_A_FULL_SPEED")
	)
	(via
		(at 246.888 -310.7436)
		(size 0.6604)
		(drill 0.3302)
		(layers "F.Cu" "B.Cu")
		(net "MAX31790_A_FULL_SPEED")
	)
	(segment
		(start 246.356632 -306.165504)
		(end 246.452136 -306.07)
		(width 0.17145)
		(layer "F.Cu")
		(net "MAX31790_A_FAIL")
	)
	(segment
		(start 245.86565 -306.30495)
		(end 246.005096 -306.165504)
		(width 0.17145)
		(layer "F.Cu")
		(net "MAX31790_A_FAIL")
	)
	(segment
		(start 246.452136 -306.07)
		(end 246.507 -306.07)
		(width 0.17145)
		(layer "F.Cu")
		(net "MAX31790_A_FAIL")
	)
	(segment
		(start 246.507 -306.07)
		(end 247.8405 -306.07)
		(width 0.17145)
		(layer "F.Cu")
		(net "MAX31790_A_FAIL")
	)
	(segment
		(start 245.11 -306.30495)
		(end 245.86565 -306.30495)
		(width 0.17145)
		(layer "F.Cu")
		(net "MAX31790_A_FAIL")
	)
	(segment
		(start 246.005096 -306.165504)
		(end 246.356632 -306.165504)
		(width 0.17145)
		(layer "F.Cu")
		(net "MAX31790_A_FAIL")
	)
	(via
		(at 246.507 -306.07)
		(size 0.6604)
		(drill 0.3302)
		(layers "F.Cu" "B.Cu")
		(net "MAX31790_A_FAIL")
	)
	(segment
		(start 243.47805 -309.89905)
		(end 243.713 -310.134)
		(width 0.17145)
		(layer "F.Cu")
		(net "MAX31790_A_ADD1")
	)
	(segment
		(start 243.713 -311.4675)
		(end 242.697 -311.4675)
		(width 0.17145)
		(layer "F.Cu")
		(net "MAX31790_A_ADD1")
	)
	(segment
		(start 243.713 -310.134)
		(end 243.713 -311.4675)
		(width 0.17145)
		(layer "F.Cu")
		(net "MAX31790_A_ADD1")
	)
	(segment
		(start 243.47805 -308.737)
		(end 243.47805 -309.89905)
		(width 0.17145)
		(layer "F.Cu")
		(net "MAX31790_A_ADD1")
	)
	(via
		(at 243.713 -310.134)
		(size 0.6604)
		(drill 0.3302)
		(layers "F.Cu" "B.Cu")
		(net "MAX31790_A_ADD1")
	)
	(segment
		(start 241.935 -310.261)
		(end 241.681 -310.515)
		(width 0.17145)
		(layer "F.Cu")
		(net "MAX31790_A_ADD0")
	)
	(segment
		(start 243.078 -309.5498)
		(end 242.3668 -310.261)
		(width 0.17145)
		(layer "F.Cu")
		(net "MAX31790_A_ADD0")
	)
	(segment
		(start 242.3668 -310.261)
		(end 241.935 -310.261)
		(width 0.17145)
		(layer "F.Cu")
		(net "MAX31790_A_ADD0")
	)
	(segment
		(start 243.078 -308.737)
		(end 243.078 -309.5498)
		(width 0.17145)
		(layer "F.Cu")
		(net "MAX31790_A_ADD0")
	)
	(segment
		(start 241.681 -311.4675)
		(end 240.665 -311.4675)
		(width 0.17145)
		(layer "F.Cu")
		(net "MAX31790_A_ADD0")
	)
	(segment
		(start 241.681 -310.515)
		(end 241.681 -311.4675)
		(width 0.17145)
		(layer "F.Cu")
		(net "MAX31790_A_ADD0")
	)
	(via
		(at 241.681 -310.515)
		(size 0.6604)
		(drill 0.3302)
		(layers "F.Cu" "B.Cu")
		(net "MAX31790_A_ADD0")
	)
	(segment
		(start 208.449926 -169.50055)
		(end 208.449672 -169.500804)
		(width 0.17145)
		(layer "F.Cu")
		(net "IOM_B_INS_N")
	)
	(segment
		(start 209.892138 -169.50055)
		(end 208.449926 -169.50055)
		(width 0.17145)
		(layer "F.Cu")
		(net "IOM_B_INS_N")
	)
	(segment
		(start 212.69706 -168.37914)
		(end 211.013548 -168.37914)
		(width 0.17145)
		(layer "F.Cu")
		(net "IOM_B_INS_N")
	)
	(segment
		(start 211.013548 -168.37914)
		(end 209.892138 -169.50055)
		(width 0.17145)
		(layer "F.Cu")
		(net "IOM_B_INS_N")
	)
	(segment
		(start 208.449672 -169.500804)
		(end 208.023968 -169.500804)
		(width 0.17145)
		(layer "F.Cu")
		(net "IOM_B_INS_N")
	)
	(segment
		(start 208.023968 -169.500804)
		(end 208.023714 -169.50055)
		(width 0.17145)
		(layer "F.Cu")
		(net "IOM_B_INS_N")
	)
	(segment
		(start 203.373736 -164.529516)
		(end 203.373736 -165.70706)
		(width 0.17145)
		(layer "F.Cu")
		(net "IOM_B_INS_N")
	)
	(segment
		(start 228.5746 -139.937744)
		(end 206.265272 -162.247072)
		(width 0.17145)
		(layer "F.Cu")
		(net "IOM_B_INS_N")
	)
	(segment
		(start 203.373736 -166.605458)
		(end 203.373736 -165.70706)
		(width 0.17145)
		(layer "F.Cu")
		(net "IOM_B_INS_N")
	)
	(segment
		(start 206.268828 -169.50055)
		(end 203.373736 -166.605458)
		(width 0.17145)
		(layer "F.Cu")
		(net "IOM_B_INS_N")
	)
	(segment
		(start 205.65618 -162.247072)
		(end 203.373736 -164.529516)
		(width 0.17145)
		(layer "F.Cu")
		(net "IOM_B_INS_N")
	)
	(segment
		(start 206.265272 -162.247072)
		(end 205.65618 -162.247072)
		(width 0.17145)
		(layer "F.Cu")
		(net "IOM_B_INS_N")
	)
	(segment
		(start 229.154736 -88.374474)
		(end 228.5746 -88.95461)
		(width 0.17145)
		(layer "F.Cu")
		(net "IOM_B_INS_N")
	)
	(segment
		(start 229.154736 -88.193626)
		(end 229.154736 -88.374474)
		(width 0.17145)
		(layer "F.Cu")
		(net "IOM_B_INS_N")
	)
	(segment
		(start 208.023714 -169.50055)
		(end 206.268828 -169.50055)
		(width 0.17145)
		(layer "F.Cu")
		(net "IOM_B_INS_N")
	)
	(segment
		(start 228.5746 -88.95461)
		(end 228.5746 -139.937744)
		(width 0.17145)
		(layer "F.Cu")
		(net "IOM_B_INS_N")
	)
	(via
		(at 229.154736 -88.193626)
		(size 0.5588)
		(drill 0.3048)
		(layers "F.Cu" "B.Cu")
		(net "IOM_B_INS_N")
	)
	(via
		(at 203.373736 -165.70706)
		(size 0.6604)
		(drill 0.3302)
		(layers "F.Cu" "B.Cu")
		(net "IOM_B_INS_N")
	)
	(segment
		(start 227.864162 -79.877158)
		(end 227.864162 -85.341714)
		(width 0.14605)
		(layer "In5.Cu")
		(net "IOM_B_INS_N")
	)
	(segment
		(start 227.864162 -85.341714)
		(end 229.154736 -86.632288)
		(width 0.14605)
		(layer "In5.Cu")
		(net "IOM_B_INS_N")
	)
	(segment
		(start 227.353114 -79.36611)
		(end 227.864162 -79.877158)
		(width 0.14605)
		(layer "In5.Cu")
		(net "IOM_B_INS_N")
	)
	(segment
		(start 228.000052 -71.699882)
		(end 227.353114 -72.34682)
		(width 0.14605)
		(layer "In5.Cu")
		(net "IOM_B_INS_N")
	)
	(segment
		(start 229.154736 -86.632288)
		(end 229.154736 -88.193626)
		(width 0.14605)
		(layer "In5.Cu")
		(net "IOM_B_INS_N")
	)
	(segment
		(start 227.353114 -72.34682)
		(end 227.353114 -79.36611)
		(width 0.14605)
		(layer "In5.Cu")
		(net "IOM_B_INS_N")
	)
	(segment
		(start 228.106986 -87.679784)
		(end 227.9904 -87.79637)
		(width 0.17145)
		(layer "F.Cu")
		(net "IOM_A_INS_N")
	)
	(segment
		(start 206.282544 -161.502344)
		(end 205.427326 -161.502344)
		(width 0.17145)
		(layer "F.Cu")
		(net "IOM_A_INS_N")
	)
	(segment
		(start 202.306936 -164.622988)
		(end 202.306936 -164.71646)
		(width 0.17145)
		(layer "F.Cu")
		(net "IOM_A_INS_N")
	)
	(segment
		(start 227.9904 -87.79637)
		(end 227.9904 -139.794488)
		(width 0.17145)
		(layer "F.Cu")
		(net "IOM_A_INS_N")
	)
	(segment
		(start 227.9904 -139.794488)
		(end 206.282544 -161.502344)
		(width 0.17145)
		(layer "F.Cu")
		(net "IOM_A_INS_N")
	)
	(segment
		(start 228.106986 -87.129366)
		(end 228.106986 -87.679784)
		(width 0.17145)
		(layer "F.Cu")
		(net "IOM_A_INS_N")
	)
	(segment
		(start 205.427326 -161.502598)
		(end 202.306936 -164.622988)
		(width 0.17145)
		(layer "F.Cu")
		(net "IOM_A_INS_N")
	)
	(segment
		(start 206.006446 -170.015154)
		(end 202.306936 -166.315644)
		(width 0.17145)
		(layer "F.Cu")
		(net "IOM_A_INS_N")
	)
	(segment
		(start 210.10499 -170.015154)
		(end 206.006446 -170.015154)
		(width 0.17145)
		(layer "F.Cu")
		(net "IOM_A_INS_N")
	)
	(segment
		(start 202.306936 -166.315644)
		(end 202.306936 -164.71646)
		(width 0.17145)
		(layer "F.Cu")
		(net "IOM_A_INS_N")
	)
	(segment
		(start 205.427326 -161.502344)
		(end 205.427326 -161.502598)
		(width 0.17145)
		(layer "F.Cu")
		(net "IOM_A_INS_N")
	)
	(segment
		(start 212.69706 -169.02938)
		(end 211.090764 -169.02938)
		(width 0.17145)
		(layer "F.Cu")
		(net "IOM_A_INS_N")
	)
	(segment
		(start 211.090764 -169.02938)
		(end 210.10499 -170.015154)
		(width 0.17145)
		(layer "F.Cu")
		(net "IOM_A_INS_N")
	)
	(via
		(at 228.106986 -87.129366)
		(size 0.5588)
		(drill 0.3048)
		(layers "F.Cu" "B.Cu")
		(net "IOM_A_INS_N")
	)
	(via
		(at 202.306936 -164.71646)
		(size 0.6604)
		(drill 0.3302)
		(layers "F.Cu" "B.Cu")
		(net "IOM_A_INS_N")
	)
	(segment
		(start 226.851464 -80.787494)
		(end 227.108258 -81.044288)
		(width 0.14605)
		(layer "In5.Cu")
		(net "IOM_A_INS_N")
	)
	(segment
		(start 226.851464 -71.74865)
		(end 226.851464 -80.787494)
		(width 0.14605)
		(layer "In5.Cu")
		(net "IOM_A_INS_N")
	)
	(segment
		(start 227.108258 -81.044288)
		(end 227.108258 -85.33384)
		(width 0.14605)
		(layer "In5.Cu")
		(net "IOM_A_INS_N")
	)
	(segment
		(start 227.108258 -85.33384)
		(end 228.106986 -86.332568)
		(width 0.14605)
		(layer "In5.Cu")
		(net "IOM_A_INS_N")
	)
	(segment
		(start 228.000052 -70.600062)
		(end 226.851464 -71.74865)
		(width 0.14605)
		(layer "In5.Cu")
		(net "IOM_A_INS_N")
	)
	(segment
		(start 228.106986 -86.332568)
		(end 228.106986 -87.129366)
		(width 0.14605)
		(layer "In5.Cu")
		(net "IOM_A_INS_N")
	)
	(segment
		(start 242.368832 -226.679506)
		(end 242.368832 -227.110036)
		(width 0.17145)
		(layer "F.Cu")
		(net "IO_EXP3_RESET#")
	)
	(segment
		(start 242.368832 -227.600764)
		(end 242.5065 -227.738432)
		(width 0.17145)
		(layer "F.Cu")
		(net "IO_EXP3_RESET#")
	)
	(segment
		(start 242.368832 -227.110036)
		(end 242.368832 -227.600764)
		(width 0.17145)
		(layer "F.Cu")
		(net "IO_EXP3_RESET#")
	)
	(segment
		(start 241.01298 -225.323654)
		(end 242.368832 -226.679506)
		(width 0.17145)
		(layer "F.Cu")
		(net "IO_EXP3_RESET#")
	)
	(segment
		(start 241.01298 -224.34042)
		(end 241.01298 -225.323654)
		(width 0.17145)
		(layer "F.Cu")
		(net "IO_EXP3_RESET#")
	)
	(segment
		(start 242.5065 -227.738432)
		(end 242.5065 -228.219)
		(width 0.17145)
		(layer "F.Cu")
		(net "IO_EXP3_RESET#")
	)
	(via
		(at 242.368832 -227.110036)
		(size 0.6604)
		(drill 0.3302)
		(layers "F.Cu" "B.Cu")
		(net "IO_EXP3_RESET#")
	)
	(segment
		(start 210.679792 -196.36232)
		(end 210.387438 -196.654674)
		(width 0.17145)
		(layer "F.Cu")
		(net "IO_EXP2_HDD_FAULT_INT_N")
	)
	(segment
		(start 210.387438 -196.654674)
		(end 210.387438 -197.282562)
		(width 0.17145)
		(layer "F.Cu")
		(net "IO_EXP2_HDD_FAULT_INT_N")
	)
	(segment
		(start 207.7593 -199.517)
		(end 208.153 -199.517)
		(width 0.17145)
		(layer "F.Cu")
		(net "IO_EXP2_HDD_FAULT_INT_N")
	)
	(segment
		(start 211.6328 -196.36232)
		(end 210.679792 -196.36232)
		(width 0.17145)
		(layer "F.Cu")
		(net "IO_EXP2_HDD_FAULT_INT_N")
	)
	(segment
		(start 208.153 -199.517)
		(end 209.423 -198.247)
		(width 0.17145)
		(layer "F.Cu")
		(net "IO_EXP2_HDD_FAULT_INT_N")
	)
	(segment
		(start 210.387438 -197.282562)
		(end 209.423 -198.247)
		(width 0.17145)
		(layer "F.Cu")
		(net "IO_EXP2_HDD_FAULT_INT_N")
	)
	(via
		(at 209.423 -198.247)
		(size 0.6604)
		(drill 0.3302)
		(layers "F.Cu" "B.Cu")
		(net "IO_EXP2_HDD_FAULT_INT_N")
	)
	(segment
		(start 212.9536 -224.81032)
		(end 212.9536 -226.2124)
		(width 0.17145)
		(layer "F.Cu")
		(net "IO_EXP1_HDD_FAULT_INT_N")
	)
	(segment
		(start 211.201 -227.965)
		(end 211.709 -227.457)
		(width 0.17145)
		(layer "F.Cu")
		(net "IO_EXP1_HDD_FAULT_INT_N")
	)
	(segment
		(start 212.9536 -226.2124)
		(end 211.709 -227.457)
		(width 0.17145)
		(layer "F.Cu")
		(net "IO_EXP1_HDD_FAULT_INT_N")
	)
	(segment
		(start 210.2485 -227.965)
		(end 211.201 -227.965)
		(width 0.17145)
		(layer "F.Cu")
		(net "IO_EXP1_HDD_FAULT_INT_N")
	)
	(via
		(at 211.709 -227.457)
		(size 0.6604)
		(drill 0.3302)
		(layers "F.Cu" "B.Cu")
		(net "IO_EXP1_HDD_FAULT_INT_N")
	)
	(segment
		(start 254.011176 -139.103354)
		(end 254.012954 -139.101576)
		(width 0.17145)
		(layer "F.Cu")
		(net "I2C_SCC_B_SDA")
	)
	(segment
		(start 249.62104 -139.265914)
		(end 249.758454 -139.1285)
		(width 0.17145)
		(layer "F.Cu")
		(net "I2C_SCC_B_SDA")
	)
	(segment
		(start 250.519946 -139.103354)
		(end 250.4948 -139.1285)
		(width 0.17145)
		(layer "F.Cu")
		(net "I2C_SCC_B_SDA")
	)
	(segment
		(start 248.557034 -139.265914)
		(end 249.62104 -139.265914)
		(width 0.17145)
		(layer "F.Cu")
		(net "I2C_SCC_B_SDA")
	)
	(segment
		(start 252.890782 -139.103354)
		(end 254.011176 -139.103354)
		(width 0.17145)
		(layer "F.Cu")
		(net "I2C_SCC_B_SDA")
	)
	(segment
		(start 251.746766 -139.103354)
		(end 252.890782 -139.103354)
		(width 0.17145)
		(layer "F.Cu")
		(net "I2C_SCC_B_SDA")
	)
	(segment
		(start 249.758454 -139.1285)
		(end 250.4948 -139.1285)
		(width 0.17145)
		(layer "F.Cu")
		(net "I2C_SCC_B_SDA")
	)
	(segment
		(start 251.746766 -139.103354)
		(end 250.519946 -139.103354)
		(width 0.17145)
		(layer "F.Cu")
		(net "I2C_SCC_B_SDA")
	)
	(via
		(at 252.890782 -139.103354)
		(size 0.6604)
		(drill 0.3302)
		(layers "F.Cu" "B.Cu")
		(net "I2C_SCC_B_SDA")
	)
	(via
		(at 210.149694 -116.666518)
		(size 0.5588)
		(drill 0.3048)
		(layers "F.Cu" "B.Cu")
		(net "I2C_SCC_B_SDA")
	)
	(via
		(at 254.012954 -139.101576)
		(size 0.5588)
		(drill 0.3048)
		(layers "F.Cu" "B.Cu")
		(net "I2C_SCC_B_SDA")
	)
	(segment
		(start 208.083912 -109.347)
		(end 209.937604 -111.200692)
		(width 0.14605)
		(layer "In2.Cu")
		(net "I2C_SCC_B_SDA")
	)
	(segment
		(start 210.477862 -93.160088)
		(end 208.083912 -95.554038)
		(width 0.14605)
		(layer "In2.Cu")
		(net "I2C_SCC_B_SDA")
	)
	(segment
		(start 209.937604 -111.200692)
		(end 209.937604 -116.454428)
		(width 0.14605)
		(layer "In2.Cu")
		(net "I2C_SCC_B_SDA")
	)
	(segment
		(start 211.800186 -70.600062)
		(end 211.800186 -70.685152)
		(width 0.14605)
		(layer "In2.Cu")
		(net "I2C_SCC_B_SDA")
	)
	(segment
		(start 209.937604 -116.454428)
		(end 210.149694 -116.666518)
		(width 0.14605)
		(layer "In2.Cu")
		(net "I2C_SCC_B_SDA")
	)
	(segment
		(start 211.1502 -80.113378)
		(end 211.24291 -80.206088)
		(width 0.14605)
		(layer "In2.Cu")
		(net "I2C_SCC_B_SDA")
	)
	(segment
		(start 211.800186 -70.685152)
		(end 211.1502 -71.335138)
		(width 0.14605)
		(layer "In2.Cu")
		(net "I2C_SCC_B_SDA")
	)
	(segment
		(start 211.24291 -80.206088)
		(end 211.24291 -81.316322)
		(width 0.14605)
		(layer "In2.Cu")
		(net "I2C_SCC_B_SDA")
	)
	(segment
		(start 211.1502 -71.335138)
		(end 211.1502 -80.113378)
		(width 0.14605)
		(layer "In2.Cu")
		(net "I2C_SCC_B_SDA")
	)
	(segment
		(start 210.477862 -82.08137)
		(end 210.477862 -93.160088)
		(width 0.14605)
		(layer "In2.Cu")
		(net "I2C_SCC_B_SDA")
	)
	(segment
		(start 208.083912 -95.554038)
		(end 208.083912 -109.347)
		(width 0.14605)
		(layer "In2.Cu")
		(net "I2C_SCC_B_SDA")
	)
	(segment
		(start 211.24291 -81.316322)
		(end 210.477862 -82.08137)
		(width 0.14605)
		(layer "In2.Cu")
		(net "I2C_SCC_B_SDA")
	)
	(segment
		(start 248.412 -137.668)
		(end 249.847354 -139.103354)
		(width 0.14605)
		(layer "In5.Cu")
		(net "I2C_SCC_B_SDA")
	)
	(segment
		(start 244.1956 -137.668)
		(end 248.412 -137.668)
		(width 0.14605)
		(layer "In5.Cu")
		(net "I2C_SCC_B_SDA")
	)
	(segment
		(start 249.847354 -139.103354)
		(end 254.011176 -139.103354)
		(width 0.14605)
		(layer "In5.Cu")
		(net "I2C_SCC_B_SDA")
	)
	(segment
		(start 217.78087 -117.85727)
		(end 236.5756 -136.652)
		(width 0.14605)
		(layer "In5.Cu")
		(net "I2C_SCC_B_SDA")
	)
	(segment
		(start 211.340446 -117.85727)
		(end 217.78087 -117.85727)
		(width 0.14605)
		(layer "In5.Cu")
		(net "I2C_SCC_B_SDA")
	)
	(segment
		(start 210.149694 -116.666518)
		(end 211.340446 -117.85727)
		(width 0.14605)
		(layer "In5.Cu")
		(net "I2C_SCC_B_SDA")
	)
	(segment
		(start 254.011176 -139.103354)
		(end 254.012954 -139.101576)
		(width 0.14605)
		(layer "In5.Cu")
		(net "I2C_SCC_B_SDA")
	)
	(segment
		(start 236.5756 -136.652)
		(end 243.1796 -136.652)
		(width 0.14605)
		(layer "In5.Cu")
		(net "I2C_SCC_B_SDA")
	)
	(segment
		(start 243.1796 -136.652)
		(end 244.1956 -137.668)
		(width 0.14605)
		(layer "In5.Cu")
		(net "I2C_SCC_B_SDA")
	)
	(segment
		(start 241.462306 -138.935714)
		(end 242.351814 -138.935714)
		(width 0.17145)
		(layer "F.Cu")
		(net "I2C_SCC_B_SCL")
	)
	(segment
		(start 242.351814 -138.935714)
		(end 242.57 -139.1539)
		(width 0.17145)
		(layer "F.Cu")
		(net "I2C_SCC_B_SCL")
	)
	(segment
		(start 240.20018 -138.935714)
		(end 240.196624 -138.93927)
		(width 0.17145)
		(layer "F.Cu")
		(net "I2C_SCC_B_SCL")
	)
	(segment
		(start 241.462306 -138.935714)
		(end 240.20018 -138.935714)
		(width 0.17145)
		(layer "F.Cu")
		(net "I2C_SCC_B_SCL")
	)
	(segment
		(start 244.416834 -139.265914)
		(end 242.682014 -139.265914)
		(width 0.17145)
		(layer "F.Cu")
		(net "I2C_SCC_B_SCL")
	)
	(segment
		(start 239.155478 -138.93927)
		(end 240.196624 -138.93927)
		(width 0.17145)
		(layer "F.Cu")
		(net "I2C_SCC_B_SCL")
	)
	(segment
		(start 242.682014 -139.265914)
		(end 242.57 -139.1539)
		(width 0.17145)
		(layer "F.Cu")
		(net "I2C_SCC_B_SCL")
	)
	(via
		(at 210.137502 -118.06047)
		(size 0.5588)
		(drill 0.3048)
		(layers "F.Cu" "B.Cu")
		(net "I2C_SCC_B_SCL")
	)
	(via
		(at 240.196624 -138.93927)
		(size 0.6604)
		(drill 0.3302)
		(layers "F.Cu" "B.Cu")
		(net "I2C_SCC_B_SCL")
	)
	(via
		(at 239.155478 -138.93927)
		(size 0.5588)
		(drill 0.3048)
		(layers "F.Cu" "B.Cu")
		(net "I2C_SCC_B_SCL")
	)
	(segment
		(start 210.64855 -70.649338)
		(end 210.64855 -80.146398)
		(width 0.14605)
		(layer "In2.Cu")
		(net "I2C_SCC_B_SCL")
	)
	(segment
		(start 210.64855 -80.146398)
		(end 210.58886 -80.206088)
		(width 0.14605)
		(layer "In2.Cu")
		(net "I2C_SCC_B_SCL")
	)
	(segment
		(start 210.58886 -81.045304)
		(end 209.823812 -81.810352)
		(width 0.14605)
		(layer "In2.Cu")
		(net "I2C_SCC_B_SCL")
	)
	(segment
		(start 209.283554 -111.47171)
		(end 209.283554 -117.206522)
		(width 0.14605)
		(layer "In2.Cu")
		(net "I2C_SCC_B_SCL")
	)
	(segment
		(start 209.823812 -92.88907)
		(end 207.429862 -95.28302)
		(width 0.14605)
		(layer "In2.Cu")
		(net "I2C_SCC_B_SCL")
	)
	(segment
		(start 209.283554 -117.206522)
		(end 210.137502 -118.06047)
		(width 0.14605)
		(layer "In2.Cu")
		(net "I2C_SCC_B_SCL")
	)
	(segment
		(start 207.429862 -95.28302)
		(end 207.429862 -109.618018)
		(width 0.14605)
		(layer "In2.Cu")
		(net "I2C_SCC_B_SCL")
	)
	(segment
		(start 209.823812 -81.810352)
		(end 209.823812 -92.88907)
		(width 0.14605)
		(layer "In2.Cu")
		(net "I2C_SCC_B_SCL")
	)
	(segment
		(start 210.58886 -80.206088)
		(end 210.58886 -81.045304)
		(width 0.14605)
		(layer "In2.Cu")
		(net "I2C_SCC_B_SCL")
	)
	(segment
		(start 211.800186 -69.497702)
		(end 210.64855 -70.649338)
		(width 0.14605)
		(layer "In2.Cu")
		(net "I2C_SCC_B_SCL")
	)
	(segment
		(start 207.429862 -109.618018)
		(end 209.283554 -111.47171)
		(width 0.14605)
		(layer "In2.Cu")
		(net "I2C_SCC_B_SCL")
	)
	(segment
		(start 211.800186 -69.200014)
		(end 211.800186 -69.497702)
		(width 0.14605)
		(layer "In2.Cu")
		(net "I2C_SCC_B_SCL")
	)
	(segment
		(start 238.011208 -137.795)
		(end 236.5248 -137.795)
		(width 0.14605)
		(layer "In5.Cu")
		(net "I2C_SCC_B_SCL")
	)
	(segment
		(start 239.155478 -138.93927)
		(end 238.011208 -137.795)
		(width 0.14605)
		(layer "In5.Cu")
		(net "I2C_SCC_B_SCL")
	)
	(segment
		(start 222.297752 -123.565158)
		(end 222.001842 -123.269248)
		(width 0.14605)
		(layer "In5.Cu")
		(net "I2C_SCC_B_SCL")
	)
	(segment
		(start 217.465148 -118.735348)
		(end 210.81238 -118.735348)
		(width 0.14605)
		(layer "In5.Cu")
		(net "I2C_SCC_B_SCL")
	)
	(segment
		(start 210.81238 -118.735348)
		(end 210.137502 -118.06047)
		(width 0.14605)
		(layer "In5.Cu")
		(net "I2C_SCC_B_SCL")
	)
	(segment
		(start 236.5248 -137.795)
		(end 222.297752 -123.567952)
		(width 0.14605)
		(layer "In5.Cu")
		(net "I2C_SCC_B_SCL")
	)
	(segment
		(start 221.999048 -123.269248)
		(end 217.465148 -118.735348)
		(width 0.14605)
		(layer "In5.Cu")
		(net "I2C_SCC_B_SCL")
	)
	(segment
		(start 222.001842 -123.269248)
		(end 221.999048 -123.269248)
		(width 0.14605)
		(layer "In5.Cu")
		(net "I2C_SCC_B_SCL")
	)
	(segment
		(start 222.297752 -123.567952)
		(end 222.297752 -123.565158)
		(width 0.14605)
		(layer "In5.Cu")
		(net "I2C_SCC_B_SCL")
	)
	(segment
		(start 261.561834 -211.051902)
		(end 260.564376 -210.054444)
		(width 0.17145)
		(layer "F.Cu")
		(net "I2C_DRIVE_B_PWR_SDA")
	)
	(segment
		(start 234.442 -213.99246)
		(end 234.442 -217.36304)
		(width 0.17145)
		(layer "F.Cu")
		(net "I2C_DRIVE_B_PWR_SDA")
	)
	(segment
		(start 238.633 -214.8205)
		(end 238.633 -213.9696)
		(width 0.17145)
		(layer "F.Cu")
		(net "I2C_DRIVE_B_PWR_SDA")
	)
	(segment
		(start 231.652318 -195.6054)
		(end 232.193084 -195.064634)
		(width 0.17145)
		(layer "F.Cu")
		(net "I2C_DRIVE_B_PWR_SDA")
	)
	(segment
		(start 229.5398 -195.6054)
		(end 231.652318 -195.6054)
		(width 0.17145)
		(layer "F.Cu")
		(net "I2C_DRIVE_B_PWR_SDA")
	)
	(segment
		(start 266.347194 -215.941148)
		(end 261.562088 -211.156042)
		(width 0.17145)
		(layer "F.Cu")
		(net "I2C_DRIVE_B_PWR_SDA")
	)
	(segment
		(start 260.564376 -210.054444)
		(end 254.029718 -210.054444)
		(width 0.17145)
		(layer "F.Cu")
		(net "I2C_DRIVE_B_PWR_SDA")
	)
	(segment
		(start 261.562088 -211.156042)
		(end 261.562088 -211.052156)
		(width 0.17145)
		(layer "F.Cu")
		(net "I2C_DRIVE_B_PWR_SDA")
	)
	(segment
		(start 236.68101 -211.75345)
		(end 234.968542 -213.465918)
		(width 0.17145)
		(layer "F.Cu")
		(net "I2C_DRIVE_B_PWR_SDA")
	)
	(segment
		(start 232.193084 -195.034916)
		(end 232.6767 -194.5513)
		(width 0.17145)
		(layer "F.Cu")
		(net "I2C_DRIVE_B_PWR_SDA")
	)
	(segment
		(start 234.86618 -218.58986)
		(end 234.86618 -217.78722)
		(width 0.17145)
		(layer "F.Cu")
		(net "I2C_DRIVE_B_PWR_SDA")
	)
	(segment
		(start 277.370032 -212.859874)
		(end 277.220426 -213.00948)
		(width 0.17145)
		(layer "F.Cu")
		(net "I2C_DRIVE_B_PWR_SDA")
	)
	(segment
		(start 282.83662 -213.494366)
		(end 282.202128 -212.859874)
		(width 0.17145)
		(layer "F.Cu")
		(net "I2C_DRIVE_B_PWR_SDA")
	)
	(segment
		(start 245.321074 -209.112104)
		(end 242.679728 -211.75345)
		(width 0.17145)
		(layer "F.Cu")
		(net "I2C_DRIVE_B_PWR_SDA")
	)
	(segment
		(start 232.6767 -194.5513)
		(end 232.6767 -194.2592)
		(width 0.17145)
		(layer "F.Cu")
		(net "I2C_DRIVE_B_PWR_SDA")
	)
	(segment
		(start 274.289774 -213.00948)
		(end 271.358106 -215.941148)
		(width 0.17145)
		(layer "F.Cu")
		(net "I2C_DRIVE_B_PWR_SDA")
	)
	(segment
		(start 277.220426 -213.00948)
		(end 274.289774 -213.00948)
		(width 0.17145)
		(layer "F.Cu")
		(net "I2C_DRIVE_B_PWR_SDA")
	)
	(segment
		(start 242.679728 -211.75345)
		(end 236.68101 -211.75345)
		(width 0.17145)
		(layer "F.Cu")
		(net "I2C_DRIVE_B_PWR_SDA")
	)
	(segment
		(start 234.442 -217.36304)
		(end 234.86618 -217.78722)
		(width 0.17145)
		(layer "F.Cu")
		(net "I2C_DRIVE_B_PWR_SDA")
	)
	(segment
		(start 234.968542 -213.465918)
		(end 234.442 -213.99246)
		(width 0.17145)
		(layer "F.Cu")
		(net "I2C_DRIVE_B_PWR_SDA")
	)
	(segment
		(start 271.358106 -215.941148)
		(end 266.347194 -215.941148)
		(width 0.17145)
		(layer "F.Cu")
		(net "I2C_DRIVE_B_PWR_SDA")
	)
	(segment
		(start 282.202128 -212.859874)
		(end 277.370032 -212.859874)
		(width 0.17145)
		(layer "F.Cu")
		(net "I2C_DRIVE_B_PWR_SDA")
	)
	(segment
		(start 254.029718 -210.054444)
		(end 253.087378 -209.112104)
		(width 0.17145)
		(layer "F.Cu")
		(net "I2C_DRIVE_B_PWR_SDA")
	)
	(segment
		(start 253.087378 -209.112104)
		(end 245.321074 -209.112104)
		(width 0.17145)
		(layer "F.Cu")
		(net "I2C_DRIVE_B_PWR_SDA")
	)
	(segment
		(start 261.562088 -211.052156)
		(end 261.561834 -211.051902)
		(width 0.17145)
		(layer "F.Cu")
		(net "I2C_DRIVE_B_PWR_SDA")
	)
	(segment
		(start 229.489 -195.5546)
		(end 229.5398 -195.6054)
		(width 0.17145)
		(layer "F.Cu")
		(net "I2C_DRIVE_B_PWR_SDA")
	)
	(segment
		(start 232.193084 -195.064634)
		(end 232.193084 -195.034916)
		(width 0.17145)
		(layer "F.Cu")
		(net "I2C_DRIVE_B_PWR_SDA")
	)
	(via
		(at 234.86618 -217.78722)
		(size 0.5588)
		(drill 0.3048)
		(layers "F.Cu" "B.Cu")
		(net "I2C_DRIVE_B_PWR_SDA")
	)
	(via
		(at 234.968542 -213.465918)
		(size 0.6604)
		(drill 0.3302)
		(layers "F.Cu" "B.Cu")
		(net "I2C_DRIVE_B_PWR_SDA")
	)
	(via
		(at 238.633 -213.9696)
		(size 0.5588)
		(drill 0.3048)
		(layers "F.Cu" "B.Cu")
		(net "I2C_DRIVE_B_PWR_SDA")
	)
	(via
		(at 229.489 -195.5546)
		(size 0.5588)
		(drill 0.3048)
		(layers "F.Cu" "B.Cu")
		(net "I2C_DRIVE_B_PWR_SDA")
	)
	(segment
		(start 238.77905 -201.347578)
		(end 236.999272 -199.5678)
		(width 0.14605)
		(layer "In5.Cu")
		(net "I2C_DRIVE_B_PWR_SDA")
	)
	(segment
		(start 233.045 -197.3326)
		(end 231.79405 -196.08165)
		(width 0.14605)
		(layer "In5.Cu")
		(net "I2C_DRIVE_B_PWR_SDA")
	)
	(segment
		(start 236.999272 -199.5678)
		(end 235.2294 -199.5678)
		(width 0.14605)
		(layer "In5.Cu")
		(net "I2C_DRIVE_B_PWR_SDA")
	)
	(segment
		(start 233.045 -197.3834)
		(end 233.045 -197.3326)
		(width 0.14605)
		(layer "In5.Cu")
		(net "I2C_DRIVE_B_PWR_SDA")
	)
	(segment
		(start 234.86618 -217.78722)
		(end 234.86618 -217.73642)
		(width 0.14605)
		(layer "In5.Cu")
		(net "I2C_DRIVE_B_PWR_SDA")
	)
	(segment
		(start 231.79405 -196.08165)
		(end 230.233982 -196.08165)
		(width 0.14605)
		(layer "In5.Cu")
		(net "I2C_DRIVE_B_PWR_SDA")
	)
	(segment
		(start 229.706932 -195.5546)
		(end 229.489 -195.5546)
		(width 0.14605)
		(layer "In5.Cu")
		(net "I2C_DRIVE_B_PWR_SDA")
	)
	(segment
		(start 238.77905 -213.82355)
		(end 238.77905 -201.347578)
		(width 0.14605)
		(layer "In5.Cu")
		(net "I2C_DRIVE_B_PWR_SDA")
	)
	(segment
		(start 230.233982 -196.08165)
		(end 229.706932 -195.5546)
		(width 0.14605)
		(layer "In5.Cu")
		(net "I2C_DRIVE_B_PWR_SDA")
	)
	(segment
		(start 235.2294 -199.5678)
		(end 233.045 -197.3834)
		(width 0.14605)
		(layer "In5.Cu")
		(net "I2C_DRIVE_B_PWR_SDA")
	)
	(segment
		(start 234.86618 -217.73642)
		(end 238.633 -213.9696)
		(width 0.14605)
		(layer "In5.Cu")
		(net "I2C_DRIVE_B_PWR_SDA")
	)
	(segment
		(start 238.633 -213.9696)
		(end 238.77905 -213.82355)
		(width 0.14605)
		(layer "In5.Cu")
		(net "I2C_DRIVE_B_PWR_SDA")
	)
	(segment
		(start 283.072332 -212.33003)
		(end 273.775424 -212.33003)
		(width 0.17145)
		(layer "F.Cu")
		(net "I2C_DRIVE_B_PWR_SCL")
	)
	(segment
		(start 253.369064 -208.432654)
		(end 245.039388 -208.432654)
		(width 0.17145)
		(layer "F.Cu")
		(net "I2C_DRIVE_B_PWR_SCL")
	)
	(segment
		(start 229.573328 -196.596)
		(end 229.507288 -196.52996)
		(width 0.17145)
		(layer "F.Cu")
		(net "I2C_DRIVE_B_PWR_SCL")
	)
	(segment
		(start 273.775424 -212.33003)
		(end 270.843756 -215.261698)
		(width 0.17145)
		(layer "F.Cu")
		(net "I2C_DRIVE_B_PWR_SCL")
	)
	(segment
		(start 261.516368 -209.582258)
		(end 261.309104 -209.374994)
		(width 0.17145)
		(layer "F.Cu")
		(net "I2C_DRIVE_B_PWR_SCL")
	)
	(segment
		(start 233.72318 -217.78722)
		(end 233.72318 -215.773)
		(width 0.17145)
		(layer "F.Cu")
		(net "I2C_DRIVE_B_PWR_SCL")
	)
	(segment
		(start 261.516368 -210.0453)
		(end 261.516368 -209.582258)
		(width 0.17145)
		(layer "F.Cu")
		(net "I2C_DRIVE_B_PWR_SCL")
	)
	(segment
		(start 266.62888 -215.261698)
		(end 262.241538 -210.874356)
		(width 0.17145)
		(layer "F.Cu")
		(net "I2C_DRIVE_B_PWR_SCL")
	)
	(segment
		(start 262.241538 -210.77047)
		(end 261.516368 -210.0453)
		(width 0.17145)
		(layer "F.Cu")
		(net "I2C_DRIVE_B_PWR_SCL")
	)
	(segment
		(start 230.8225 -196.596)
		(end 229.573328 -196.596)
		(width 0.17145)
		(layer "F.Cu")
		(net "I2C_DRIVE_B_PWR_SCL")
	)
	(segment
		(start 237.488476 -214.822024)
		(end 236.526324 -214.822024)
		(width 0.17145)
		(layer "F.Cu")
		(net "I2C_DRIVE_B_PWR_SCL")
	)
	(segment
		(start 233.72318 -218.58986)
		(end 233.72318 -217.78722)
		(width 0.17145)
		(layer "F.Cu")
		(net "I2C_DRIVE_B_PWR_SCL")
	)
	(segment
		(start 284.236668 -213.494366)
		(end 283.072332 -212.33003)
		(width 0.17145)
		(layer "F.Cu")
		(net "I2C_DRIVE_B_PWR_SCL")
	)
	(segment
		(start 261.309104 -209.374994)
		(end 254.311404 -209.374994)
		(width 0.17145)
		(layer "F.Cu")
		(net "I2C_DRIVE_B_PWR_SCL")
	)
	(segment
		(start 245.039388 -208.432654)
		(end 242.398042 -211.074)
		(width 0.17145)
		(layer "F.Cu")
		(net "I2C_DRIVE_B_PWR_SCL")
	)
	(segment
		(start 262.241538 -210.874356)
		(end 262.241538 -210.77047)
		(width 0.17145)
		(layer "F.Cu")
		(net "I2C_DRIVE_B_PWR_SCL")
	)
	(segment
		(start 233.72318 -213.750144)
		(end 233.72318 -215.773)
		(width 0.17145)
		(layer "F.Cu")
		(net "I2C_DRIVE_B_PWR_SCL")
	)
	(segment
		(start 236.399324 -211.074)
		(end 233.72318 -213.750144)
		(width 0.17145)
		(layer "F.Cu")
		(net "I2C_DRIVE_B_PWR_SCL")
	)
	(segment
		(start 242.398042 -211.074)
		(end 236.399324 -211.074)
		(width 0.17145)
		(layer "F.Cu")
		(net "I2C_DRIVE_B_PWR_SCL")
	)
	(segment
		(start 237.49 -214.8205)
		(end 237.488476 -214.822024)
		(width 0.17145)
		(layer "F.Cu")
		(net "I2C_DRIVE_B_PWR_SCL")
	)
	(segment
		(start 270.843756 -215.261698)
		(end 266.62888 -215.261698)
		(width 0.17145)
		(layer "F.Cu")
		(net "I2C_DRIVE_B_PWR_SCL")
	)
	(segment
		(start 254.311404 -209.374994)
		(end 253.369064 -208.432654)
		(width 0.17145)
		(layer "F.Cu")
		(net "I2C_DRIVE_B_PWR_SCL")
	)
	(via
		(at 233.72318 -215.773)
		(size 0.6604)
		(drill 0.3302)
		(layers "F.Cu" "B.Cu")
		(net "I2C_DRIVE_B_PWR_SCL")
	)
	(via
		(at 229.507288 -196.52996)
		(size 0.5588)
		(drill 0.3048)
		(layers "F.Cu" "B.Cu")
		(net "I2C_DRIVE_B_PWR_SCL")
	)
	(via
		(at 233.72318 -217.78722)
		(size 0.5588)
		(drill 0.3048)
		(layers "F.Cu" "B.Cu")
		(net "I2C_DRIVE_B_PWR_SCL")
	)
	(via
		(at 236.526324 -214.822024)
		(size 0.5588)
		(drill 0.3048)
		(layers "F.Cu" "B.Cu")
		(net "I2C_DRIVE_B_PWR_SCL")
	)
	(segment
		(start 233.72318 -217.625168)
		(end 236.526324 -214.822024)
		(width 0.14605)
		(layer "In5.Cu")
		(net "I2C_DRIVE_B_PWR_SCL")
	)
	(segment
		(start 233.72318 -217.78722)
		(end 233.72318 -217.625168)
		(width 0.14605)
		(layer "In5.Cu")
		(net "I2C_DRIVE_B_PWR_SCL")
	)
	(segment
		(start 231.503982 -196.76745)
		(end 234.958382 -200.22185)
		(width 0.14605)
		(layer "In5.Cu")
		(net "I2C_DRIVE_B_PWR_SCL")
	)
	(segment
		(start 234.958382 -200.22185)
		(end 236.728254 -200.22185)
		(width 0.14605)
		(layer "In5.Cu")
		(net "I2C_DRIVE_B_PWR_SCL")
	)
	(segment
		(start 229.507288 -196.52996)
		(end 229.5144 -196.52996)
		(width 0.14605)
		(layer "In5.Cu")
		(net "I2C_DRIVE_B_PWR_SCL")
	)
	(segment
		(start 229.55504 -196.5706)
		(end 229.579932 -196.5706)
		(width 0.14605)
		(layer "In5.Cu")
		(net "I2C_DRIVE_B_PWR_SCL")
	)
	(segment
		(start 236.728254 -200.22185)
		(end 238.125 -201.618596)
		(width 0.14605)
		(layer "In5.Cu")
		(net "I2C_DRIVE_B_PWR_SCL")
	)
	(segment
		(start 229.5144 -196.52996)
		(end 229.55504 -196.5706)
		(width 0.14605)
		(layer "In5.Cu")
		(net "I2C_DRIVE_B_PWR_SCL")
	)
	(segment
		(start 229.776782 -196.76745)
		(end 231.503982 -196.76745)
		(width 0.14605)
		(layer "In5.Cu")
		(net "I2C_DRIVE_B_PWR_SCL")
	)
	(segment
		(start 238.125 -201.618596)
		(end 238.125 -213.223348)
		(width 0.14605)
		(layer "In5.Cu")
		(net "I2C_DRIVE_B_PWR_SCL")
	)
	(segment
		(start 238.125 -213.223348)
		(end 236.526324 -214.822024)
		(width 0.14605)
		(layer "In5.Cu")
		(net "I2C_DRIVE_B_PWR_SCL")
	)
	(segment
		(start 229.579932 -196.5706)
		(end 229.776782 -196.76745)
		(width 0.14605)
		(layer "In5.Cu")
		(net "I2C_DRIVE_B_PWR_SCL")
	)
	(segment
		(start 268.6685 -212.8012)
		(end 268.6685 -212.359748)
		(width 0.17145)
		(layer "F.Cu")
		(net "I2C_DRIVE_B_INS_SDA")
	)
	(segment
		(start 281.199844 -211.057744)
		(end 277.223982 -211.057744)
		(width 0.17145)
		(layer "F.Cu")
		(net "I2C_DRIVE_B_INS_SDA")
	)
	(segment
		(start 205.19263 -232.148634)
		(end 202.850496 -234.490768)
		(width 0.17145)
		(layer "F.Cu")
		(net "I2C_DRIVE_B_INS_SDA")
	)
	(segment
		(start 210.93938 -234.74172)
		(end 210.93938 -233.02976)
		(width 0.17145)
		(layer "F.Cu")
		(net "I2C_DRIVE_B_INS_SDA")
	)
	(segment
		(start 277.223982 -211.057744)
		(end 277.220426 -211.0613)
		(width 0.17145)
		(layer "F.Cu")
		(net "I2C_DRIVE_B_INS_SDA")
	)
	(segment
		(start 253.65075 -207.753204)
		(end 244.60327 -207.753204)
		(width 0.17145)
		(layer "F.Cu")
		(net "I2C_DRIVE_B_INS_SDA")
	)
	(segment
		(start 254.59309 -208.695544)
		(end 253.65075 -207.753204)
		(width 0.17145)
		(layer "F.Cu")
		(net "I2C_DRIVE_B_INS_SDA")
	)
	(segment
		(start 244.60327 -207.753204)
		(end 243.577618 -208.778856)
		(width 0.17145)
		(layer "F.Cu")
		(net "I2C_DRIVE_B_INS_SDA")
	)
	(segment
		(start 237.756446 -208.778856)
		(end 239.157256 -208.778856)
		(width 0.17145)
		(layer "F.Cu")
		(net "I2C_DRIVE_B_INS_SDA")
	)
	(segment
		(start 268.6685 -212.359748)
		(end 268.249654 -211.940902)
		(width 0.17145)
		(layer "F.Cu")
		(net "I2C_DRIVE_B_INS_SDA")
	)
	(segment
		(start 206.75092 -164.38626)
		(end 206.75092 -164.44722)
		(width 0.17145)
		(layer "F.Cu")
		(net "I2C_DRIVE_B_INS_SDA")
	)
	(segment
		(start 210.93938 -233.02976)
		(end 210.058254 -232.148634)
		(width 0.17145)
		(layer "F.Cu")
		(net "I2C_DRIVE_B_INS_SDA")
	)
	(segment
		(start 207.10652 -204.978)
		(end 207.09382 -204.9907)
		(width 0.17145)
		(layer "F.Cu")
		(net "I2C_DRIVE_B_INS_SDA")
	)
	(segment
		(start 203.022962 -235.226098)
		(end 203.022962 -235.533184)
		(width 0.17145)
		(layer "F.Cu")
		(net "I2C_DRIVE_B_INS_SDA")
	)
	(segment
		(start 281.836622 -211.694522)
		(end 281.199844 -211.057744)
		(width 0.17145)
		(layer "F.Cu")
		(net "I2C_DRIVE_B_INS_SDA")
	)
	(segment
		(start 237.61319 -208.6356)
		(end 237.756446 -208.778856)
		(width 0.17145)
		(layer "F.Cu")
		(net "I2C_DRIVE_B_INS_SDA")
	)
	(segment
		(start 268.249654 -211.940902)
		(end 266.785598 -211.940902)
		(width 0.17145)
		(layer "F.Cu")
		(net "I2C_DRIVE_B_INS_SDA")
	)
	(segment
		(start 269.845536 -212.8012)
		(end 268.6685 -212.8012)
		(width 0.17145)
		(layer "F.Cu")
		(net "I2C_DRIVE_B_INS_SDA")
	)
	(segment
		(start 202.850496 -234.490768)
		(end 202.850496 -235.053632)
		(width 0.17145)
		(layer "F.Cu")
		(net "I2C_DRIVE_B_INS_SDA")
	)
	(segment
		(start 266.785598 -211.940902)
		(end 263.54024 -208.695544)
		(width 0.17145)
		(layer "F.Cu")
		(net "I2C_DRIVE_B_INS_SDA")
	)
	(segment
		(start 277.220426 -211.0613)
		(end 271.585436 -211.0613)
		(width 0.17145)
		(layer "F.Cu")
		(net "I2C_DRIVE_B_INS_SDA")
	)
	(segment
		(start 208.59496 -164.38626)
		(end 206.75092 -164.38626)
		(width 0.17145)
		(layer "F.Cu")
		(net "I2C_DRIVE_B_INS_SDA")
	)
	(segment
		(start 208.9785 -204.978)
		(end 207.10652 -204.978)
		(width 0.17145)
		(layer "F.Cu")
		(net "I2C_DRIVE_B_INS_SDA")
	)
	(segment
		(start 202.850496 -235.053632)
		(end 203.022962 -235.226098)
		(width 0.17145)
		(layer "F.Cu")
		(net "I2C_DRIVE_B_INS_SDA")
	)
	(segment
		(start 271.585436 -211.0613)
		(end 269.845536 -212.8012)
		(width 0.17145)
		(layer "F.Cu")
		(net "I2C_DRIVE_B_INS_SDA")
	)
	(segment
		(start 243.577618 -208.778856)
		(end 239.157256 -208.778856)
		(width 0.17145)
		(layer "F.Cu")
		(net "I2C_DRIVE_B_INS_SDA")
	)
	(segment
		(start 210.058254 -232.148634)
		(end 205.19263 -232.148634)
		(width 0.17145)
		(layer "F.Cu")
		(net "I2C_DRIVE_B_INS_SDA")
	)
	(segment
		(start 263.54024 -208.695544)
		(end 254.59309 -208.695544)
		(width 0.17145)
		(layer "F.Cu")
		(net "I2C_DRIVE_B_INS_SDA")
	)
	(via
		(at 206.75092 -164.44722)
		(size 0.5588)
		(drill 0.3048)
		(layers "F.Cu" "B.Cu")
		(net "I2C_DRIVE_B_INS_SDA")
	)
	(via
		(at 239.157256 -208.778856)
		(size 0.6604)
		(drill 0.3302)
		(layers "F.Cu" "B.Cu")
		(net "I2C_DRIVE_B_INS_SDA")
	)
	(via
		(at 207.09382 -204.9907)
		(size 0.5588)
		(drill 0.3048)
		(layers "F.Cu" "B.Cu")
		(net "I2C_DRIVE_B_INS_SDA")
	)
	(via
		(at 237.61319 -208.6356)
		(size 0.5588)
		(drill 0.3048)
		(layers "F.Cu" "B.Cu")
		(net "I2C_DRIVE_B_INS_SDA")
	)
	(via
		(at 203.022962 -235.533184)
		(size 0.5588)
		(drill 0.3048)
		(layers "F.Cu" "B.Cu")
		(net "I2C_DRIVE_B_INS_SDA")
	)
	(segment
		(start 203.06919 -235.533184)
		(end 203.022962 -235.533184)
		(width 0.14605)
		(layer "In2.Cu")
		(net "I2C_DRIVE_B_INS_SDA")
	)
	(segment
		(start 206.462122 -205.622398)
		(end 206.462122 -215.476328)
		(width 0.14605)
		(layer "In2.Cu")
		(net "I2C_DRIVE_B_INS_SDA")
	)
	(segment
		(start 205.787752 -216.150952)
		(end 205.787244 -216.15146)
		(width 0.14605)
		(layer "In2.Cu")
		(net "I2C_DRIVE_B_INS_SDA")
	)
	(segment
		(start 206.79664 -204.69352)
		(end 207.09382 -204.9907)
		(width 0.14605)
		(layer "In2.Cu")
		(net "I2C_DRIVE_B_INS_SDA")
	)
	(segment
		(start 202.708256 -224.530666)
		(end 202.708256 -235.17225)
		(width 0.14605)
		(layer "In2.Cu")
		(net "I2C_DRIVE_B_INS_SDA")
	)
	(segment
		(start 205.797658 -168.776396)
		(end 206.79664 -169.775378)
		(width 0.14605)
		(layer "In2.Cu")
		(net "I2C_DRIVE_B_INS_SDA")
	)
	(segment
		(start 206.79664 -169.775378)
		(end 206.79664 -204.69352)
		(width 0.14605)
		(layer "In2.Cu")
		(net "I2C_DRIVE_B_INS_SDA")
	)
	(segment
		(start 205.797658 -165.400482)
		(end 205.797658 -168.776396)
		(width 0.14605)
		(layer "In2.Cu")
		(net "I2C_DRIVE_B_INS_SDA")
	)
	(segment
		(start 202.708256 -235.17225)
		(end 203.06919 -235.533184)
		(width 0.14605)
		(layer "In2.Cu")
		(net "I2C_DRIVE_B_INS_SDA")
	)
	(segment
		(start 207.09382 -204.9907)
		(end 206.462122 -205.622398)
		(width 0.14605)
		(layer "In2.Cu")
		(net "I2C_DRIVE_B_INS_SDA")
	)
	(segment
		(start 205.787244 -217.235024)
		(end 205.787498 -217.235278)
		(width 0.14605)
		(layer "In2.Cu")
		(net "I2C_DRIVE_B_INS_SDA")
	)
	(segment
		(start 205.787244 -216.15146)
		(end 205.787244 -217.235024)
		(width 0.14605)
		(layer "In2.Cu")
		(net "I2C_DRIVE_B_INS_SDA")
	)
	(segment
		(start 205.787752 -216.150698)
		(end 205.787752 -216.150952)
		(width 0.14605)
		(layer "In2.Cu")
		(net "I2C_DRIVE_B_INS_SDA")
	)
	(segment
		(start 206.462122 -215.476328)
		(end 205.787752 -216.150698)
		(width 0.14605)
		(layer "In2.Cu")
		(net "I2C_DRIVE_B_INS_SDA")
	)
	(segment
		(start 205.787498 -221.451424)
		(end 202.708256 -224.530666)
		(width 0.14605)
		(layer "In2.Cu")
		(net "I2C_DRIVE_B_INS_SDA")
	)
	(segment
		(start 206.75092 -164.44722)
		(end 205.797658 -165.400482)
		(width 0.14605)
		(layer "In2.Cu")
		(net "I2C_DRIVE_B_INS_SDA")
	)
	(segment
		(start 205.787498 -217.235278)
		(end 205.787498 -221.451424)
		(width 0.14605)
		(layer "In2.Cu")
		(net "I2C_DRIVE_B_INS_SDA")
	)
	(segment
		(start 211.210652 -205.317852)
		(end 211.743798 -205.850998)
		(width 0.14605)
		(layer "In5.Cu")
		(net "I2C_DRIVE_B_INS_SDA")
	)
	(segment
		(start 220.095064 -205.850998)
		(end 220.457014 -205.489048)
		(width 0.14605)
		(layer "In5.Cu")
		(net "I2C_DRIVE_B_INS_SDA")
	)
	(segment
		(start 229.818692 -204.65923)
		(end 236.051598 -204.65923)
		(width 0.14605)
		(layer "In5.Cu")
		(net "I2C_DRIVE_B_INS_SDA")
	)
	(segment
		(start 229.075742 -204.66685)
		(end 229.811072 -204.66685)
		(width 0.14605)
		(layer "In5.Cu")
		(net "I2C_DRIVE_B_INS_SDA")
	)
	(segment
		(start 207.420972 -205.317852)
		(end 211.210652 -205.317852)
		(width 0.14605)
		(layer "In5.Cu")
		(net "I2C_DRIVE_B_INS_SDA")
	)
	(segment
		(start 207.09382 -204.9907)
		(end 207.420972 -205.317852)
		(width 0.14605)
		(layer "In5.Cu")
		(net "I2C_DRIVE_B_INS_SDA")
	)
	(segment
		(start 228.253544 -205.489048)
		(end 229.075742 -204.66685)
		(width 0.14605)
		(layer "In5.Cu")
		(net "I2C_DRIVE_B_INS_SDA")
	)
	(segment
		(start 220.457014 -205.489048)
		(end 228.253544 -205.489048)
		(width 0.14605)
		(layer "In5.Cu")
		(net "I2C_DRIVE_B_INS_SDA")
	)
	(segment
		(start 236.051598 -204.65923)
		(end 237.081568 -205.6892)
		(width 0.14605)
		(layer "In5.Cu")
		(net "I2C_DRIVE_B_INS_SDA")
	)
	(segment
		(start 229.811072 -204.66685)
		(end 229.818692 -204.65923)
		(width 0.14605)
		(layer "In5.Cu")
		(net "I2C_DRIVE_B_INS_SDA")
	)
	(segment
		(start 237.081568 -205.6892)
		(end 237.081568 -208.103978)
		(width 0.14605)
		(layer "In5.Cu")
		(net "I2C_DRIVE_B_INS_SDA")
	)
	(segment
		(start 211.743798 -205.850998)
		(end 220.095064 -205.850998)
		(width 0.14605)
		(layer "In5.Cu")
		(net "I2C_DRIVE_B_INS_SDA")
	)
	(segment
		(start 237.081568 -208.103978)
		(end 237.61319 -208.6356)
		(width 0.14605)
		(layer "In5.Cu")
		(net "I2C_DRIVE_B_INS_SDA")
	)
	(segment
		(start 263.821926 -208.016094)
		(end 254.874776 -208.016094)
		(width 0.17145)
		(layer "F.Cu")
		(net "I2C_DRIVE_B_INS_SCL")
	)
	(segment
		(start 208.9785 -205.994)
		(end 207.136492 -205.994)
		(width 0.17145)
		(layer "F.Cu")
		(net "I2C_DRIVE_B_INS_SCL")
	)
	(segment
		(start 268.6685 -210.924394)
		(end 268.331442 -211.261452)
		(width 0.17145)
		(layer "F.Cu")
		(net "I2C_DRIVE_B_INS_SCL")
	)
	(segment
		(start 208.59496 -165.40226)
		(end 206.83728 -165.40226)
		(width 0.17145)
		(layer "F.Cu")
		(net "I2C_DRIVE_B_INS_SCL")
	)
	(segment
		(start 268.70025 -210.38185)
		(end 268.6685 -210.4136)
		(width 0.17145)
		(layer "F.Cu")
		(net "I2C_DRIVE_B_INS_SCL")
	)
	(segment
		(start 254.874776 -208.016094)
		(end 253.932436 -207.073754)
		(width 0.17145)
		(layer "F.Cu")
		(net "I2C_DRIVE_B_INS_SCL")
	)
	(segment
		(start 283.23667 -211.694522)
		(end 282.072842 -210.530694)
		(width 0.17145)
		(layer "F.Cu")
		(net "I2C_DRIVE_B_INS_SCL")
	)
	(segment
		(start 206.83728 -165.40226)
		(end 206.83728 -165.38448)
		(width 0.17145)
		(layer "F.Cu")
		(net "I2C_DRIVE_B_INS_SCL")
	)
	(segment
		(start 244.321584 -207.073754)
		(end 243.37518 -208.020158)
		(width 0.17145)
		(layer "F.Cu")
		(net "I2C_DRIVE_B_INS_SCL")
	)
	(segment
		(start 242.250468 -208.020158)
		(end 237.211362 -208.020158)
		(width 0.17145)
		(layer "F.Cu")
		(net "I2C_DRIVE_B_INS_SCL")
	)
	(segment
		(start 205.474316 -232.828084)
		(end 203.5302 -234.7722)
		(width 0.17145)
		(layer "F.Cu")
		(net "I2C_DRIVE_B_INS_SCL")
	)
	(segment
		(start 268.331442 -211.261452)
		(end 267.067284 -211.261452)
		(width 0.17145)
		(layer "F.Cu")
		(net "I2C_DRIVE_B_INS_SCL")
	)
	(segment
		(start 237.211362 -208.020158)
		(end 236.57052 -208.661)
		(width 0.17145)
		(layer "F.Cu")
		(net "I2C_DRIVE_B_INS_SCL")
	)
	(segment
		(start 268.6685 -210.4136)
		(end 268.6685 -210.924394)
		(width 0.17145)
		(layer "F.Cu")
		(net "I2C_DRIVE_B_INS_SCL")
	)
	(segment
		(start 243.37518 -208.020158)
		(end 242.250468 -208.020158)
		(width 0.17145)
		(layer "F.Cu")
		(net "I2C_DRIVE_B_INS_SCL")
	)
	(segment
		(start 277.220426 -210.38185)
		(end 268.70025 -210.38185)
		(width 0.17145)
		(layer "F.Cu")
		(net "I2C_DRIVE_B_INS_SCL")
	)
	(segment
		(start 209.30616 -232.828084)
		(end 205.474316 -232.828084)
		(width 0.17145)
		(layer "F.Cu")
		(net "I2C_DRIVE_B_INS_SCL")
	)
	(segment
		(start 267.067284 -211.261452)
		(end 263.821926 -208.016094)
		(width 0.17145)
		(layer "F.Cu")
		(net "I2C_DRIVE_B_INS_SCL")
	)
	(segment
		(start 282.072842 -210.530694)
		(end 277.36927 -210.530694)
		(width 0.17145)
		(layer "F.Cu")
		(net "I2C_DRIVE_B_INS_SCL")
	)
	(segment
		(start 209.92338 -233.445304)
		(end 209.30616 -232.828084)
		(width 0.17145)
		(layer "F.Cu")
		(net "I2C_DRIVE_B_INS_SCL")
	)
	(segment
		(start 277.36927 -210.530694)
		(end 277.220426 -210.38185)
		(width 0.17145)
		(layer "F.Cu")
		(net "I2C_DRIVE_B_INS_SCL")
	)
	(segment
		(start 253.932436 -207.073754)
		(end 244.321584 -207.073754)
		(width 0.17145)
		(layer "F.Cu")
		(net "I2C_DRIVE_B_INS_SCL")
	)
	(segment
		(start 207.136492 -205.994)
		(end 207.129126 -206.001366)
		(width 0.17145)
		(layer "F.Cu")
		(net "I2C_DRIVE_B_INS_SCL")
	)
	(segment
		(start 209.92338 -234.74172)
		(end 209.92338 -233.445304)
		(width 0.17145)
		(layer "F.Cu")
		(net "I2C_DRIVE_B_INS_SCL")
	)
	(via
		(at 203.5302 -234.7722)
		(size 0.5588)
		(drill 0.3048)
		(layers "F.Cu" "B.Cu")
		(net "I2C_DRIVE_B_INS_SCL")
	)
	(via
		(at 242.250468 -208.020158)
		(size 0.6604)
		(drill 0.3302)
		(layers "F.Cu" "B.Cu")
		(net "I2C_DRIVE_B_INS_SCL")
	)
	(via
		(at 206.83728 -165.38448)
		(size 0.5588)
		(drill 0.3048)
		(layers "F.Cu" "B.Cu")
		(net "I2C_DRIVE_B_INS_SCL")
	)
	(via
		(at 236.57052 -208.661)
		(size 0.5588)
		(drill 0.3048)
		(layers "F.Cu" "B.Cu")
		(net "I2C_DRIVE_B_INS_SCL")
	)
	(via
		(at 207.129126 -206.001366)
		(size 0.5588)
		(drill 0.3048)
		(layers "F.Cu" "B.Cu")
		(net "I2C_DRIVE_B_INS_SCL")
	)
	(segment
		(start 206.441802 -216.421716)
		(end 206.441802 -216.42197)
		(width 0.14605)
		(layer "In2.Cu")
		(net "I2C_DRIVE_B_INS_SCL")
	)
	(segment
		(start 206.441548 -216.96426)
		(end 206.441548 -221.722442)
		(width 0.14605)
		(layer "In2.Cu")
		(net "I2C_DRIVE_B_INS_SCL")
	)
	(segment
		(start 206.441802 -216.42197)
		(end 206.441294 -216.422478)
		(width 0.14605)
		(layer "In2.Cu")
		(net "I2C_DRIVE_B_INS_SCL")
	)
	(segment
		(start 206.451708 -168.505378)
		(end 207.45069 -169.50436)
		(width 0.14605)
		(layer "In2.Cu")
		(net "I2C_DRIVE_B_INS_SCL")
	)
	(segment
		(start 203.5048 -234.7468)
		(end 203.5302 -234.7722)
		(width 0.14605)
		(layer "In2.Cu")
		(net "I2C_DRIVE_B_INS_SCL")
	)
	(segment
		(start 207.129126 -215.734392)
		(end 206.441802 -216.421716)
		(width 0.14605)
		(layer "In2.Cu")
		(net "I2C_DRIVE_B_INS_SCL")
	)
	(segment
		(start 207.129126 -206.001366)
		(end 207.129126 -215.734392)
		(width 0.14605)
		(layer "In2.Cu")
		(net "I2C_DRIVE_B_INS_SCL")
	)
	(segment
		(start 207.748124 -204.719936)
		(end 207.748124 -205.382368)
		(width 0.14605)
		(layer "In2.Cu")
		(net "I2C_DRIVE_B_INS_SCL")
	)
	(segment
		(start 207.45069 -204.422502)
		(end 207.748124 -204.719936)
		(width 0.14605)
		(layer "In2.Cu")
		(net "I2C_DRIVE_B_INS_SCL")
	)
	(segment
		(start 207.45069 -169.50436)
		(end 207.45069 -204.422502)
		(width 0.14605)
		(layer "In2.Cu")
		(net "I2C_DRIVE_B_INS_SCL")
	)
	(segment
		(start 203.5048 -224.65919)
		(end 203.5048 -234.7468)
		(width 0.14605)
		(layer "In2.Cu")
		(net "I2C_DRIVE_B_INS_SCL")
	)
	(segment
		(start 206.441294 -216.422478)
		(end 206.441294 -216.964006)
		(width 0.14605)
		(layer "In2.Cu")
		(net "I2C_DRIVE_B_INS_SCL")
	)
	(segment
		(start 207.748124 -205.382368)
		(end 207.129126 -206.001366)
		(width 0.14605)
		(layer "In2.Cu")
		(net "I2C_DRIVE_B_INS_SCL")
	)
	(segment
		(start 206.451708 -165.770052)
		(end 206.451708 -168.505378)
		(width 0.14605)
		(layer "In2.Cu")
		(net "I2C_DRIVE_B_INS_SCL")
	)
	(segment
		(start 206.83728 -165.38448)
		(end 206.451708 -165.770052)
		(width 0.14605)
		(layer "In2.Cu")
		(net "I2C_DRIVE_B_INS_SCL")
	)
	(segment
		(start 206.441294 -216.964006)
		(end 206.441548 -216.96426)
		(width 0.14605)
		(layer "In2.Cu")
		(net "I2C_DRIVE_B_INS_SCL")
	)
	(segment
		(start 206.441548 -221.722442)
		(end 203.5048 -224.65919)
		(width 0.14605)
		(layer "In2.Cu")
		(net "I2C_DRIVE_B_INS_SCL")
	)
	(segment
		(start 236.081824 -208.172304)
		(end 236.081824 -205.6384)
		(width 0.14605)
		(layer "In5.Cu")
		(net "I2C_DRIVE_B_INS_SCL")
	)
	(segment
		(start 220.366082 -206.505048)
		(end 211.47278 -206.505048)
		(width 0.14605)
		(layer "In5.Cu")
		(net "I2C_DRIVE_B_INS_SCL")
	)
	(segment
		(start 229.34676 -205.3209)
		(end 228.524562 -206.143098)
		(width 0.14605)
		(layer "In5.Cu")
		(net "I2C_DRIVE_B_INS_SCL")
	)
	(segment
		(start 230.08971 -205.31328)
		(end 230.08209 -205.3209)
		(width 0.14605)
		(layer "In5.Cu")
		(net "I2C_DRIVE_B_INS_SCL")
	)
	(segment
		(start 230.08209 -205.3209)
		(end 229.34676 -205.3209)
		(width 0.14605)
		(layer "In5.Cu")
		(net "I2C_DRIVE_B_INS_SCL")
	)
	(segment
		(start 236.57052 -208.661)
		(end 236.081824 -208.172304)
		(width 0.14605)
		(layer "In5.Cu")
		(net "I2C_DRIVE_B_INS_SCL")
	)
	(segment
		(start 235.756704 -205.31328)
		(end 230.08971 -205.31328)
		(width 0.14605)
		(layer "In5.Cu")
		(net "I2C_DRIVE_B_INS_SCL")
	)
	(segment
		(start 220.728032 -206.143098)
		(end 220.366082 -206.505048)
		(width 0.14605)
		(layer "In5.Cu")
		(net "I2C_DRIVE_B_INS_SCL")
	)
	(segment
		(start 228.524562 -206.143098)
		(end 220.728032 -206.143098)
		(width 0.14605)
		(layer "In5.Cu")
		(net "I2C_DRIVE_B_INS_SCL")
	)
	(segment
		(start 236.081824 -205.6384)
		(end 235.756704 -205.31328)
		(width 0.14605)
		(layer "In5.Cu")
		(net "I2C_DRIVE_B_INS_SCL")
	)
	(segment
		(start 211.47278 -206.505048)
		(end 210.969098 -206.001366)
		(width 0.14605)
		(layer "In5.Cu")
		(net "I2C_DRIVE_B_INS_SCL")
	)
	(segment
		(start 210.969098 -206.001366)
		(end 207.129126 -206.001366)
		(width 0.14605)
		(layer "In5.Cu")
		(net "I2C_DRIVE_B_INS_SCL")
	)
	(segment
		(start 265.728196 -208.499456)
		(end 268.380718 -208.499456)
		(width 0.17145)
		(layer "F.Cu")
		(net "I2C_DRIVE_B_FLT_LED_SDA")
	)
	(segment
		(start 224.914206 -222.656654)
		(end 224.914206 -221.273624)
		(width 0.17145)
		(layer "F.Cu")
		(net "I2C_DRIVE_B_FLT_LED_SDA")
	)
	(segment
		(start 224.914206 -216.03462)
		(end 227.005134 -213.943692)
		(width 0.17145)
		(layer "F.Cu")
		(net "I2C_DRIVE_B_FLT_LED_SDA")
	)
	(segment
		(start 220.1926 -91.432634)
		(end 223.376998 -94.617032)
		(width 0.17145)
		(layer "F.Cu")
		(net "I2C_DRIVE_B_FLT_LED_SDA")
	)
	(segment
		(start 255.156462 -207.336644)
		(end 264.565384 -207.336644)
		(width 0.17145)
		(layer "F.Cu")
		(net "I2C_DRIVE_B_FLT_LED_SDA")
	)
	(segment
		(start 224.798382 -138.684508)
		(end 198.8058 -164.67709)
		(width 0.17145)
		(layer "F.Cu")
		(net "I2C_DRIVE_B_FLT_LED_SDA")
	)
	(segment
		(start 268.711172 -209.402172)
		(end 277.554182 -209.402172)
		(width 0.17145)
		(layer "F.Cu")
		(net "I2C_DRIVE_B_FLT_LED_SDA")
	)
	(segment
		(start 277.696422 -209.259932)
		(end 282.202128 -209.259932)
		(width 0.17145)
		(layer "F.Cu")
		(net "I2C_DRIVE_B_FLT_LED_SDA")
	)
	(segment
		(start 221.1197 -195.58)
		(end 221.617794 -195.58)
		(width 0.17145)
		(layer "F.Cu")
		(net "I2C_DRIVE_B_FLT_LED_SDA")
	)
	(segment
		(start 254.214122 -206.394304)
		(end 255.156462 -207.336644)
		(width 0.17145)
		(layer "F.Cu")
		(net "I2C_DRIVE_B_FLT_LED_SDA")
	)
	(segment
		(start 223.138492 -224.268284)
		(end 223.302576 -224.268284)
		(width 0.17145)
		(layer "F.Cu")
		(net "I2C_DRIVE_B_FLT_LED_SDA")
	)
	(segment
		(start 264.565384 -207.336644)
		(end 265.728196 -208.499456)
		(width 0.17145)
		(layer "F.Cu")
		(net "I2C_DRIVE_B_FLT_LED_SDA")
	)
	(segment
		(start 282.202128 -209.259932)
		(end 282.83662 -209.894424)
		(width 0.17145)
		(layer "F.Cu")
		(net "I2C_DRIVE_B_FLT_LED_SDA")
	)
	(segment
		(start 223.376998 -113.2078)
		(end 224.798382 -114.629184)
		(width 0.17145)
		(layer "F.Cu")
		(net "I2C_DRIVE_B_FLT_LED_SDA")
	)
	(segment
		(start 277.554182 -209.402172)
		(end 277.696422 -209.259932)
		(width 0.17145)
		(layer "F.Cu")
		(net "I2C_DRIVE_B_FLT_LED_SDA")
	)
	(segment
		(start 223.302576 -224.268284)
		(end 224.709736 -222.861124)
		(width 0.17145)
		(layer "F.Cu")
		(net "I2C_DRIVE_B_FLT_LED_SDA")
	)
	(segment
		(start 268.6685 -209.3595)
		(end 268.711172 -209.402172)
		(width 0.17145)
		(layer "F.Cu")
		(net "I2C_DRIVE_B_FLT_LED_SDA")
	)
	(segment
		(start 224.988882 -219.49664)
		(end 224.914206 -219.421964)
		(width 0.17145)
		(layer "F.Cu")
		(net "I2C_DRIVE_B_FLT_LED_SDA")
	)
	(segment
		(start 221.617794 -195.58)
		(end 222.204534 -194.99326)
		(width 0.17145)
		(layer "F.Cu")
		(net "I2C_DRIVE_B_FLT_LED_SDA")
	)
	(segment
		(start 220.1926 -80.195674)
		(end 220.1926 -91.432634)
		(width 0.17145)
		(layer "F.Cu")
		(net "I2C_DRIVE_B_FLT_LED_SDA")
	)
	(segment
		(start 224.914206 -221.273624)
		(end 224.988882 -221.198948)
		(width 0.17145)
		(layer "F.Cu")
		(net "I2C_DRIVE_B_FLT_LED_SDA")
	)
	(segment
		(start 224.709736 -222.861124)
		(end 224.914206 -222.656654)
		(width 0.17145)
		(layer "F.Cu")
		(net "I2C_DRIVE_B_FLT_LED_SDA")
	)
	(segment
		(start 268.6685 -208.787238)
		(end 268.6685 -209.3595)
		(width 0.17145)
		(layer "F.Cu")
		(net "I2C_DRIVE_B_FLT_LED_SDA")
	)
	(segment
		(start 222.4405 -224.282)
		(end 223.124776 -224.282)
		(width 0.17145)
		(layer "F.Cu")
		(net "I2C_DRIVE_B_FLT_LED_SDA")
	)
	(segment
		(start 224.988882 -221.198948)
		(end 224.988882 -219.49664)
		(width 0.17145)
		(layer "F.Cu")
		(net "I2C_DRIVE_B_FLT_LED_SDA")
	)
	(segment
		(start 224.914206 -219.421964)
		(end 224.914206 -216.03462)
		(width 0.17145)
		(layer "F.Cu")
		(net "I2C_DRIVE_B_FLT_LED_SDA")
	)
	(segment
		(start 268.380718 -208.499456)
		(end 268.6685 -208.787238)
		(width 0.17145)
		(layer "F.Cu")
		(net "I2C_DRIVE_B_FLT_LED_SDA")
	)
	(segment
		(start 223.124776 -224.282)
		(end 223.138492 -224.268284)
		(width 0.17145)
		(layer "F.Cu")
		(net "I2C_DRIVE_B_FLT_LED_SDA")
	)
	(segment
		(start 198.8058 -188.222128)
		(end 197.785482 -189.242446)
		(width 0.17145)
		(layer "F.Cu")
		(net "I2C_DRIVE_B_FLT_LED_SDA")
	)
	(segment
		(start 220.165676 -70.36562)
		(end 220.165676 -80.16875)
		(width 0.17145)
		(layer "F.Cu")
		(net "I2C_DRIVE_B_FLT_LED_SDA")
	)
	(segment
		(start 244.039898 -206.394304)
		(end 254.214122 -206.394304)
		(width 0.17145)
		(layer "F.Cu")
		(net "I2C_DRIVE_B_FLT_LED_SDA")
	)
	(segment
		(start 219.00007 -69.200014)
		(end 220.165676 -70.36562)
		(width 0.17145)
		(layer "F.Cu")
		(net "I2C_DRIVE_B_FLT_LED_SDA")
	)
	(segment
		(start 220.165676 -80.16875)
		(end 220.1926 -80.195674)
		(width 0.17145)
		(layer "F.Cu")
		(net "I2C_DRIVE_B_FLT_LED_SDA")
	)
	(segment
		(start 227.005134 -213.943692)
		(end 230.181404 -213.943692)
		(width 0.17145)
		(layer "F.Cu")
		(net "I2C_DRIVE_B_FLT_LED_SDA")
	)
	(segment
		(start 224.798382 -114.629184)
		(end 224.798382 -138.684508)
		(width 0.17145)
		(layer "F.Cu")
		(net "I2C_DRIVE_B_FLT_LED_SDA")
	)
	(segment
		(start 230.181404 -213.943692)
		(end 232.931208 -211.193888)
		(width 0.17145)
		(layer "F.Cu")
		(net "I2C_DRIVE_B_FLT_LED_SDA")
	)
	(segment
		(start 243.093494 -207.340708)
		(end 244.039898 -206.394304)
		(width 0.17145)
		(layer "F.Cu")
		(net "I2C_DRIVE_B_FLT_LED_SDA")
	)
	(segment
		(start 236.784388 -207.340708)
		(end 243.093494 -207.340708)
		(width 0.17145)
		(layer "F.Cu")
		(net "I2C_DRIVE_B_FLT_LED_SDA")
	)
	(segment
		(start 232.931208 -211.193888)
		(end 236.784388 -207.340708)
		(width 0.17145)
		(layer "F.Cu")
		(net "I2C_DRIVE_B_FLT_LED_SDA")
	)
	(segment
		(start 198.8058 -164.67709)
		(end 198.8058 -188.222128)
		(width 0.17145)
		(layer "F.Cu")
		(net "I2C_DRIVE_B_FLT_LED_SDA")
	)
	(segment
		(start 223.376998 -94.617032)
		(end 223.376998 -113.2078)
		(width 0.17145)
		(layer "F.Cu")
		(net "I2C_DRIVE_B_FLT_LED_SDA")
	)
	(via
		(at 222.204534 -194.99326)
		(size 0.5588)
		(drill 0.3048)
		(layers "F.Cu" "B.Cu")
		(net "I2C_DRIVE_B_FLT_LED_SDA")
	)
	(via
		(at 232.931208 -211.193888)
		(size 0.6604)
		(drill 0.3302)
		(layers "F.Cu" "B.Cu")
		(net "I2C_DRIVE_B_FLT_LED_SDA")
	)
	(via
		(at 224.709736 -222.861124)
		(size 0.5588)
		(drill 0.3048)
		(layers "F.Cu" "B.Cu")
		(net "I2C_DRIVE_B_FLT_LED_SDA")
	)
	(via
		(at 192.4304 -224.6376)
		(size 0.5588)
		(drill 0.3048)
		(layers "F.Cu" "B.Cu")
		(net "I2C_DRIVE_B_FLT_LED_SDA")
	)
	(via
		(at 197.785482 -189.242446)
		(size 0.5588)
		(drill 0.3048)
		(layers "F.Cu" "B.Cu")
		(net "I2C_DRIVE_B_FLT_LED_SDA")
	)
	(segment
		(start 190.503556 -224.0026)
		(end 191.7954 -224.0026)
		(width 0.14605)
		(layer "In2.Cu")
		(net "I2C_DRIVE_B_FLT_LED_SDA")
	)
	(segment
		(start 189.2554 -188.9252)
		(end 179.533042 -198.647558)
		(width 0.14605)
		(layer "In2.Cu")
		(net "I2C_DRIVE_B_FLT_LED_SDA")
	)
	(segment
		(start 197.468236 -188.9252)
		(end 189.2554 -188.9252)
		(width 0.14605)
		(layer "In2.Cu")
		(net "I2C_DRIVE_B_FLT_LED_SDA")
	)
	(segment
		(start 191.7954 -224.0026)
		(end 192.4304 -224.6376)
		(width 0.14605)
		(layer "In2.Cu")
		(net "I2C_DRIVE_B_FLT_LED_SDA")
	)
	(segment
		(start 179.533042 -213.032086)
		(end 190.503556 -224.0026)
		(width 0.14605)
		(layer "In2.Cu")
		(net "I2C_DRIVE_B_FLT_LED_SDA")
	)
	(segment
		(start 179.533042 -198.647558)
		(end 179.533042 -213.032086)
		(width 0.14605)
		(layer "In2.Cu")
		(net "I2C_DRIVE_B_FLT_LED_SDA")
	)
	(segment
		(start 197.785482 -189.242446)
		(end 197.468236 -188.9252)
		(width 0.14605)
		(layer "In2.Cu")
		(net "I2C_DRIVE_B_FLT_LED_SDA")
	)
	(segment
		(start 206.52867 -222.854012)
		(end 216.44483 -222.854012)
		(width 0.14605)
		(layer "In5.Cu")
		(net "I2C_DRIVE_B_FLT_LED_SDA")
	)
	(segment
		(start 204.646276 -224.736406)
		(end 206.52867 -222.854012)
		(width 0.14605)
		(layer "In5.Cu")
		(net "I2C_DRIVE_B_FLT_LED_SDA")
	)
	(segment
		(start 216.44483 -222.854012)
		(end 217.0938 -223.502982)
		(width 0.14605)
		(layer "In5.Cu")
		(net "I2C_DRIVE_B_FLT_LED_SDA")
	)
	(segment
		(start 222.204534 -194.99326)
		(end 211.314284 -194.99326)
		(width 0.14605)
		(layer "In5.Cu")
		(net "I2C_DRIVE_B_FLT_LED_SDA")
	)
	(segment
		(start 201.397108 -192.854072)
		(end 197.785482 -189.242446)
		(width 0.14605)
		(layer "In5.Cu")
		(net "I2C_DRIVE_B_FLT_LED_SDA")
	)
	(segment
		(start 209.175096 -192.854072)
		(end 201.397108 -192.854072)
		(width 0.14605)
		(layer "In5.Cu")
		(net "I2C_DRIVE_B_FLT_LED_SDA")
	)
	(segment
		(start 224.067878 -223.502982)
		(end 224.709736 -222.861124)
		(width 0.14605)
		(layer "In5.Cu")
		(net "I2C_DRIVE_B_FLT_LED_SDA")
	)
	(segment
		(start 211.314284 -194.99326)
		(end 209.175096 -192.854072)
		(width 0.14605)
		(layer "In5.Cu")
		(net "I2C_DRIVE_B_FLT_LED_SDA")
	)
	(segment
		(start 192.529206 -224.736406)
		(end 204.646276 -224.736406)
		(width 0.14605)
		(layer "In5.Cu")
		(net "I2C_DRIVE_B_FLT_LED_SDA")
	)
	(segment
		(start 192.4304 -224.6376)
		(end 192.529206 -224.736406)
		(width 0.14605)
		(layer "In5.Cu")
		(net "I2C_DRIVE_B_FLT_LED_SDA")
	)
	(segment
		(start 217.0938 -223.502982)
		(end 224.067878 -223.502982)
		(width 0.14605)
		(layer "In5.Cu")
		(net "I2C_DRIVE_B_FLT_LED_SDA")
	)
	(segment
		(start 222.4405 -223.139)
		(end 223.13138 -223.139)
		(width 0.17145)
		(layer "F.Cu")
		(net "I2C_DRIVE_B_FLT_LED_SCL")
	)
	(segment
		(start 224.118932 -138.402822)
		(end 198.0438 -164.477954)
		(width 0.17145)
		(layer "F.Cu")
		(net "I2C_DRIVE_B_FLT_LED_SCL")
	)
	(segment
		(start 221.714822 -194.437)
		(end 222.146622 -194.0052)
		(width 0.17145)
		(layer "F.Cu")
		(net "I2C_DRIVE_B_FLT_LED_SCL")
	)
	(segment
		(start 223.435418 -222.834962)
		(end 223.768666 -222.834962)
		(width 0.17145)
		(layer "F.Cu")
		(net "I2C_DRIVE_B_FLT_LED_SCL")
	)
	(segment
		(start 264.903966 -206.657194)
		(end 266.066778 -207.820006)
		(width 0.17145)
		(layer "F.Cu")
		(net "I2C_DRIVE_B_FLT_LED_SCL")
	)
	(segment
		(start 224.118932 -114.91087)
		(end 224.118932 -138.402822)
		(width 0.17145)
		(layer "F.Cu")
		(net "I2C_DRIVE_B_FLT_LED_SCL")
	)
	(segment
		(start 255.438148 -206.657194)
		(end 264.903966 -206.657194)
		(width 0.17145)
		(layer "F.Cu")
		(net "I2C_DRIVE_B_FLT_LED_SCL")
	)
	(segment
		(start 277.230586 -208.732882)
		(end 283.075126 -208.732882)
		(width 0.17145)
		(layer "F.Cu")
		(net "I2C_DRIVE_B_FLT_LED_SCL")
	)
	(segment
		(start 224.309432 -220.917262)
		(end 224.309432 -219.778326)
		(width 0.17145)
		(layer "F.Cu")
		(net "I2C_DRIVE_B_FLT_LED_SCL")
	)
	(segment
		(start 223.13138 -223.139)
		(end 223.435418 -222.834962)
		(width 0.17145)
		(layer "F.Cu")
		(net "I2C_DRIVE_B_FLT_LED_SCL")
	)
	(segment
		(start 219.51315 -91.71432)
		(end 222.697548 -94.898718)
		(width 0.17145)
		(layer "F.Cu")
		(net "I2C_DRIVE_B_FLT_LED_SCL")
	)
	(segment
		(start 222.697548 -94.898718)
		(end 222.697548 -105.837482)
		(width 0.17145)
		(layer "F.Cu")
		(net "I2C_DRIVE_B_FLT_LED_SCL")
	)
	(segment
		(start 224.234756 -222.368872)
		(end 224.234756 -220.991938)
		(width 0.17145)
		(layer "F.Cu")
		(net "I2C_DRIVE_B_FLT_LED_SCL")
	)
	(segment
		(start 221.1197 -194.437)
		(end 221.714822 -194.437)
		(width 0.17145)
		(layer "F.Cu")
		(net "I2C_DRIVE_B_FLT_LED_SCL")
	)
	(segment
		(start 268.6685 -207.423766)
		(end 268.6685 -206.883)
		(width 0.17145)
		(layer "F.Cu")
		(net "I2C_DRIVE_B_FLT_LED_SCL")
	)
	(segment
		(start 224.234756 -215.752934)
		(end 226.723448 -213.264242)
		(width 0.17145)
		(layer "F.Cu")
		(net "I2C_DRIVE_B_FLT_LED_SCL")
	)
	(segment
		(start 224.234756 -219.70365)
		(end 224.234756 -215.752934)
		(width 0.17145)
		(layer "F.Cu")
		(net "I2C_DRIVE_B_FLT_LED_SCL")
	)
	(segment
		(start 277.220426 -208.722722)
		(end 277.230586 -208.732882)
		(width 0.17145)
		(layer "F.Cu")
		(net "I2C_DRIVE_B_FLT_LED_SCL")
	)
	(segment
		(start 226.723448 -213.264242)
		(end 229.848918 -213.264242)
		(width 0.17145)
		(layer "F.Cu")
		(net "I2C_DRIVE_B_FLT_LED_SCL")
	)
	(segment
		(start 276.4409 -208.410048)
		(end 276.753574 -208.722722)
		(width 0.17145)
		(layer "F.Cu")
		(net "I2C_DRIVE_B_FLT_LED_SCL")
	)
	(segment
		(start 219.634562 -79.335122)
		(end 219.51315 -79.456534)
		(width 0.17145)
		(layer "F.Cu")
		(net "I2C_DRIVE_B_FLT_LED_SCL")
	)
	(segment
		(start 229.848918 -213.264242)
		(end 233.797094 -209.316066)
		(width 0.17145)
		(layer "F.Cu")
		(net "I2C_DRIVE_B_FLT_LED_SCL")
	)
	(segment
		(start 254.495808 -205.714854)
		(end 255.438148 -206.657194)
		(width 0.17145)
		(layer "F.Cu")
		(net "I2C_DRIVE_B_FLT_LED_SCL")
	)
	(segment
		(start 222.697548 -105.837482)
		(end 222.692468 -105.842562)
		(width 0.17145)
		(layer "F.Cu")
		(net "I2C_DRIVE_B_FLT_LED_SCL")
	)
	(segment
		(start 242.811554 -206.661258)
		(end 243.757958 -205.714854)
		(width 0.17145)
		(layer "F.Cu")
		(net "I2C_DRIVE_B_FLT_LED_SCL")
	)
	(segment
		(start 268.27226 -207.820006)
		(end 268.6685 -207.423766)
		(width 0.17145)
		(layer "F.Cu")
		(net "I2C_DRIVE_B_FLT_LED_SCL")
	)
	(segment
		(start 224.234756 -220.991938)
		(end 224.309432 -220.917262)
		(width 0.17145)
		(layer "F.Cu")
		(net "I2C_DRIVE_B_FLT_LED_SCL")
	)
	(segment
		(start 198.0438 -186.581034)
		(end 197.771258 -186.853576)
		(width 0.17145)
		(layer "F.Cu")
		(net "I2C_DRIVE_B_FLT_LED_SCL")
	)
	(segment
		(start 283.075126 -208.732882)
		(end 284.236668 -209.894424)
		(width 0.17145)
		(layer "F.Cu")
		(net "I2C_DRIVE_B_FLT_LED_SCL")
	)
	(segment
		(start 268.6685 -206.883)
		(end 272.8468 -206.883)
		(width 0.17145)
		(layer "F.Cu")
		(net "I2C_DRIVE_B_FLT_LED_SCL")
	)
	(segment
		(start 222.692468 -113.484406)
		(end 224.118932 -114.91087)
		(width 0.17145)
		(layer "F.Cu")
		(net "I2C_DRIVE_B_FLT_LED_SCL")
	)
	(segment
		(start 219.00007 -70.600062)
		(end 219.634562 -71.234554)
		(width 0.17145)
		(layer "F.Cu")
		(net "I2C_DRIVE_B_FLT_LED_SCL")
	)
	(segment
		(start 276.753574 -208.722722)
		(end 277.220426 -208.722722)
		(width 0.17145)
		(layer "F.Cu")
		(net "I2C_DRIVE_B_FLT_LED_SCL")
	)
	(segment
		(start 274.373848 -208.410048)
		(end 276.4409 -208.410048)
		(width 0.17145)
		(layer "F.Cu")
		(net "I2C_DRIVE_B_FLT_LED_SCL")
	)
	(segment
		(start 198.0438 -164.477954)
		(end 198.0438 -186.581034)
		(width 0.17145)
		(layer "F.Cu")
		(net "I2C_DRIVE_B_FLT_LED_SCL")
	)
	(segment
		(start 222.692468 -105.842562)
		(end 222.692468 -113.484406)
		(width 0.17145)
		(layer "F.Cu")
		(net "I2C_DRIVE_B_FLT_LED_SCL")
	)
	(segment
		(start 224.309432 -219.778326)
		(end 224.234756 -219.70365)
		(width 0.17145)
		(layer "F.Cu")
		(net "I2C_DRIVE_B_FLT_LED_SCL")
	)
	(segment
		(start 243.757958 -205.714854)
		(end 254.495808 -205.714854)
		(width 0.17145)
		(layer "F.Cu")
		(net "I2C_DRIVE_B_FLT_LED_SCL")
	)
	(segment
		(start 219.51315 -79.456534)
		(end 219.51315 -91.71432)
		(width 0.17145)
		(layer "F.Cu")
		(net "I2C_DRIVE_B_FLT_LED_SCL")
	)
	(segment
		(start 266.066778 -207.820006)
		(end 268.27226 -207.820006)
		(width 0.17145)
		(layer "F.Cu")
		(net "I2C_DRIVE_B_FLT_LED_SCL")
	)
	(segment
		(start 219.634562 -71.234554)
		(end 219.634562 -79.335122)
		(width 0.17145)
		(layer "F.Cu")
		(net "I2C_DRIVE_B_FLT_LED_SCL")
	)
	(segment
		(start 272.8468 -206.883)
		(end 274.373848 -208.410048)
		(width 0.17145)
		(layer "F.Cu")
		(net "I2C_DRIVE_B_FLT_LED_SCL")
	)
	(segment
		(start 223.768666 -222.834962)
		(end 224.234756 -222.368872)
		(width 0.17145)
		(layer "F.Cu")
		(net "I2C_DRIVE_B_FLT_LED_SCL")
	)
	(segment
		(start 236.451902 -206.661258)
		(end 242.811554 -206.661258)
		(width 0.17145)
		(layer "F.Cu")
		(net "I2C_DRIVE_B_FLT_LED_SCL")
	)
	(segment
		(start 233.797094 -209.316066)
		(end 236.451902 -206.661258)
		(width 0.17145)
		(layer "F.Cu")
		(net "I2C_DRIVE_B_FLT_LED_SCL")
	)
	(via
		(at 223.435418 -222.834962)
		(size 0.5588)
		(drill 0.3048)
		(layers "F.Cu" "B.Cu")
		(net "I2C_DRIVE_B_FLT_LED_SCL")
	)
	(via
		(at 233.797094 -209.316066)
		(size 0.6604)
		(drill 0.3302)
		(layers "F.Cu" "B.Cu")
		(net "I2C_DRIVE_B_FLT_LED_SCL")
	)
	(via
		(at 222.146622 -194.0052)
		(size 0.5588)
		(drill 0.3048)
		(layers "F.Cu" "B.Cu")
		(net "I2C_DRIVE_B_FLT_LED_SCL")
	)
	(via
		(at 191.516 -224.669096)
		(size 0.5588)
		(drill 0.3048)
		(layers "F.Cu" "B.Cu")
		(net "I2C_DRIVE_B_FLT_LED_SCL")
	)
	(via
		(at 197.771258 -186.853576)
		(size 0.5588)
		(drill 0.3048)
		(layers "F.Cu" "B.Cu")
		(net "I2C_DRIVE_B_FLT_LED_SCL")
	)
	(segment
		(start 178.878992 -213.303104)
		(end 178.878992 -198.285608)
		(width 0.14605)
		(layer "In2.Cu")
		(net "I2C_DRIVE_B_FLT_LED_SCL")
	)
	(segment
		(start 196.450458 -188.174376)
		(end 197.771258 -186.853576)
		(width 0.14605)
		(layer "In2.Cu")
		(net "I2C_DRIVE_B_FLT_LED_SCL")
	)
	(segment
		(start 191.516 -224.669096)
		(end 190.244984 -224.669096)
		(width 0.14605)
		(layer "In2.Cu")
		(net "I2C_DRIVE_B_FLT_LED_SCL")
	)
	(segment
		(start 178.878992 -198.285608)
		(end 188.990224 -188.174376)
		(width 0.14605)
		(layer "In2.Cu")
		(net "I2C_DRIVE_B_FLT_LED_SCL")
	)
	(segment
		(start 188.990224 -188.174376)
		(end 196.450458 -188.174376)
		(width 0.14605)
		(layer "In2.Cu")
		(net "I2C_DRIVE_B_FLT_LED_SCL")
	)
	(segment
		(start 190.244984 -224.669096)
		(end 178.878992 -213.303104)
		(width 0.14605)
		(layer "In2.Cu")
		(net "I2C_DRIVE_B_FLT_LED_SCL")
	)
	(segment
		(start 211.522818 -194.276726)
		(end 209.446114 -192.200022)
		(width 0.14605)
		(layer "In5.Cu")
		(net "I2C_DRIVE_B_FLT_LED_SCL")
	)
	(segment
		(start 222.146622 -194.0052)
		(end 221.875096 -194.276726)
		(width 0.14605)
		(layer "In5.Cu")
		(net "I2C_DRIVE_B_FLT_LED_SCL")
	)
	(segment
		(start 192.334896 -223.8502)
		(end 204.607414 -223.8502)
		(width 0.14605)
		(layer "In5.Cu")
		(net "I2C_DRIVE_B_FLT_LED_SCL")
	)
	(segment
		(start 209.446114 -192.200022)
		(end 203.429362 -192.200022)
		(width 0.14605)
		(layer "In5.Cu")
		(net "I2C_DRIVE_B_FLT_LED_SCL")
	)
	(segment
		(start 203.429362 -192.200022)
		(end 198.082916 -186.853576)
		(width 0.14605)
		(layer "In5.Cu")
		(net "I2C_DRIVE_B_FLT_LED_SCL")
	)
	(segment
		(start 198.082916 -186.853576)
		(end 197.771258 -186.853576)
		(width 0.14605)
		(layer "In5.Cu")
		(net "I2C_DRIVE_B_FLT_LED_SCL")
	)
	(segment
		(start 191.516 -224.669096)
		(end 192.334896 -223.8502)
		(width 0.14605)
		(layer "In5.Cu")
		(net "I2C_DRIVE_B_FLT_LED_SCL")
	)
	(segment
		(start 204.607414 -223.8502)
		(end 206.257652 -222.199962)
		(width 0.14605)
		(layer "In5.Cu")
		(net "I2C_DRIVE_B_FLT_LED_SCL")
	)
	(segment
		(start 217.364818 -222.848932)
		(end 223.421448 -222.848932)
		(width 0.14605)
		(layer "In5.Cu")
		(net "I2C_DRIVE_B_FLT_LED_SCL")
	)
	(segment
		(start 206.257652 -222.199962)
		(end 216.715848 -222.199962)
		(width 0.14605)
		(layer "In5.Cu")
		(net "I2C_DRIVE_B_FLT_LED_SCL")
	)
	(segment
		(start 221.875096 -194.276726)
		(end 211.522818 -194.276726)
		(width 0.14605)
		(layer "In5.Cu")
		(net "I2C_DRIVE_B_FLT_LED_SCL")
	)
	(segment
		(start 216.715848 -222.199962)
		(end 217.364818 -222.848932)
		(width 0.14605)
		(layer "In5.Cu")
		(net "I2C_DRIVE_B_FLT_LED_SCL")
	)
	(segment
		(start 223.421448 -222.848932)
		(end 223.435418 -222.834962)
		(width 0.14605)
		(layer "In5.Cu")
		(net "I2C_DRIVE_B_FLT_LED_SCL")
	)
	(segment
		(start 213.245192 -113.410492)
		(end 214.52459 -114.68989)
		(width 0.17145)
		(layer "F.Cu")
		(net "I2C_DPB_B_SDA")
	)
	(segment
		(start 213.245192 -100.133658)
		(end 213.245192 -113.410492)
		(width 0.17145)
		(layer "F.Cu")
		(net "I2C_DPB_B_SDA")
	)
	(segment
		(start 251.596652 -132.846572)
		(end 251.850652 -132.592572)
		(width 0.17145)
		(layer "F.Cu")
		(net "I2C_DPB_B_SDA")
	)
	(segment
		(start 212.963252 -80.203802)
		(end 212.980778 -80.221328)
		(width 0.17145)
		(layer "F.Cu")
		(net "I2C_DPB_B_SDA")
	)
	(segment
		(start 212.980778 -99.869244)
		(end 213.245192 -100.133658)
		(width 0.17145)
		(layer "F.Cu")
		(net "I2C_DPB_B_SDA")
	)
	(segment
		(start 249.952256 -132.6007)
		(end 250.198128 -132.846572)
		(width 0.17145)
		(layer "F.Cu")
		(net "I2C_DPB_B_SDA")
	)
	(segment
		(start 247.958102 -132.632958)
		(end 249.0724 -132.632958)
		(width 0.17145)
		(layer "F.Cu")
		(net "I2C_DPB_B_SDA")
	)
	(segment
		(start 249.104658 -132.6007)
		(end 249.7582 -132.6007)
		(width 0.17145)
		(layer "F.Cu")
		(net "I2C_DPB_B_SDA")
	)
	(segment
		(start 214.52459 -114.68989)
		(end 215.259412 -114.68989)
		(width 0.17145)
		(layer "F.Cu")
		(net "I2C_DPB_B_SDA")
	)
	(segment
		(start 249.7582 -132.6007)
		(end 249.952256 -132.6007)
		(width 0.17145)
		(layer "F.Cu")
		(net "I2C_DPB_B_SDA")
	)
	(segment
		(start 250.782582 -132.846572)
		(end 251.596652 -132.846572)
		(width 0.17145)
		(layer "F.Cu")
		(net "I2C_DPB_B_SDA")
	)
	(segment
		(start 213.60003 -68.200016)
		(end 212.963252 -68.836794)
		(width 0.17145)
		(layer "F.Cu")
		(net "I2C_DPB_B_SDA")
	)
	(segment
		(start 212.980778 -80.221328)
		(end 212.980778 -99.869244)
		(width 0.17145)
		(layer "F.Cu")
		(net "I2C_DPB_B_SDA")
	)
	(segment
		(start 250.198128 -132.846572)
		(end 250.782582 -132.846572)
		(width 0.17145)
		(layer "F.Cu")
		(net "I2C_DPB_B_SDA")
	)
	(segment
		(start 212.963252 -68.836794)
		(end 212.963252 -80.203802)
		(width 0.17145)
		(layer "F.Cu")
		(net "I2C_DPB_B_SDA")
	)
	(segment
		(start 215.259412 -114.68989)
		(end 215.782906 -115.213384)
		(width 0.17145)
		(layer "F.Cu")
		(net "I2C_DPB_B_SDA")
	)
	(segment
		(start 249.0724 -132.632958)
		(end 249.104658 -132.6007)
		(width 0.17145)
		(layer "F.Cu")
		(net "I2C_DPB_B_SDA")
	)
	(via
		(at 215.782906 -115.213384)
		(size 0.5588)
		(drill 0.3048)
		(layers "F.Cu" "B.Cu")
		(net "I2C_DPB_B_SDA")
	)
	(via
		(at 214.52459 -114.68989)
		(size 0.6604)
		(drill 0.3302)
		(layers "F.Cu" "B.Cu")
		(net "I2C_DPB_B_SDA")
	)
	(via
		(at 251.850652 -132.592572)
		(size 0.5588)
		(drill 0.3048)
		(layers "F.Cu" "B.Cu")
		(net "I2C_DPB_B_SDA")
	)
	(segment
		(start 215.782906 -115.213384)
		(end 218.131644 -115.213384)
		(width 0.14605)
		(layer "In5.Cu")
		(net "I2C_DPB_B_SDA")
	)
	(segment
		(start 232.982008 -130.063748)
		(end 238.757714 -130.063748)
		(width 0.14605)
		(layer "In5.Cu")
		(net "I2C_DPB_B_SDA")
	)
	(segment
		(start 218.131644 -115.213384)
		(end 232.982008 -130.063748)
		(width 0.14605)
		(layer "In5.Cu")
		(net "I2C_DPB_B_SDA")
	)
	(segment
		(start 241.286538 -132.592572)
		(end 251.850652 -132.592572)
		(width 0.14605)
		(layer "In5.Cu")
		(net "I2C_DPB_B_SDA")
	)
	(segment
		(start 238.757714 -130.063748)
		(end 241.286538 -132.592572)
		(width 0.14605)
		(layer "In5.Cu")
		(net "I2C_DPB_B_SDA")
	)
	(segment
		(start 214.427308 -116.129308)
		(end 212.458554 -114.160554)
		(width 0.17145)
		(layer "F.Cu")
		(net "I2C_DPB_B_SCL")
	)
	(segment
		(start 215.594946 -116.129308)
		(end 214.427308 -116.129308)
		(width 0.17145)
		(layer "F.Cu")
		(net "I2C_DPB_B_SCL")
	)
	(segment
		(start 240.009426 -132.240528)
		(end 239.874298 -132.1054)
		(width 0.17145)
		(layer "F.Cu")
		(net "I2C_DPB_B_SCL")
	)
	(segment
		(start 240.687098 -132.240528)
		(end 240.009426 -132.240528)
		(width 0.17145)
		(layer "F.Cu")
		(net "I2C_DPB_B_SCL")
	)
	(segment
		(start 212.436202 -79.206598)
		(end 212.301328 -79.341472)
		(width 0.17145)
		(layer "F.Cu")
		(net "I2C_DPB_B_SCL")
	)
	(segment
		(start 241.8334 -132.0927)
		(end 241.219228 -132.0927)
		(width 0.17145)
		(layer "F.Cu")
		(net "I2C_DPB_B_SCL")
	)
	(segment
		(start 242.232942 -132.0927)
		(end 241.8334 -132.0927)
		(width 0.17145)
		(layer "F.Cu")
		(net "I2C_DPB_B_SCL")
	)
	(segment
		(start 242.7732 -132.632958)
		(end 242.232942 -132.0927)
		(width 0.17145)
		(layer "F.Cu")
		(net "I2C_DPB_B_SCL")
	)
	(segment
		(start 243.817902 -132.632958)
		(end 242.7732 -132.632958)
		(width 0.17145)
		(layer "F.Cu")
		(net "I2C_DPB_B_SCL")
	)
	(segment
		(start 212.458554 -100.308156)
		(end 212.458554 -112.966754)
		(width 0.17145)
		(layer "F.Cu")
		(net "I2C_DPB_B_SCL")
	)
	(segment
		(start 212.436202 -67.963796)
		(end 212.436202 -79.206598)
		(width 0.17145)
		(layer "F.Cu")
		(net "I2C_DPB_B_SCL")
	)
	(segment
		(start 241.219228 -132.0927)
		(end 241.0714 -132.240528)
		(width 0.17145)
		(layer "F.Cu")
		(net "I2C_DPB_B_SCL")
	)
	(segment
		(start 212.301328 -79.341472)
		(end 212.301328 -100.15093)
		(width 0.17145)
		(layer "F.Cu")
		(net "I2C_DPB_B_SCL")
	)
	(segment
		(start 213.60003 -66.799968)
		(end 212.436202 -67.963796)
		(width 0.17145)
		(layer "F.Cu")
		(net "I2C_DPB_B_SCL")
	)
	(segment
		(start 212.301328 -100.15093)
		(end 212.458554 -100.308156)
		(width 0.17145)
		(layer "F.Cu")
		(net "I2C_DPB_B_SCL")
	)
	(segment
		(start 212.458554 -114.160554)
		(end 212.458554 -112.966754)
		(width 0.17145)
		(layer "F.Cu")
		(net "I2C_DPB_B_SCL")
	)
	(segment
		(start 241.0714 -132.240528)
		(end 240.687098 -132.240528)
		(width 0.17145)
		(layer "F.Cu")
		(net "I2C_DPB_B_SCL")
	)
	(via
		(at 239.874298 -132.1054)
		(size 0.5588)
		(drill 0.3048)
		(layers "F.Cu" "B.Cu")
		(net "I2C_DPB_B_SCL")
	)
	(via
		(at 212.458554 -112.966754)
		(size 0.6604)
		(drill 0.3302)
		(layers "F.Cu" "B.Cu")
		(net "I2C_DPB_B_SCL")
	)
	(via
		(at 215.594946 -116.129308)
		(size 0.5588)
		(drill 0.3048)
		(layers "F.Cu" "B.Cu")
		(net "I2C_DPB_B_SCL")
	)
	(segment
		(start 238.486696 -130.717798)
		(end 239.874298 -132.1054)
		(width 0.14605)
		(layer "In5.Cu")
		(net "I2C_DPB_B_SCL")
	)
	(segment
		(start 232.71099 -130.717798)
		(end 238.486696 -130.717798)
		(width 0.14605)
		(layer "In5.Cu")
		(net "I2C_DPB_B_SCL")
	)
	(segment
		(start 218.1225 -116.129308)
		(end 232.71099 -130.717798)
		(width 0.14605)
		(layer "In5.Cu")
		(net "I2C_DPB_B_SCL")
	)
	(segment
		(start 215.594946 -116.129308)
		(end 218.1225 -116.129308)
		(width 0.14605)
		(layer "In5.Cu")
		(net "I2C_DPB_B_SCL")
	)
	(segment
		(start 219.983812 -94.140782)
		(end 219.983812 -106.12882)
		(width 0.17145)
		(layer "F.Cu")
		(net "I2C_BMC_B_EXP_B_SDA")
	)
	(segment
		(start 221.742 -123.7234)
		(end 221.742 -122.555)
		(width 0.17145)
		(layer "F.Cu")
		(net "I2C_BMC_B_EXP_B_SDA")
	)
	(segment
		(start 285.082742 -125.167136)
		(end 285.082742 -121.203466)
		(width 0.17145)
		(layer "F.Cu")
		(net "I2C_BMC_B_EXP_B_SDA")
	)
	(segment
		(start 281.836622 -132.094478)
		(end 282.208224 -131.722876)
		(width 0.17145)
		(layer "F.Cu")
		(net "I2C_BMC_B_EXP_B_SDA")
	)
	(segment
		(start 219.990416 -107.507532)
		(end 219.4941 -107.011216)
		(width 0.17145)
		(layer "F.Cu")
		(net "I2C_BMC_B_EXP_B_SDA")
	)
	(segment
		(start 217.83675 -91.99372)
		(end 219.983812 -94.140782)
		(width 0.17145)
		(layer "F.Cu")
		(net "I2C_BMC_B_EXP_B_SDA")
	)
	(segment
		(start 217.83675 -76.036678)
		(end 217.83675 -91.99372)
		(width 0.17145)
		(layer "F.Cu")
		(net "I2C_BMC_B_EXP_B_SDA")
	)
	(segment
		(start 219.79255 -120.60555)
		(end 219.79255 -108.749846)
		(width 0.17145)
		(layer "F.Cu")
		(net "I2C_BMC_B_EXP_B_SDA")
	)
	(segment
		(start 219.183712 -107.011216)
		(end 219.142564 -106.970068)
		(width 0.17145)
		(layer "F.Cu")
		(net "I2C_BMC_B_EXP_B_SDA")
	)
	(segment
		(start 236.012228 -131.462018)
		(end 235.990384 -131.462018)
		(width 0.17145)
		(layer "F.Cu")
		(net "I2C_BMC_B_EXP_B_SDA")
	)
	(segment
		(start 282.208224 -131.722876)
		(end 282.208224 -128.041654)
		(width 0.17145)
		(layer "F.Cu")
		(net "I2C_BMC_B_EXP_B_SDA")
	)
	(segment
		(start 284.265624 -120.386348)
		(end 247.087898 -120.386348)
		(width 0.17145)
		(layer "F.Cu")
		(net "I2C_BMC_B_EXP_B_SDA")
	)
	(segment
		(start 282.208224 -128.041654)
		(end 285.082742 -125.167136)
		(width 0.17145)
		(layer "F.Cu")
		(net "I2C_BMC_B_EXP_B_SDA")
	)
	(segment
		(start 247.087898 -120.386348)
		(end 236.012228 -131.462018)
		(width 0.17145)
		(layer "F.Cu")
		(net "I2C_BMC_B_EXP_B_SDA")
	)
	(segment
		(start 219.4941 -107.011216)
		(end 219.183712 -107.011216)
		(width 0.17145)
		(layer "F.Cu")
		(net "I2C_BMC_B_EXP_B_SDA")
	)
	(segment
		(start 221.742 -122.555)
		(end 219.79255 -120.60555)
		(width 0.17145)
		(layer "F.Cu")
		(net "I2C_BMC_B_EXP_B_SDA")
	)
	(segment
		(start 219.79255 -108.749846)
		(end 219.990416 -108.55198)
		(width 0.17145)
		(layer "F.Cu")
		(net "I2C_BMC_B_EXP_B_SDA")
	)
	(segment
		(start 217.199972 -75.3999)
		(end 217.83675 -76.036678)
		(width 0.17145)
		(layer "F.Cu")
		(net "I2C_BMC_B_EXP_B_SDA")
	)
	(segment
		(start 285.082742 -121.203466)
		(end 284.265624 -120.386348)
		(width 0.17145)
		(layer "F.Cu")
		(net "I2C_BMC_B_EXP_B_SDA")
	)
	(segment
		(start 219.983812 -106.12882)
		(end 219.142564 -106.970068)
		(width 0.17145)
		(layer "F.Cu")
		(net "I2C_BMC_B_EXP_B_SDA")
	)
	(segment
		(start 219.990416 -108.55198)
		(end 219.990416 -107.507532)
		(width 0.17145)
		(layer "F.Cu")
		(net "I2C_BMC_B_EXP_B_SDA")
	)
	(segment
		(start 221.7928 -123.7742)
		(end 221.742 -123.7234)
		(width 0.17145)
		(layer "F.Cu")
		(net "I2C_BMC_B_EXP_B_SDA")
	)
	(via
		(at 221.7928 -123.7742)
		(size 0.5588)
		(drill 0.3048)
		(layers "F.Cu" "B.Cu")
		(net "I2C_BMC_B_EXP_B_SDA")
	)
	(via
		(at 231.972104 -127.443738)
		(size 0.6096)
		(drill 0.3048)
		(layers "F.Cu" "B.Cu")
		(net "I2C_BMC_B_EXP_B_SDA")
	)
	(via
		(at 235.990384 -131.462018)
		(size 0.5588)
		(drill 0.3048)
		(layers "F.Cu" "B.Cu")
		(net "I2C_BMC_B_EXP_B_SDA")
	)
	(segment
		(start 231.972104 -127.443738)
		(end 230.21544 -125.687074)
		(width 0.17145)
		(layer "B.Cu")
		(net "I2C_BMC_B_EXP_B_SDA")
	)
	(segment
		(start 223.705674 -125.687074)
		(end 221.7928 -123.7742)
		(width 0.17145)
		(layer "B.Cu")
		(net "I2C_BMC_B_EXP_B_SDA")
	)
	(segment
		(start 230.21544 -125.687074)
		(end 223.705674 -125.687074)
		(width 0.17145)
		(layer "B.Cu")
		(net "I2C_BMC_B_EXP_B_SDA")
	)
	(segment
		(start 235.990384 -131.462018)
		(end 231.972104 -127.443738)
		(width 0.17145)
		(layer "B.Cu")
		(net "I2C_BMC_B_EXP_B_SDA")
	)
	(segment
		(start 282.887674 -128.32334)
		(end 285.762192 -125.448822)
		(width 0.17145)
		(layer "F.Cu")
		(net "I2C_BMC_B_EXP_B_SCL")
	)
	(segment
		(start 285.762192 -120.92178)
		(end 284.54731 -119.706898)
		(width 0.17145)
		(layer "F.Cu")
		(net "I2C_BMC_B_EXP_B_SCL")
	)
	(segment
		(start 283.23667 -132.094478)
		(end 282.887674 -131.745482)
		(width 0.17145)
		(layer "F.Cu")
		(net "I2C_BMC_B_EXP_B_SCL")
	)
	(segment
		(start 217.199972 -73.999852)
		(end 218.3638 -75.16368)
		(width 0.17145)
		(layer "F.Cu")
		(net "I2C_BMC_B_EXP_B_SCL")
	)
	(segment
		(start 285.762192 -125.448822)
		(end 285.762192 -120.92178)
		(width 0.17145)
		(layer "F.Cu")
		(net "I2C_BMC_B_EXP_B_SCL")
	)
	(segment
		(start 222.484188 -124.759212)
		(end 221.742 -125.5014)
		(width 0.17145)
		(layer "F.Cu")
		(net "I2C_BMC_B_EXP_B_SCL")
	)
	(segment
		(start 220.472 -109.031532)
		(end 220.472 -120.142)
		(width 0.17145)
		(layer "F.Cu")
		(net "I2C_BMC_B_EXP_B_SCL")
	)
	(segment
		(start 220.472 -120.142)
		(end 222.484188 -122.154188)
		(width 0.17145)
		(layer "F.Cu")
		(net "I2C_BMC_B_EXP_B_SCL")
	)
	(segment
		(start 218.694 -79.56804)
		(end 218.694 -91.889834)
		(width 0.17145)
		(layer "F.Cu")
		(net "I2C_BMC_B_EXP_B_SCL")
	)
	(segment
		(start 220.669866 -108.833666)
		(end 220.472 -109.031532)
		(width 0.17145)
		(layer "F.Cu")
		(net "I2C_BMC_B_EXP_B_SCL")
	)
	(segment
		(start 218.3638 -75.16368)
		(end 218.3638 -79.23784)
		(width 0.17145)
		(layer "F.Cu")
		(net "I2C_BMC_B_EXP_B_SCL")
	)
	(segment
		(start 246.652034 -119.706898)
		(end 234.32135 -132.037582)
		(width 0.17145)
		(layer "F.Cu")
		(net "I2C_BMC_B_EXP_B_SCL")
	)
	(segment
		(start 284.54731 -119.706898)
		(end 246.652034 -119.706898)
		(width 0.17145)
		(layer "F.Cu")
		(net "I2C_BMC_B_EXP_B_SCL")
	)
	(segment
		(start 218.694 -91.889834)
		(end 220.663262 -93.859096)
		(width 0.17145)
		(layer "F.Cu")
		(net "I2C_BMC_B_EXP_B_SCL")
	)
	(segment
		(start 222.484188 -122.154188)
		(end 222.484188 -124.759212)
		(width 0.17145)
		(layer "F.Cu")
		(net "I2C_BMC_B_EXP_B_SCL")
	)
	(segment
		(start 220.669866 -107.823)
		(end 220.669866 -108.833666)
		(width 0.17145)
		(layer "F.Cu")
		(net "I2C_BMC_B_EXP_B_SCL")
	)
	(segment
		(start 218.3638 -79.23784)
		(end 218.694 -79.56804)
		(width 0.17145)
		(layer "F.Cu")
		(net "I2C_BMC_B_EXP_B_SCL")
	)
	(segment
		(start 220.663262 -106.110532)
		(end 221.522798 -106.970068)
		(width 0.17145)
		(layer "F.Cu")
		(net "I2C_BMC_B_EXP_B_SCL")
	)
	(segment
		(start 220.663262 -93.859096)
		(end 220.663262 -106.110532)
		(width 0.17145)
		(layer "F.Cu")
		(net "I2C_BMC_B_EXP_B_SCL")
	)
	(segment
		(start 221.522798 -106.970068)
		(end 220.669866 -107.823)
		(width 0.17145)
		(layer "F.Cu")
		(net "I2C_BMC_B_EXP_B_SCL")
	)
	(segment
		(start 282.887674 -131.745482)
		(end 282.887674 -128.32334)
		(width 0.17145)
		(layer "F.Cu")
		(net "I2C_BMC_B_EXP_B_SCL")
	)
	(via
		(at 227.704904 -127.663194)
		(size 0.6096)
		(drill 0.3048)
		(layers "F.Cu" "B.Cu")
		(net "I2C_BMC_B_EXP_B_SCL")
	)
	(via
		(at 221.742 -125.5014)
		(size 0.5588)
		(drill 0.3048)
		(layers "F.Cu" "B.Cu")
		(net "I2C_BMC_B_EXP_B_SCL")
	)
	(via
		(at 234.32135 -132.037582)
		(size 0.5588)
		(drill 0.3048)
		(layers "F.Cu" "B.Cu")
		(net "I2C_BMC_B_EXP_B_SCL")
	)
	(segment
		(start 222.395288 -125.5014)
		(end 224.557082 -127.663194)
		(width 0.17145)
		(layer "B.Cu")
		(net "I2C_BMC_B_EXP_B_SCL")
	)
	(segment
		(start 224.557082 -127.663194)
		(end 227.704904 -127.663194)
		(width 0.17145)
		(layer "B.Cu")
		(net "I2C_BMC_B_EXP_B_SCL")
	)
	(segment
		(start 221.742 -125.5014)
		(end 222.395288 -125.5014)
		(width 0.17145)
		(layer "B.Cu")
		(net "I2C_BMC_B_EXP_B_SCL")
	)
	(segment
		(start 227.704904 -127.663194)
		(end 229.946962 -127.663194)
		(width 0.17145)
		(layer "B.Cu")
		(net "I2C_BMC_B_EXP_B_SCL")
	)
	(segment
		(start 229.946962 -127.663194)
		(end 234.32135 -132.037582)
		(width 0.17145)
		(layer "B.Cu")
		(net "I2C_BMC_B_EXP_B_SCL")
	)
	(segment
		(start 218.791028 -115.5954)
		(end 218.791282 -115.595146)
		(width 0.17145)
		(layer "F.Cu")
		(net "I2C_BMC_A_EXP_B_SDA")
	)
	(segment
		(start 218.791282 -113.93932)
		(end 217.66784 -112.815878)
		(width 0.17145)
		(layer "F.Cu")
		(net "I2C_BMC_A_EXP_B_SDA")
	)
	(segment
		(start 217.678 -103.389176)
		(end 218.515692 -104.226868)
		(width 0.17145)
		(layer "F.Cu")
		(net "I2C_BMC_A_EXP_B_SDA")
	)
	(segment
		(start 221.0054 -122.8344)
		(end 218.791028 -120.620028)
		(width 0.17145)
		(layer "F.Cu")
		(net "I2C_BMC_A_EXP_B_SDA")
	)
	(segment
		(start 216.56548 -68.834508)
		(end 216.56548 -91.89339)
		(width 0.17145)
		(layer "F.Cu")
		(net "I2C_BMC_A_EXP_B_SDA")
	)
	(segment
		(start 218.791282 -115.595146)
		(end 218.791282 -113.93932)
		(width 0.17145)
		(layer "F.Cu")
		(net "I2C_BMC_A_EXP_B_SDA")
	)
	(segment
		(start 220.293946 -126.2888)
		(end 221.0054 -125.577346)
		(width 0.17145)
		(layer "F.Cu")
		(net "I2C_BMC_A_EXP_B_SDA")
	)
	(segment
		(start 217.199972 -68.200016)
		(end 216.56548 -68.834508)
		(width 0.17145)
		(layer "F.Cu")
		(net "I2C_BMC_A_EXP_B_SDA")
	)
	(segment
		(start 218.791028 -120.620028)
		(end 218.791028 -115.5954)
		(width 0.17145)
		(layer "F.Cu")
		(net "I2C_BMC_A_EXP_B_SDA")
	)
	(segment
		(start 217.66784 -105.07472)
		(end 218.515692 -104.226868)
		(width 0.17145)
		(layer "F.Cu")
		(net "I2C_BMC_A_EXP_B_SDA")
	)
	(segment
		(start 217.678 -93.00591)
		(end 217.678 -103.389176)
		(width 0.17145)
		(layer "F.Cu")
		(net "I2C_BMC_A_EXP_B_SDA")
	)
	(segment
		(start 216.56548 -91.89339)
		(end 217.678 -93.00591)
		(width 0.17145)
		(layer "F.Cu")
		(net "I2C_BMC_A_EXP_B_SDA")
	)
	(segment
		(start 217.66784 -112.815878)
		(end 217.66784 -105.07472)
		(width 0.17145)
		(layer "F.Cu")
		(net "I2C_BMC_A_EXP_B_SDA")
	)
	(segment
		(start 221.0054 -125.577346)
		(end 221.0054 -122.8344)
		(width 0.17145)
		(layer "F.Cu")
		(net "I2C_BMC_A_EXP_B_SDA")
	)
	(via
		(at 220.293946 -126.2888)
		(size 0.5588)
		(drill 0.3048)
		(layers "F.Cu" "B.Cu")
		(net "I2C_BMC_A_EXP_B_SDA")
	)
	(via
		(at 252.810264 -140.781024)
		(size 0.6096)
		(drill 0.3048)
		(layers "F.Cu" "B.Cu")
		(net "I2C_BMC_A_EXP_B_SDA")
	)
	(segment
		(start 251.465842 -139.436602)
		(end 252.810264 -140.781024)
		(width 0.17145)
		(layer "B.Cu")
		(net "I2C_BMC_A_EXP_B_SDA")
	)
	(segment
		(start 235.664248 -135.711692)
		(end 240.044224 -135.711692)
		(width 0.17145)
		(layer "B.Cu")
		(net "I2C_BMC_A_EXP_B_SDA")
	)
	(segment
		(start 247.764808 -134.951216)
		(end 248.786396 -135.972804)
		(width 0.17145)
		(layer "B.Cu")
		(net "I2C_BMC_A_EXP_B_SDA")
	)
	(segment
		(start 290.18484 -144.658842)
		(end 290.18484 -145.221706)
		(width 0.17145)
		(layer "B.Cu")
		(net "I2C_BMC_A_EXP_B_SDA")
	)
	(segment
		(start 248.786396 -137.294366)
		(end 250.928632 -139.436602)
		(width 0.17145)
		(layer "B.Cu")
		(net "I2C_BMC_A_EXP_B_SDA")
	)
	(segment
		(start 240.8047 -134.951216)
		(end 247.764808 -134.951216)
		(width 0.17145)
		(layer "B.Cu")
		(net "I2C_BMC_A_EXP_B_SDA")
	)
	(segment
		(start 229.679754 -129.727198)
		(end 235.664248 -135.711692)
		(width 0.17145)
		(layer "B.Cu")
		(net "I2C_BMC_A_EXP_B_SDA")
	)
	(segment
		(start 288.029142 -142.0114)
		(end 290.184586 -144.166844)
		(width 0.17145)
		(layer "B.Cu")
		(net "I2C_BMC_A_EXP_B_SDA")
	)
	(segment
		(start 248.786396 -135.972804)
		(end 248.786396 -137.294366)
		(width 0.17145)
		(layer "B.Cu")
		(net "I2C_BMC_A_EXP_B_SDA")
	)
	(segment
		(start 282.719526 -142.0114)
		(end 288.029142 -142.0114)
		(width 0.17145)
		(layer "B.Cu")
		(net "I2C_BMC_A_EXP_B_SDA")
	)
	(segment
		(start 260.859778 -148.830538)
		(end 252.810264 -140.781024)
		(width 0.17145)
		(layer "B.Cu")
		(net "I2C_BMC_A_EXP_B_SDA")
	)
	(segment
		(start 290.184586 -144.658588)
		(end 290.18484 -144.658842)
		(width 0.17145)
		(layer "B.Cu")
		(net "I2C_BMC_A_EXP_B_SDA")
	)
	(segment
		(start 290.184586 -144.166844)
		(end 290.184586 -144.658588)
		(width 0.17145)
		(layer "B.Cu")
		(net "I2C_BMC_A_EXP_B_SDA")
	)
	(segment
		(start 224.011236 -129.727198)
		(end 229.679754 -129.727198)
		(width 0.17145)
		(layer "B.Cu")
		(net "I2C_BMC_A_EXP_B_SDA")
	)
	(segment
		(start 220.293946 -126.2888)
		(end 220.572838 -126.2888)
		(width 0.17145)
		(layer "B.Cu")
		(net "I2C_BMC_A_EXP_B_SDA")
	)
	(segment
		(start 250.928632 -139.436602)
		(end 251.465842 -139.436602)
		(width 0.17145)
		(layer "B.Cu")
		(net "I2C_BMC_A_EXP_B_SDA")
	)
	(segment
		(start 240.044224 -135.711692)
		(end 240.8047 -134.951216)
		(width 0.17145)
		(layer "B.Cu")
		(net "I2C_BMC_A_EXP_B_SDA")
	)
	(segment
		(start 220.572838 -126.2888)
		(end 224.011236 -129.727198)
		(width 0.17145)
		(layer "B.Cu")
		(net "I2C_BMC_A_EXP_B_SDA")
	)
	(segment
		(start 281.836622 -142.894304)
		(end 282.719526 -142.0114)
		(width 0.17145)
		(layer "B.Cu")
		(net "I2C_BMC_A_EXP_B_SDA")
	)
	(segment
		(start 286.576008 -148.830538)
		(end 260.859778 -148.830538)
		(width 0.17145)
		(layer "B.Cu")
		(net "I2C_BMC_A_EXP_B_SDA")
	)
	(segment
		(start 290.18484 -145.221706)
		(end 286.576008 -148.830538)
		(width 0.17145)
		(layer "B.Cu")
		(net "I2C_BMC_A_EXP_B_SDA")
	)
	(segment
		(start 217.199972 -66.799968)
		(end 216.03462 -67.96532)
		(width 0.17145)
		(layer "F.Cu")
		(net "I2C_BMC_A_EXP_B_SCL")
	)
	(segment
		(start 218.111578 -121.007632)
		(end 218.111578 -114.220752)
		(width 0.17145)
		(layer "F.Cu")
		(net "I2C_BMC_A_EXP_B_SCL")
	)
	(segment
		(start 215.72855 -92.017596)
		(end 216.99855 -93.287596)
		(width 0.17145)
		(layer "F.Cu")
		(net "I2C_BMC_A_EXP_B_SCL")
	)
	(segment
		(start 216.99855 -103.368856)
		(end 216.140538 -104.226868)
		(width 0.17145)
		(layer "F.Cu")
		(net "I2C_BMC_A_EXP_B_SCL")
	)
	(segment
		(start 216.99855 -93.287596)
		(end 216.99855 -103.368856)
		(width 0.17145)
		(layer "F.Cu")
		(net "I2C_BMC_A_EXP_B_SCL")
	)
	(segment
		(start 220.293946 -125.2982)
		(end 220.293946 -123.19)
		(width 0.17145)
		(layer "F.Cu")
		(net "I2C_BMC_A_EXP_B_SCL")
	)
	(segment
		(start 216.98839 -113.097564)
		(end 216.98839 -105.07472)
		(width 0.17145)
		(layer "F.Cu")
		(net "I2C_BMC_A_EXP_B_SCL")
	)
	(segment
		(start 216.03462 -79.432912)
		(end 215.72855 -79.738982)
		(width 0.17145)
		(layer "F.Cu")
		(net "I2C_BMC_A_EXP_B_SCL")
	)
	(segment
		(start 218.111578 -114.220752)
		(end 216.98839 -113.097564)
		(width 0.17145)
		(layer "F.Cu")
		(net "I2C_BMC_A_EXP_B_SCL")
	)
	(segment
		(start 220.293946 -123.19)
		(end 218.111578 -121.007632)
		(width 0.17145)
		(layer "F.Cu")
		(net "I2C_BMC_A_EXP_B_SCL")
	)
	(segment
		(start 216.03462 -67.96532)
		(end 216.03462 -79.432912)
		(width 0.17145)
		(layer "F.Cu")
		(net "I2C_BMC_A_EXP_B_SCL")
	)
	(segment
		(start 216.98839 -105.07472)
		(end 216.140538 -104.226868)
		(width 0.17145)
		(layer "F.Cu")
		(net "I2C_BMC_A_EXP_B_SCL")
	)
	(segment
		(start 215.72855 -79.738982)
		(end 215.72855 -92.017596)
		(width 0.17145)
		(layer "F.Cu")
		(net "I2C_BMC_A_EXP_B_SCL")
	)
	(via
		(at 255.120648 -142.130272)
		(size 0.6096)
		(drill 0.3048)
		(layers "F.Cu" "B.Cu")
		(net "I2C_BMC_A_EXP_B_SCL")
	)
	(via
		(at 220.293946 -125.2982)
		(size 0.5588)
		(drill 0.3048)
		(layers "F.Cu" "B.Cu")
		(net "I2C_BMC_A_EXP_B_SCL")
	)
	(segment
		(start 248.04624 -134.271512)
		(end 240.523268 -134.271512)
		(width 0.17145)
		(layer "B.Cu")
		(net "I2C_BMC_A_EXP_B_SCL")
	)
	(segment
		(start 220.543374 -125.2982)
		(end 220.293946 -125.2982)
		(width 0.17145)
		(layer "B.Cu")
		(net "I2C_BMC_A_EXP_B_SCL")
	)
	(segment
		(start 249.465846 -137.01268)
		(end 249.465846 -135.691118)
		(width 0.17145)
		(layer "B.Cu")
		(net "I2C_BMC_A_EXP_B_SCL")
	)
	(segment
		(start 251.210318 -138.757152)
		(end 249.465846 -137.01268)
		(width 0.17145)
		(layer "B.Cu")
		(net "I2C_BMC_A_EXP_B_SCL")
	)
	(segment
		(start 240.523268 -134.271512)
		(end 239.762538 -135.032242)
		(width 0.17145)
		(layer "B.Cu")
		(net "I2C_BMC_A_EXP_B_SCL")
	)
	(segment
		(start 289.505136 -144.44853)
		(end 289.505136 -144.940274)
		(width 0.17145)
		(layer "B.Cu")
		(net "I2C_BMC_A_EXP_B_SCL")
	)
	(segment
		(start 286.294322 -148.151088)
		(end 261.141464 -148.151088)
		(width 0.17145)
		(layer "B.Cu")
		(net "I2C_BMC_A_EXP_B_SCL")
	)
	(segment
		(start 224.292922 -129.047748)
		(end 220.543374 -125.2982)
		(width 0.17145)
		(layer "B.Cu")
		(net "I2C_BMC_A_EXP_B_SCL")
	)
	(segment
		(start 255.120648 -142.130272)
		(end 251.747528 -138.757152)
		(width 0.17145)
		(layer "B.Cu")
		(net "I2C_BMC_A_EXP_B_SCL")
	)
	(segment
		(start 261.141464 -148.151088)
		(end 255.120648 -142.130272)
		(width 0.17145)
		(layer "B.Cu")
		(net "I2C_BMC_A_EXP_B_SCL")
	)
	(segment
		(start 283.23667 -142.894304)
		(end 283.974286 -143.63192)
		(width 0.17145)
		(layer "B.Cu")
		(net "I2C_BMC_A_EXP_B_SCL")
	)
	(segment
		(start 288.688526 -143.63192)
		(end 289.505136 -144.44853)
		(width 0.17145)
		(layer "B.Cu")
		(net "I2C_BMC_A_EXP_B_SCL")
	)
	(segment
		(start 289.505136 -144.940274)
		(end 286.294322 -148.151088)
		(width 0.17145)
		(layer "B.Cu")
		(net "I2C_BMC_A_EXP_B_SCL")
	)
	(segment
		(start 249.465846 -135.691118)
		(end 248.04624 -134.271512)
		(width 0.17145)
		(layer "B.Cu")
		(net "I2C_BMC_A_EXP_B_SCL")
	)
	(segment
		(start 283.974286 -143.63192)
		(end 288.688526 -143.63192)
		(width 0.17145)
		(layer "B.Cu")
		(net "I2C_BMC_A_EXP_B_SCL")
	)
	(segment
		(start 229.96144 -129.047748)
		(end 224.292922 -129.047748)
		(width 0.17145)
		(layer "B.Cu")
		(net "I2C_BMC_A_EXP_B_SCL")
	)
	(segment
		(start 239.762538 -135.032242)
		(end 235.945934 -135.032242)
		(width 0.17145)
		(layer "B.Cu")
		(net "I2C_BMC_A_EXP_B_SCL")
	)
	(segment
		(start 235.945934 -135.032242)
		(end 229.96144 -129.047748)
		(width 0.17145)
		(layer "B.Cu")
		(net "I2C_BMC_A_EXP_B_SCL")
	)
	(segment
		(start 251.747528 -138.757152)
		(end 251.210318 -138.757152)
		(width 0.17145)
		(layer "B.Cu")
		(net "I2C_BMC_A_EXP_B_SCL")
	)
	(segment
		(start 34.8615 -262.128)
		(end 34.818574 -262.085074)
		(width 0.17145)
		(layer "F.Cu")
		(net "HDD_PRSNT_0")
	)
	(segment
		(start 34.925 -264.6045)
		(end 34.8615 -264.541)
		(width 0.17145)
		(layer "F.Cu")
		(net "HDD_PRSNT_0")
	)
	(segment
		(start 34.925 -266.065)
		(end 34.925 -264.6045)
		(width 0.17145)
		(layer "F.Cu")
		(net "HDD_PRSNT_0")
	)
	(segment
		(start 34.818574 -262.085074)
		(end 30.025086 -262.085074)
		(width 0.17145)
		(layer "F.Cu")
		(net "HDD_PRSNT_0")
	)
	(segment
		(start 34.8615 -262.128)
		(end 34.8615 -263.144)
		(width 0.17145)
		(layer "F.Cu")
		(net "HDD_PRSNT_0")
	)
	(segment
		(start 34.8615 -263.144)
		(end 34.8615 -264.541)
		(width 0.17145)
		(layer "F.Cu")
		(net "HDD_PRSNT_0")
	)
	(via
		(at 34.8615 -264.541)
		(size 0.6604)
		(drill 0.3302)
		(layers "F.Cu" "B.Cu")
		(net "HDD_PRSNT_0")
	)
	(segment
		(start 409.194 -212.082888)
		(end 409.299664 -211.977224)
		(width 0.254)
		(layer "F.Cu")
		(net "FLT_HDD9")
	)
	(segment
		(start 409.299664 -181.130194)
		(end 409.299664 -203.197968)
		(width 0.254)
		(layer "F.Cu")
		(net "FLT_HDD9")
	)
	(segment
		(start 409.194 -213.487)
		(end 409.194 -212.082888)
		(width 0.254)
		(layer "F.Cu")
		(net "FLT_HDD9")
	)
	(segment
		(start 409.299664 -211.977224)
		(end 409.299664 -203.197968)
		(width 0.254)
		(layer "F.Cu")
		(net "FLT_HDD9")
	)
	(via
		(at 409.299664 -203.197968)
		(size 0.6604)
		(drill 0.3302)
		(layers "F.Cu" "B.Cu")
		(net "FLT_HDD9")
	)
	(segment
		(start 377.698 -213.487)
		(end 377.698 -210.917028)
		(width 0.254)
		(layer "F.Cu")
		(net "FLT_HDD8")
	)
	(segment
		(start 377.749562 -210.865466)
		(end 377.749562 -202.908408)
		(width 0.254)
		(layer "F.Cu")
		(net "FLT_HDD8")
	)
	(segment
		(start 377.749562 -181.130194)
		(end 377.749562 -202.908408)
		(width 0.254)
		(layer "F.Cu")
		(net "FLT_HDD8")
	)
	(segment
		(start 377.698 -210.917028)
		(end 377.749562 -210.865466)
		(width 0.254)
		(layer "F.Cu")
		(net "FLT_HDD8")
	)
	(via
		(at 377.749562 -202.908408)
		(size 0.6604)
		(drill 0.3302)
		(layers "F.Cu" "B.Cu")
		(net "FLT_HDD8")
	)
	(segment
		(start 346.075 -213.614)
		(end 346.075 -210.926426)
		(width 0.254)
		(layer "F.Cu")
		(net "FLT_HDD7")
	)
	(segment
		(start 346.075 -210.926426)
		(end 346.199714 -210.801712)
		(width 0.254)
		(layer "F.Cu")
		(net "FLT_HDD7")
	)
	(segment
		(start 346.199714 -181.130194)
		(end 346.199714 -202.779884)
		(width 0.254)
		(layer "F.Cu")
		(net "FLT_HDD7")
	)
	(segment
		(start 346.199714 -210.801712)
		(end 346.199714 -202.779884)
		(width 0.254)
		(layer "F.Cu")
		(net "FLT_HDD7")
	)
	(via
		(at 346.199714 -202.779884)
		(size 0.6604)
		(drill 0.3302)
		(layers "F.Cu" "B.Cu")
		(net "FLT_HDD7")
	)
	(segment
		(start 314.649612 -212.311488)
		(end 314.649612 -202.780392)
		(width 0.254)
		(layer "F.Cu")
		(net "FLT_HDD6")
	)
	(segment
		(start 314.649612 -181.130194)
		(end 314.649612 -202.780392)
		(width 0.254)
		(layer "F.Cu")
		(net "FLT_HDD6")
	)
	(segment
		(start 314.569348 -212.391752)
		(end 314.649612 -212.311488)
		(width 0.254)
		(layer "F.Cu")
		(net "FLT_HDD6")
	)
	(via
		(at 314.649612 -202.780392)
		(size 0.6604)
		(drill 0.3302)
		(layers "F.Cu" "B.Cu")
		(net "FLT_HDD6")
	)
	(segment
		(start 175.049688 -191.58077)
		(end 172.847 -193.783458)
		(width 0.254)
		(layer "F.Cu")
		(net "FLT_HDD5")
	)
	(segment
		(start 175.049688 -181.130194)
		(end 175.049688 -191.58077)
		(width 0.254)
		(layer "F.Cu")
		(net "FLT_HDD5")
	)
	(segment
		(start 172.847 -200.816464)
		(end 172.847 -213.487)
		(width 0.254)
		(layer "F.Cu")
		(net "FLT_HDD5")
	)
	(segment
		(start 172.847 -193.783458)
		(end 172.847 -200.816464)
		(width 0.254)
		(layer "F.Cu")
		(net "FLT_HDD5")
	)
	(via
		(at 172.847 -200.816464)
		(size 0.6604)
		(drill 0.3302)
		(layers "F.Cu" "B.Cu")
		(net "FLT_HDD5")
	)
	(segment
		(start 143.499586 -210.036918)
		(end 143.499586 -201.10577)
		(width 0.254)
		(layer "F.Cu")
		(net "FLT_HDD4")
	)
	(segment
		(start 143.256 -213.487)
		(end 143.256 -210.280504)
		(width 0.254)
		(layer "F.Cu")
		(net "FLT_HDD4")
	)
	(segment
		(start 143.499586 -201.10577)
		(end 143.499586 -181.130194)
		(width 0.254)
		(layer "F.Cu")
		(net "FLT_HDD4")
	)
	(segment
		(start 143.256 -210.280504)
		(end 143.499586 -210.036918)
		(width 0.254)
		(layer "F.Cu")
		(net "FLT_HDD4")
	)
	(via
		(at 143.499586 -201.10577)
		(size 0.6604)
		(drill 0.3302)
		(layers "F.Cu" "B.Cu")
		(net "FLT_HDD4")
	)
	(segment
		(start 111.76 -213.487)
		(end 111.76 -212.53323)
		(width 0.254)
		(layer "F.Cu")
		(net "FLT_HDD3")
	)
	(segment
		(start 111.949738 -199.431656)
		(end 111.949738 -181.130194)
		(width 0.254)
		(layer "F.Cu")
		(net "FLT_HDD3")
	)
	(segment
		(start 111.76 -212.53323)
		(end 111.949738 -212.343492)
		(width 0.254)
		(layer "F.Cu")
		(net "FLT_HDD3")
	)
	(segment
		(start 111.949738 -212.343492)
		(end 111.949738 -199.431656)
		(width 0.254)
		(layer "F.Cu")
		(net "FLT_HDD3")
	)
	(via
		(at 111.949738 -199.431656)
		(size 0.6604)
		(drill 0.3302)
		(layers "F.Cu" "B.Cu")
		(net "FLT_HDD3")
	)
	(segment
		(start 80.399636 -181.130194)
		(end 80.399636 -200.703434)
		(width 0.254)
		(layer "F.Cu")
		(net "FLT_HDD2")
	)
	(segment
		(start 80.137 -209.48396)
		(end 80.399636 -209.221324)
		(width 0.254)
		(layer "F.Cu")
		(net "FLT_HDD2")
	)
	(segment
		(start 80.137 -213.487)
		(end 80.137 -209.48396)
		(width 0.254)
		(layer "F.Cu")
		(net "FLT_HDD2")
	)
	(segment
		(start 80.399636 -209.221324)
		(end 80.399636 -200.703434)
		(width 0.254)
		(layer "F.Cu")
		(net "FLT_HDD2")
	)
	(via
		(at 80.399636 -200.703434)
		(size 0.6604)
		(drill 0.3302)
		(layers "F.Cu" "B.Cu")
		(net "FLT_HDD2")
	)
	(segment
		(start 17.146016 -66.28384)
		(end 17.146016 -91.644216)
		(width 0.254)
		(layer "F.Cu")
		(net "FLT_HDD12")
	)
	(segment
		(start 17.299686 -66.13017)
		(end 17.146016 -66.28384)
		(width 0.254)
		(layer "F.Cu")
		(net "FLT_HDD12")
	)
	(segment
		(start 20.210018 -94.708218)
		(end 18.4404 -92.9386)
		(width 0.254)
		(layer "F.Cu")
		(net "FLT_HDD12")
	)
	(segment
		(start 17.146016 -91.644216)
		(end 18.4404 -92.9386)
		(width 0.254)
		(layer "F.Cu")
		(net "FLT_HDD12")
	)
	(segment
		(start 20.210018 -98.639884)
		(end 20.210018 -94.708218)
		(width 0.254)
		(layer "F.Cu")
		(net "FLT_HDD12")
	)
	(via
		(at 18.4404 -92.9386)
		(size 0.6604)
		(drill 0.3302)
		(layers "F.Cu" "B.Cu")
		(net "FLT_HDD12")
	)
	(segment
		(start 472.399614 -211.121752)
		(end 472.399614 -202.940666)
		(width 0.254)
		(layer "F.Cu")
		(net "FLT_HDD11")
	)
	(segment
		(start 472.399614 -181.130194)
		(end 472.399614 -202.940666)
		(width 0.254)
		(layer "F.Cu")
		(net "FLT_HDD11")
	)
	(segment
		(start 472.313 -211.208366)
		(end 472.399614 -211.121752)
		(width 0.254)
		(layer "F.Cu")
		(net "FLT_HDD11")
	)
	(segment
		(start 472.313 -213.487)
		(end 472.313 -211.208366)
		(width 0.254)
		(layer "F.Cu")
		(net "FLT_HDD11")
	)
	(via
		(at 472.399614 -202.940666)
		(size 0.6604)
		(drill 0.3302)
		(layers "F.Cu" "B.Cu")
		(net "FLT_HDD11")
	)
	(segment
		(start 440.69 -212.104224)
		(end 440.849512 -211.944712)
		(width 0.254)
		(layer "F.Cu")
		(net "FLT_HDD10")
	)
	(segment
		(start 440.849512 -211.944712)
		(end 440.849512 -203.712826)
		(width 0.254)
		(layer "F.Cu")
		(net "FLT_HDD10")
	)
	(segment
		(start 440.849512 -181.130194)
		(end 440.849512 -203.712826)
		(width 0.254)
		(layer "F.Cu")
		(net "FLT_HDD10")
	)
	(segment
		(start 440.69 -213.487)
		(end 440.69 -212.104224)
		(width 0.254)
		(layer "F.Cu")
		(net "FLT_HDD10")
	)
	(via
		(at 440.849512 -203.712826)
		(size 0.6604)
		(drill 0.3302)
		(layers "F.Cu" "B.Cu")
		(net "FLT_HDD10")
	)
	(segment
		(start 48.849534 -181.130194)
		(end 48.849534 -199.48017)
		(width 0.254)
		(layer "F.Cu")
		(net "FLT_HDD1")
	)
	(segment
		(start 48.849534 -213.151466)
		(end 48.849534 -199.48017)
		(width 0.254)
		(layer "F.Cu")
		(net "FLT_HDD1")
	)
	(segment
		(start 48.514 -213.487)
		(end 48.849534 -213.151466)
		(width 0.254)
		(layer "F.Cu")
		(net "FLT_HDD1")
	)
	(via
		(at 48.849534 -199.48017)
		(size 0.6604)
		(drill 0.3302)
		(layers "F.Cu" "B.Cu")
		(net "FLT_HDD1")
	)
	(segment
		(start 17.399 -209.300064)
		(end 17.299686 -209.20075)
		(width 0.254)
		(layer "F.Cu")
		(net "FLT_HDD0")
	)
	(segment
		(start 17.299686 -181.130194)
		(end 17.299686 -199.544178)
		(width 0.254)
		(layer "F.Cu")
		(net "FLT_HDD0")
	)
	(segment
		(start 17.299686 -209.20075)
		(end 17.299686 -199.544178)
		(width 0.254)
		(layer "F.Cu")
		(net "FLT_HDD0")
	)
	(segment
		(start 17.399 -213.487)
		(end 17.399 -209.300064)
		(width 0.254)
		(layer "F.Cu")
		(net "FLT_HDD0")
	)
	(via
		(at 17.299686 -199.544178)
		(size 0.6604)
		(drill 0.3302)
		(layers "F.Cu" "B.Cu")
		(net "FLT_HDD0")
	)
	(segment
		(start 430.59985 -367.09985)
		(end 430.5427 -367.157)
		(width 0.254)
		(layer "F.Cu")
		(net "FAN_3_TACH1")
	)
	(segment
		(start 426.879004 -367.1189)
		(end 426.917104 -367.157)
		(width 0.254)
		(layer "F.Cu")
		(net "FAN_3_TACH1")
	)
	(segment
		(start 425.863004 -365.4425)
		(end 426.879004 -365.4425)
		(width 0.254)
		(layer "F.Cu")
		(net "FAN_3_TACH1")
	)
	(segment
		(start 426.879004 -365.4425)
		(end 426.879004 -367.1189)
		(width 0.254)
		(layer "F.Cu")
		(net "FAN_3_TACH1")
	)
	(segment
		(start 430.5427 -367.157)
		(end 426.917104 -367.157)
		(width 0.254)
		(layer "F.Cu")
		(net "FAN_3_TACH1")
	)
	(segment
		(start 424.783504 -365.4425)
		(end 425.863004 -365.4425)
		(width 0.254)
		(layer "F.Cu")
		(net "FAN_3_TACH1")
	)
	(segment
		(start 424.720004 -365.379)
		(end 424.783504 -365.4425)
		(width 0.254)
		(layer "F.Cu")
		(net "FAN_3_TACH1")
	)
	(segment
		(start 430.59985 -372.599966)
		(end 429.855884 -371.856)
		(width 0.254)
		(layer "F.Cu")
		(net "FAN_3_TACH0")
	)
	(segment
		(start 424.783504 -370.1415)
		(end 425.863004 -370.1415)
		(width 0.254)
		(layer "F.Cu")
		(net "FAN_3_TACH0")
	)
	(segment
		(start 424.720004 -370.078)
		(end 424.783504 -370.1415)
		(width 0.254)
		(layer "F.Cu")
		(net "FAN_3_TACH0")
	)
	(segment
		(start 426.879004 -370.1415)
		(end 426.917104 -370.1796)
		(width 0.254)
		(layer "F.Cu")
		(net "FAN_3_TACH0")
	)
	(segment
		(start 429.855884 -371.856)
		(end 426.917104 -371.856)
		(width 0.254)
		(layer "F.Cu")
		(net "FAN_3_TACH0")
	)
	(segment
		(start 426.917104 -370.1796)
		(end 426.917104 -371.856)
		(width 0.254)
		(layer "F.Cu")
		(net "FAN_3_TACH0")
	)
	(segment
		(start 425.863004 -370.1415)
		(end 426.879004 -370.1415)
		(width 0.254)
		(layer "F.Cu")
		(net "FAN_3_TACH0")
	)
	(segment
		(start 419.73754 -370.0145)
		(end 420.6875 -370.0145)
		(width 0.254)
		(layer "F.Cu")
		(net "FAN_3_PWM")
	)
	(segment
		(start 421.513 -370.84)
		(end 421.513 -372.618)
		(width 0.254)
		(layer "F.Cu")
		(net "FAN_3_PWM")
	)
	(segment
		(start 434.799994 -367.09985)
		(end 434.799994 -372.599966)
		(width 0.254)
		(layer "F.Cu")
		(net "FAN_3_PWM")
	)
	(segment
		(start 420.6875 -370.0145)
		(end 421.513 -370.84)
		(width 0.254)
		(layer "F.Cu")
		(net "FAN_3_PWM")
	)
	(segment
		(start 432.62296 -374.777)
		(end 434.799994 -372.599966)
		(width 0.254)
		(layer "F.Cu")
		(net "FAN_3_PWM")
	)
	(segment
		(start 423.672 -374.777)
		(end 432.62296 -374.777)
		(width 0.254)
		(layer "F.Cu")
		(net "FAN_3_PWM")
	)
	(segment
		(start 421.513 -372.618)
		(end 423.672 -374.777)
		(width 0.254)
		(layer "F.Cu")
		(net "FAN_3_PWM")
	)
	(segment
		(start 197.612254 -292.515798)
		(end 193.386456 -288.29)
		(width 0.17145)
		(layer "F.Cu")
		(net "FAN_3_INS_N")
	)
	(segment
		(start 249.471688 -298.864274)
		(end 253.053088 -298.864274)
		(width 0.17145)
		(layer "F.Cu")
		(net "FAN_3_INS_N")
	)
	(segment
		(start 420.6875 -372.11)
		(end 420.6875 -371.1575)
		(width 0.17145)
		(layer "F.Cu")
		(net "FAN_3_INS_N")
	)
	(segment
		(start 229.88016 -91.416378)
		(end 230.993442 -90.303096)
		(width 0.17145)
		(layer "F.Cu")
		(net "FAN_3_INS_N")
	)
	(segment
		(start 205.773528 -170.5356)
		(end 210.312 -170.5356)
		(width 0.17145)
		(layer "F.Cu")
		(net "FAN_3_INS_N")
	)
	(segment
		(start 215.09355 -165.089586)
		(end 215.817958 -164.365178)
		(width 0.17145)
		(layer "F.Cu")
		(net "FAN_3_INS_N")
	)
	(segment
		(start 201.319892 -168.092628)
		(end 203.330556 -168.092628)
		(width 0.17145)
		(layer "F.Cu")
		(net "FAN_3_INS_N")
	)
	(segment
		(start 210.312 -170.5356)
		(end 211.16798 -169.67962)
		(width 0.17145)
		(layer "F.Cu")
		(net "FAN_3_INS_N")
	)
	(segment
		(start 215.09355 -168.49725)
		(end 215.09355 -165.089586)
		(width 0.17145)
		(layer "F.Cu")
		(net "FAN_3_INS_N")
	)
	(segment
		(start 244.317012 -293.709598)
		(end 201.50201 -293.709598)
		(width 0.17145)
		(layer "F.Cu")
		(net "FAN_3_INS_N")
	)
	(segment
		(start 249.471688 -298.864274)
		(end 244.317012 -293.709598)
		(width 0.17145)
		(layer "F.Cu")
		(net "FAN_3_INS_N")
	)
	(segment
		(start 200.19264 -169.21988)
		(end 201.319892 -168.092628)
		(width 0.17145)
		(layer "F.Cu")
		(net "FAN_3_INS_N")
	)
	(segment
		(start 212.69706 -169.67962)
		(end 213.91118 -169.67962)
		(width 0.17145)
		(layer "F.Cu")
		(net "FAN_3_INS_N")
	)
	(segment
		(start 200.30821 -292.515798)
		(end 197.612254 -292.515798)
		(width 0.17145)
		(layer "F.Cu")
		(net "FAN_3_INS_N")
	)
	(segment
		(start 253.053088 -298.864274)
		(end 256.199132 -302.010318)
		(width 0.17145)
		(layer "F.Cu")
		(net "FAN_3_INS_N")
	)
	(segment
		(start 435.67985 -375.92)
		(end 438.999884 -372.599966)
		(width 0.17145)
		(layer "F.Cu")
		(net "FAN_3_INS_N")
	)
	(segment
		(start 423.545 -375.92)
		(end 435.67985 -375.92)
		(width 0.17145)
		(layer "F.Cu")
		(net "FAN_3_INS_N")
	)
	(segment
		(start 229.88016 -140.302996)
		(end 229.88016 -91.416378)
		(width 0.17145)
		(layer "F.Cu")
		(net "FAN_3_INS_N")
	)
	(segment
		(start 203.330556 -168.092628)
		(end 205.773528 -170.5356)
		(width 0.17145)
		(layer "F.Cu")
		(net "FAN_3_INS_N")
	)
	(segment
		(start 271.898364 -302.010318)
		(end 272.524474 -302.636428)
		(width 0.17145)
		(layer "F.Cu")
		(net "FAN_3_INS_N")
	)
	(segment
		(start 211.16798 -169.67962)
		(end 212.69706 -169.67962)
		(width 0.17145)
		(layer "F.Cu")
		(net "FAN_3_INS_N")
	)
	(segment
		(start 215.817958 -164.365178)
		(end 215.817958 -154.365198)
		(width 0.17145)
		(layer "F.Cu")
		(net "FAN_3_INS_N")
	)
	(segment
		(start 420.6875 -373.0625)
		(end 423.545 -375.92)
		(width 0.17145)
		(layer "F.Cu")
		(net "FAN_3_INS_N")
	)
	(segment
		(start 230.993442 -90.303096)
		(end 230.993442 -90.015822)
		(width 0.17145)
		(layer "F.Cu")
		(net "FAN_3_INS_N")
	)
	(segment
		(start 420.6875 -372.11)
		(end 420.6875 -373.0625)
		(width 0.17145)
		(layer "F.Cu")
		(net "FAN_3_INS_N")
	)
	(segment
		(start 215.817958 -154.365198)
		(end 229.88016 -140.302996)
		(width 0.17145)
		(layer "F.Cu")
		(net "FAN_3_INS_N")
	)
	(segment
		(start 213.91118 -169.67962)
		(end 215.09355 -168.49725)
		(width 0.17145)
		(layer "F.Cu")
		(net "FAN_3_INS_N")
	)
	(segment
		(start 201.50201 -293.709598)
		(end 200.30821 -292.515798)
		(width 0.17145)
		(layer "F.Cu")
		(net "FAN_3_INS_N")
	)
	(segment
		(start 256.199132 -302.010318)
		(end 271.898364 -302.010318)
		(width 0.17145)
		(layer "F.Cu")
		(net "FAN_3_INS_N")
	)
	(segment
		(start 193.386456 -288.29)
		(end 192.979548 -288.29)
		(width 0.17145)
		(layer "F.Cu")
		(net "FAN_3_INS_N")
	)
	(via
		(at 425.833794 -328.29373)
		(size 0.5588)
		(drill 0.3048)
		(layers "F.Cu" "B.Cu")
		(net "FAN_3_INS_N")
	)
	(via
		(at 249.471688 -298.864274)
		(size 0.6604)
		(drill 0.3302)
		(layers "F.Cu" "B.Cu")
		(net "FAN_3_INS_N")
	)
	(via
		(at 272.524474 -302.636428)
		(size 0.5588)
		(drill 0.3048)
		(layers "F.Cu" "B.Cu")
		(net "FAN_3_INS_N")
	)
	(via
		(at 200.19264 -169.21988)
		(size 0.5588)
		(drill 0.3048)
		(layers "F.Cu" "B.Cu")
		(net "FAN_3_INS_N")
	)
	(via
		(at 230.993442 -90.015822)
		(size 0.5588)
		(drill 0.3048)
		(layers "F.Cu" "B.Cu")
		(net "FAN_3_INS_N")
	)
	(via
		(at 192.979548 -288.29)
		(size 0.5588)
		(drill 0.3048)
		(layers "F.Cu" "B.Cu")
		(net "FAN_3_INS_N")
	)
	(via
		(at 420.6875 -371.1575)
		(size 0.5588)
		(drill 0.3048)
		(layers "F.Cu" "B.Cu")
		(net "FAN_3_INS_N")
	)
	(segment
		(start 429.387 -331.846936)
		(end 425.833794 -328.29373)
		(width 0.14605)
		(layer "In2.Cu")
		(net "FAN_3_INS_N")
	)
	(segment
		(start 192.795398 -222.504)
		(end 194.192398 -223.901)
		(width 0.14605)
		(layer "In2.Cu")
		(net "FAN_3_INS_N")
	)
	(segment
		(start 199.329548 -170.082972)
		(end 199.329548 -190.001652)
		(width 0.14605)
		(layer "In2.Cu")
		(net "FAN_3_INS_N")
	)
	(segment
		(start 194.192398 -223.901)
		(end 194.192398 -287.07715)
		(width 0.14605)
		(layer "In2.Cu")
		(net "FAN_3_INS_N")
	)
	(segment
		(start 188.4172 -191.897)
		(end 180.9496 -199.3646)
		(width 0.14605)
		(layer "In2.Cu")
		(net "FAN_3_INS_N")
	)
	(segment
		(start 191.271906 -222.504)
		(end 192.795398 -222.504)
		(width 0.14605)
		(layer "In2.Cu")
		(net "FAN_3_INS_N")
	)
	(segment
		(start 200.19264 -169.21988)
		(end 199.329548 -170.082972)
		(width 0.14605)
		(layer "In2.Cu")
		(net "FAN_3_INS_N")
	)
	(segment
		(start 420.6875 -367.286032)
		(end 429.387 -358.586532)
		(width 0.14605)
		(layer "In2.Cu")
		(net "FAN_3_INS_N")
	)
	(segment
		(start 420.6875 -371.1575)
		(end 420.6875 -367.286032)
		(width 0.14605)
		(layer "In2.Cu")
		(net "FAN_3_INS_N")
	)
	(segment
		(start 197.4342 -191.897)
		(end 188.4172 -191.897)
		(width 0.14605)
		(layer "In2.Cu")
		(net "FAN_3_INS_N")
	)
	(segment
		(start 429.387 -358.586532)
		(end 429.387 -331.846936)
		(width 0.14605)
		(layer "In2.Cu")
		(net "FAN_3_INS_N")
	)
	(segment
		(start 180.9496 -212.181694)
		(end 191.271906 -222.504)
		(width 0.14605)
		(layer "In2.Cu")
		(net "FAN_3_INS_N")
	)
	(segment
		(start 180.9496 -199.3646)
		(end 180.9496 -212.181694)
		(width 0.14605)
		(layer "In2.Cu")
		(net "FAN_3_INS_N")
	)
	(segment
		(start 199.329548 -190.001652)
		(end 197.4342 -191.897)
		(width 0.14605)
		(layer "In2.Cu")
		(net "FAN_3_INS_N")
	)
	(segment
		(start 194.192398 -287.07715)
		(end 192.979548 -288.29)
		(width 0.14605)
		(layer "In2.Cu")
		(net "FAN_3_INS_N")
	)
	(segment
		(start 228.000052 -69.200014)
		(end 229.154736 -70.354698)
		(width 0.14605)
		(layer "In5.Cu")
		(net "FAN_3_INS_N")
	)
	(segment
		(start 229.614476 -84.380324)
		(end 231.02824 -85.794088)
		(width 0.14605)
		(layer "In5.Cu")
		(net "FAN_3_INS_N")
	)
	(segment
		(start 425.833794 -328.29373)
		(end 424.689016 -327.148952)
		(width 0.14605)
		(layer "In5.Cu")
		(net "FAN_3_INS_N")
	)
	(segment
		(start 229.08768 -79.9973)
		(end 229.08768 -81.240122)
		(width 0.14605)
		(layer "In5.Cu")
		(net "FAN_3_INS_N")
	)
	(segment
		(start 231.02824 -85.794088)
		(end 231.02824 -89.981024)
		(width 0.14605)
		(layer "In5.Cu")
		(net "FAN_3_INS_N")
	)
	(segment
		(start 281.762708 -316.912752)
		(end 277.701248 -312.851292)
		(width 0.14605)
		(layer "In5.Cu")
		(net "FAN_3_INS_N")
	)
	(segment
		(start 424.689016 -327.148952)
		(end 323.444108 -327.148952)
		(width 0.14605)
		(layer "In5.Cu")
		(net "FAN_3_INS_N")
	)
	(segment
		(start 272.524474 -303.95545)
		(end 272.524474 -302.636428)
		(width 0.14605)
		(layer "In5.Cu")
		(net "FAN_3_INS_N")
	)
	(segment
		(start 277.701248 -309.132224)
		(end 272.524474 -303.95545)
		(width 0.14605)
		(layer "In5.Cu")
		(net "FAN_3_INS_N")
	)
	(segment
		(start 313.207908 -316.912752)
		(end 281.762708 -316.912752)
		(width 0.14605)
		(layer "In5.Cu")
		(net "FAN_3_INS_N")
	)
	(segment
		(start 229.154736 -70.354698)
		(end 229.154736 -79.930244)
		(width 0.14605)
		(layer "In5.Cu")
		(net "FAN_3_INS_N")
	)
	(segment
		(start 323.444108 -327.148952)
		(end 313.207908 -316.912752)
		(width 0.14605)
		(layer "In5.Cu")
		(net "FAN_3_INS_N")
	)
	(segment
		(start 231.02824 -89.981024)
		(end 230.993442 -90.015822)
		(width 0.14605)
		(layer "In5.Cu")
		(net "FAN_3_INS_N")
	)
	(segment
		(start 277.701248 -312.851292)
		(end 277.701248 -309.132224)
		(width 0.14605)
		(layer "In5.Cu")
		(net "FAN_3_INS_N")
	)
	(segment
		(start 229.08768 -81.240122)
		(end 229.614476 -81.766918)
		(width 0.14605)
		(layer "In5.Cu")
		(net "FAN_3_INS_N")
	)
	(segment
		(start 229.614476 -81.766918)
		(end 229.614476 -84.380324)
		(width 0.14605)
		(layer "In5.Cu")
		(net "FAN_3_INS_N")
	)
	(segment
		(start 229.154736 -79.930244)
		(end 229.08768 -79.9973)
		(width 0.14605)
		(layer "In5.Cu")
		(net "FAN_3_INS_N")
	)
	(segment
		(start 333.94269 -367.157)
		(end 330.333096 -367.157)
		(width 0.254)
		(layer "F.Cu")
		(net "FAN_2_TACH1")
	)
	(segment
		(start 329.278996 -365.4425)
		(end 330.294996 -365.4425)
		(width 0.254)
		(layer "F.Cu")
		(net "FAN_2_TACH1")
	)
	(segment
		(start 328.199496 -365.4425)
		(end 329.278996 -365.4425)
		(width 0.254)
		(layer "F.Cu")
		(net "FAN_2_TACH1")
	)
	(segment
		(start 330.333096 -365.4806)
		(end 330.333096 -367.157)
		(width 0.254)
		(layer "F.Cu")
		(net "FAN_2_TACH1")
	)
	(segment
		(start 330.294996 -365.4425)
		(end 330.333096 -365.4806)
		(width 0.254)
		(layer "F.Cu")
		(net "FAN_2_TACH1")
	)
	(segment
		(start 328.135996 -365.379)
		(end 328.199496 -365.4425)
		(width 0.254)
		(layer "F.Cu")
		(net "FAN_2_TACH1")
	)
	(segment
		(start 333.99984 -367.09985)
		(end 333.94269 -367.157)
		(width 0.254)
		(layer "F.Cu")
		(net "FAN_2_TACH1")
	)
	(segment
		(start 333.99984 -372.599966)
		(end 333.956406 -372.6434)
		(width 0.254)
		(layer "F.Cu")
		(net "FAN_2_TACH0")
	)
	(segment
		(start 333.956406 -372.6434)
		(end 331.120496 -372.6434)
		(width 0.254)
		(layer "F.Cu")
		(net "FAN_2_TACH0")
	)
	(segment
		(start 328.199496 -370.1415)
		(end 329.278996 -370.1415)
		(width 0.254)
		(layer "F.Cu")
		(net "FAN_2_TACH0")
	)
	(segment
		(start 329.278996 -370.1415)
		(end 330.294996 -370.1415)
		(width 0.254)
		(layer "F.Cu")
		(net "FAN_2_TACH0")
	)
	(segment
		(start 330.294996 -370.1415)
		(end 330.333096 -370.1796)
		(width 0.254)
		(layer "F.Cu")
		(net "FAN_2_TACH0")
	)
	(segment
		(start 331.120496 -372.6434)
		(end 330.333096 -371.856)
		(width 0.254)
		(layer "F.Cu")
		(net "FAN_2_TACH0")
	)
	(segment
		(start 328.135996 -370.078)
		(end 328.199496 -370.1415)
		(width 0.254)
		(layer "F.Cu")
		(net "FAN_2_TACH0")
	)
	(segment
		(start 330.333096 -370.1796)
		(end 330.333096 -371.856)
		(width 0.254)
		(layer "F.Cu")
		(net "FAN_2_TACH0")
	)
	(segment
		(start 338.199984 -372.599966)
		(end 335.94675 -374.8532)
		(width 0.254)
		(layer "F.Cu")
		(net "FAN_2_PWM")
	)
	(segment
		(start 328.275696 -374.8532)
		(end 327.183496 -373.761)
		(width 0.254)
		(layer "F.Cu")
		(net "FAN_2_PWM")
	)
	(segment
		(start 338.199984 -367.09985)
		(end 338.199984 -372.599966)
		(width 0.254)
		(layer "F.Cu")
		(net "FAN_2_PWM")
	)
	(segment
		(start 335.94675 -374.8532)
		(end 328.275696 -374.8532)
		(width 0.254)
		(layer "F.Cu")
		(net "FAN_2_PWM")
	)
	(segment
		(start 243.808504 -294.223948)
		(end 201.288904 -294.223948)
		(width 0.17145)
		(layer "F.Cu")
		(net "FAN_2_INS_N")
	)
	(segment
		(start 327.183496 -375.92)
		(end 327.183496 -376.4915)
		(width 0.17145)
		(layer "F.Cu")
		(net "FAN_2_INS_N")
	)
	(segment
		(start 215.6079 -168.86682)
		(end 214.14486 -170.32986)
		(width 0.17145)
		(layer "F.Cu")
		(net "FAN_2_INS_N")
	)
	(segment
		(start 230.71836 -91.54922)
		(end 230.39451 -91.87307)
		(width 0.17145)
		(layer "F.Cu")
		(net "FAN_2_INS_N")
	)
	(segment
		(start 216.332308 -155.20289)
		(end 216.332308 -164.578538)
		(width 0.17145)
		(layer "F.Cu")
		(net "FAN_2_INS_N")
	)
	(segment
		(start 327.183496 -376.4915)
		(end 327.551796 -376.8598)
		(width 0.17145)
		(layer "F.Cu")
		(net "FAN_2_INS_N")
	)
	(segment
		(start 193.5734 -289.2044)
		(end 192.9638 -289.2044)
		(width 0.17145)
		(layer "F.Cu")
		(net "FAN_2_INS_N")
	)
	(segment
		(start 215.6079 -165.302692)
		(end 215.6079 -168.86682)
		(width 0.17145)
		(layer "F.Cu")
		(net "FAN_2_INS_N")
	)
	(segment
		(start 200.095104 -293.030148)
		(end 197.399148 -293.030148)
		(width 0.17145)
		(layer "F.Cu")
		(net "FAN_2_INS_N")
	)
	(segment
		(start 216.031318 -164.879528)
		(end 216.031064 -164.879528)
		(width 0.17145)
		(layer "F.Cu")
		(net "FAN_2_INS_N")
	)
	(segment
		(start 197.399148 -293.030148)
		(end 193.5734 -289.2044)
		(width 0.17145)
		(layer "F.Cu")
		(net "FAN_2_INS_N")
	)
	(segment
		(start 255.975104 -302.529748)
		(end 253.114556 -299.6692)
		(width 0.17145)
		(layer "F.Cu")
		(net "FAN_2_INS_N")
	)
	(segment
		(start 201.288904 -294.223948)
		(end 200.095104 -293.030148)
		(width 0.17145)
		(layer "F.Cu")
		(net "FAN_2_INS_N")
	)
	(segment
		(start 250.7742 -299.6692)
		(end 249.253756 -299.6692)
		(width 0.17145)
		(layer "F.Cu")
		(net "FAN_2_INS_N")
	)
	(segment
		(start 339.07984 -375.92)
		(end 327.183496 -375.92)
		(width 0.17145)
		(layer "F.Cu")
		(net "FAN_2_INS_N")
	)
	(segment
		(start 271.416526 -302.64862)
		(end 257.92303 -302.64862)
		(width 0.17145)
		(layer "F.Cu")
		(net "FAN_2_INS_N")
	)
	(segment
		(start 202.333098 -171.04995)
		(end 200.975722 -169.692574)
		(width 0.17145)
		(layer "F.Cu")
		(net "FAN_2_INS_N")
	)
	(segment
		(start 253.114556 -299.6692)
		(end 250.7742 -299.6692)
		(width 0.17145)
		(layer "F.Cu")
		(net "FAN_2_INS_N")
	)
	(segment
		(start 257.804158 -302.529748)
		(end 255.975104 -302.529748)
		(width 0.17145)
		(layer "F.Cu")
		(net "FAN_2_INS_N")
	)
	(segment
		(start 230.39451 -91.87307)
		(end 230.39451 -141.140688)
		(width 0.17145)
		(layer "F.Cu")
		(net "FAN_2_INS_N")
	)
	(segment
		(start 257.92303 -302.64862)
		(end 257.804158 -302.529748)
		(width 0.17145)
		(layer "F.Cu")
		(net "FAN_2_INS_N")
	)
	(segment
		(start 212.69706 -170.32986)
		(end 211.245196 -170.32986)
		(width 0.17145)
		(layer "F.Cu")
		(net "FAN_2_INS_N")
	)
	(segment
		(start 214.14486 -170.32986)
		(end 212.69706 -170.32986)
		(width 0.17145)
		(layer "F.Cu")
		(net "FAN_2_INS_N")
	)
	(segment
		(start 210.525106 -171.04995)
		(end 202.333098 -171.04995)
		(width 0.17145)
		(layer "F.Cu")
		(net "FAN_2_INS_N")
	)
	(segment
		(start 216.332308 -164.578538)
		(end 216.031318 -164.879528)
		(width 0.17145)
		(layer "F.Cu")
		(net "FAN_2_INS_N")
	)
	(segment
		(start 216.031064 -164.879528)
		(end 215.6079 -165.302692)
		(width 0.17145)
		(layer "F.Cu")
		(net "FAN_2_INS_N")
	)
	(segment
		(start 211.245196 -170.32986)
		(end 210.525106 -171.04995)
		(width 0.17145)
		(layer "F.Cu")
		(net "FAN_2_INS_N")
	)
	(segment
		(start 249.253756 -299.6692)
		(end 243.808504 -294.223948)
		(width 0.17145)
		(layer "F.Cu")
		(net "FAN_2_INS_N")
	)
	(segment
		(start 342.399874 -372.599966)
		(end 339.07984 -375.92)
		(width 0.17145)
		(layer "F.Cu")
		(net "FAN_2_INS_N")
	)
	(segment
		(start 230.39451 -141.140688)
		(end 216.332308 -155.20289)
		(width 0.17145)
		(layer "F.Cu")
		(net "FAN_2_INS_N")
	)
	(via
		(at 271.416526 -302.64862)
		(size 0.5588)
		(drill 0.3048)
		(layers "F.Cu" "B.Cu")
		(net "FAN_2_INS_N")
	)
	(via
		(at 327.551796 -376.8598)
		(size 0.5588)
		(drill 0.3048)
		(layers "F.Cu" "B.Cu")
		(net "FAN_2_INS_N")
	)
	(via
		(at 192.9638 -289.2044)
		(size 0.5588)
		(drill 0.3048)
		(layers "F.Cu" "B.Cu")
		(net "FAN_2_INS_N")
	)
	(via
		(at 200.975722 -169.692574)
		(size 0.5588)
		(drill 0.3048)
		(layers "F.Cu" "B.Cu")
		(net "FAN_2_INS_N")
	)
	(via
		(at 230.71836 -91.54922)
		(size 0.5588)
		(drill 0.3048)
		(layers "F.Cu" "B.Cu")
		(net "FAN_2_INS_N")
	)
	(via
		(at 250.7742 -299.6692)
		(size 0.6604)
		(drill 0.3302)
		(layers "F.Cu" "B.Cu")
		(net "FAN_2_INS_N")
	)
	(segment
		(start 197.104 -212.692488)
		(end 196.719952 -213.076536)
		(width 0.14605)
		(layer "In2.Cu")
		(net "FAN_2_INS_N")
	)
	(segment
		(start 196.719952 -213.076536)
		(end 196.719952 -219.133166)
		(width 0.14605)
		(layer "In2.Cu")
		(net "FAN_2_INS_N")
	)
	(segment
		(start 228.000052 -68.09994)
		(end 228.10724 -68.09994)
		(width 0.14605)
		(layer "In2.Cu")
		(net "FAN_2_INS_N")
	)
	(segment
		(start 228.655626 -68.648326)
		(end 228.655626 -87.978742)
		(width 0.14605)
		(layer "In2.Cu")
		(net "FAN_2_INS_N")
	)
	(segment
		(start 196.719952 -219.133166)
		(end 194.630548 -221.22257)
		(width 0.14605)
		(layer "In2.Cu")
		(net "FAN_2_INS_N")
	)
	(segment
		(start 197.862698 -192.116202)
		(end 197.862698 -211.001102)
		(width 0.14605)
		(layer "In2.Cu")
		(net "FAN_2_INS_N")
	)
	(segment
		(start 199.767698 -190.211202)
		(end 197.862698 -192.116202)
		(width 0.14605)
		(layer "In2.Cu")
		(net "FAN_2_INS_N")
	)
	(segment
		(start 197.862698 -211.001102)
		(end 197.104 -211.7598)
		(width 0.14605)
		(layer "In2.Cu")
		(net "FAN_2_INS_N")
	)
	(segment
		(start 197.104 -211.7598)
		(end 197.104 -212.692488)
		(width 0.14605)
		(layer "In2.Cu")
		(net "FAN_2_INS_N")
	)
	(segment
		(start 228.655626 -87.978742)
		(end 228.649784 -87.984584)
		(width 0.14605)
		(layer "In2.Cu")
		(net "FAN_2_INS_N")
	)
	(segment
		(start 194.630548 -287.537652)
		(end 192.9638 -289.2044)
		(width 0.14605)
		(layer "In2.Cu")
		(net "FAN_2_INS_N")
	)
	(segment
		(start 200.975722 -169.692574)
		(end 199.767698 -170.900598)
		(width 0.14605)
		(layer "In2.Cu")
		(net "FAN_2_INS_N")
	)
	(segment
		(start 228.649784 -89.480644)
		(end 230.71836 -91.54922)
		(width 0.14605)
		(layer "In2.Cu")
		(net "FAN_2_INS_N")
	)
	(segment
		(start 199.767698 -170.900598)
		(end 199.767698 -190.211202)
		(width 0.14605)
		(layer "In2.Cu")
		(net "FAN_2_INS_N")
	)
	(segment
		(start 194.630548 -221.22257)
		(end 194.630548 -287.537652)
		(width 0.14605)
		(layer "In2.Cu")
		(net "FAN_2_INS_N")
	)
	(segment
		(start 228.649784 -87.984584)
		(end 228.649784 -89.480644)
		(width 0.14605)
		(layer "In2.Cu")
		(net "FAN_2_INS_N")
	)
	(segment
		(start 228.10724 -68.09994)
		(end 228.655626 -68.648326)
		(width 0.14605)
		(layer "In2.Cu")
		(net "FAN_2_INS_N")
	)
	(segment
		(start 271.614138 -303.664874)
		(end 277.262844 -309.31358)
		(width 0.14605)
		(layer "In5.Cu")
		(net "FAN_2_INS_N")
	)
	(segment
		(start 277.262844 -313.032902)
		(end 281.580844 -317.350902)
		(width 0.14605)
		(layer "In5.Cu")
		(net "FAN_2_INS_N")
	)
	(segment
		(start 271.416526 -302.64862)
		(end 271.614138 -302.846232)
		(width 0.14605)
		(layer "In5.Cu")
		(net "FAN_2_INS_N")
	)
	(segment
		(start 312.626756 -317.350902)
		(end 328.422 -333.146146)
		(width 0.14605)
		(layer "In5.Cu")
		(net "FAN_2_INS_N")
	)
	(segment
		(start 325.344536 -368.500152)
		(end 327.828148 -370.983764)
		(width 0.14605)
		(layer "In5.Cu")
		(net "FAN_2_INS_N")
	)
	(segment
		(start 277.262844 -309.31358)
		(end 277.262844 -313.032902)
		(width 0.14605)
		(layer "In5.Cu")
		(net "FAN_2_INS_N")
	)
	(segment
		(start 324.379844 -367.71326)
		(end 325.166736 -368.500152)
		(width 0.14605)
		(layer "In5.Cu")
		(net "FAN_2_INS_N")
	)
	(segment
		(start 325.166736 -368.500152)
		(end 325.344536 -368.500152)
		(width 0.14605)
		(layer "In5.Cu")
		(net "FAN_2_INS_N")
	)
	(segment
		(start 328.422 -360.90733)
		(end 324.379844 -364.949486)
		(width 0.14605)
		(layer "In5.Cu")
		(net "FAN_2_INS_N")
	)
	(segment
		(start 324.379844 -364.949486)
		(end 324.379844 -367.71326)
		(width 0.14605)
		(layer "In5.Cu")
		(net "FAN_2_INS_N")
	)
	(segment
		(start 281.580844 -317.350902)
		(end 312.626756 -317.350902)
		(width 0.14605)
		(layer "In5.Cu")
		(net "FAN_2_INS_N")
	)
	(segment
		(start 327.828148 -376.583448)
		(end 327.551796 -376.8598)
		(width 0.14605)
		(layer "In5.Cu")
		(net "FAN_2_INS_N")
	)
	(segment
		(start 328.422 -333.146146)
		(end 328.422 -360.90733)
		(width 0.14605)
		(layer "In5.Cu")
		(net "FAN_2_INS_N")
	)
	(segment
		(start 271.614138 -302.846232)
		(end 271.614138 -303.664874)
		(width 0.14605)
		(layer "In5.Cu")
		(net "FAN_2_INS_N")
	)
	(segment
		(start 327.828148 -370.983764)
		(end 327.828148 -376.583448)
		(width 0.14605)
		(layer "In5.Cu")
		(net "FAN_2_INS_N")
	)
	(segment
		(start 135.9408 -367.7793)
		(end 138.520424 -367.7793)
		(width 0.254)
		(layer "F.Cu")
		(net "FAN_1_TACH1")
	)
	(segment
		(start 134.2263 -368.8334)
		(end 134.2263 -367.8174)
		(width 0.254)
		(layer "F.Cu")
		(net "FAN_1_TACH1")
	)
	(segment
		(start 134.2263 -369.9129)
		(end 134.2263 -368.8334)
		(width 0.254)
		(layer "F.Cu")
		(net "FAN_1_TACH1")
	)
	(segment
		(start 134.1628 -369.9764)
		(end 134.2263 -369.9129)
		(width 0.254)
		(layer "F.Cu")
		(net "FAN_1_TACH1")
	)
	(segment
		(start 134.2263 -367.8174)
		(end 135.9027 -367.8174)
		(width 0.254)
		(layer "F.Cu")
		(net "FAN_1_TACH1")
	)
	(segment
		(start 135.9027 -367.8174)
		(end 135.9408 -367.7793)
		(width 0.254)
		(layer "F.Cu")
		(net "FAN_1_TACH1")
	)
	(segment
		(start 138.520424 -367.7793)
		(end 139.199874 -367.09985)
		(width 0.254)
		(layer "F.Cu")
		(net "FAN_1_TACH1")
	)
	(segment
		(start 130.829304 -373.868696)
		(end 131.445 -373.868696)
		(width 0.254)
		(layer "F.Cu")
		(net "FAN_1_TACH0")
	)
	(segment
		(start 130.175 -374.523)
		(end 130.829304 -373.868696)
		(width 0.254)
		(layer "F.Cu")
		(net "FAN_1_TACH0")
	)
	(segment
		(start 132.314696 -373.868696)
		(end 131.445 -373.868696)
		(width 0.254)
		(layer "F.Cu")
		(net "FAN_1_TACH0")
	)
	(segment
		(start 129.7305 -372.3005)
		(end 129.667 -372.237)
		(width 0.254)
		(layer "F.Cu")
		(net "FAN_1_TACH0")
	)
	(segment
		(start 139.199874 -372.599966)
		(end 136.879838 -374.920002)
		(width 0.254)
		(layer "F.Cu")
		(net "FAN_1_TACH0")
	)
	(segment
		(start 136.879838 -374.920002)
		(end 133.366002 -374.920002)
		(width 0.254)
		(layer "F.Cu")
		(net "FAN_1_TACH0")
	)
	(segment
		(start 129.7305 -374.523)
		(end 130.175 -374.523)
		(width 0.254)
		(layer "F.Cu")
		(net "FAN_1_TACH0")
	)
	(segment
		(start 133.366002 -374.920002)
		(end 132.314696 -373.868696)
		(width 0.254)
		(layer "F.Cu")
		(net "FAN_1_TACH0")
	)
	(segment
		(start 129.7305 -374.523)
		(end 129.7305 -373.507)
		(width 0.254)
		(layer "F.Cu")
		(net "FAN_1_TACH0")
	)
	(segment
		(start 129.7305 -373.507)
		(end 129.7305 -372.3005)
		(width 0.254)
		(layer "F.Cu")
		(net "FAN_1_TACH0")
	)
	(segment
		(start 160.7185 -371.983)
		(end 160.7185 -373.1895)
		(width 0.254)
		(layer "F.Cu")
		(net "FAN_1_PWM")
	)
	(segment
		(start 160.7185 -373.1895)
		(end 156.583888 -377.324112)
		(width 0.254)
		(layer "F.Cu")
		(net "FAN_1_PWM")
	)
	(segment
		(start 143.400018 -373.637302)
		(end 143.400018 -372.599966)
		(width 0.254)
		(layer "F.Cu")
		(net "FAN_1_PWM")
	)
	(segment
		(start 156.583888 -377.324112)
		(end 147.086828 -377.324112)
		(width 0.254)
		(layer "F.Cu")
		(net "FAN_1_PWM")
	)
	(segment
		(start 147.086828 -377.324112)
		(end 143.400018 -373.637302)
		(width 0.254)
		(layer "F.Cu")
		(net "FAN_1_PWM")
	)
	(segment
		(start 143.400018 -367.09985)
		(end 143.400018 -372.599966)
		(width 0.254)
		(layer "F.Cu")
		(net "FAN_1_PWM")
	)
	(segment
		(start 230.90886 -94.05112)
		(end 231.23144 -93.72854)
		(width 0.17145)
		(layer "F.Cu")
		(net "FAN_1_INS_N")
	)
	(segment
		(start 216.12225 -165.515798)
		(end 216.24417 -165.393878)
		(width 0.17145)
		(layer "F.Cu")
		(net "FAN_1_INS_N")
	)
	(segment
		(start 212.69706 -170.9801)
		(end 214.31758 -170.9801)
		(width 0.17145)
		(layer "F.Cu")
		(net "FAN_1_INS_N")
	)
	(segment
		(start 216.846658 -164.791644)
		(end 216.846658 -156.780992)
		(width 0.17145)
		(layer "F.Cu")
		(net "FAN_1_INS_N")
	)
	(segment
		(start 216.244424 -165.393878)
		(end 216.846658 -164.791644)
		(width 0.17145)
		(layer "F.Cu")
		(net "FAN_1_INS_N")
	)
	(segment
		(start 159.1945 -372.0465)
		(end 154.944572 -376.296428)
		(width 0.17145)
		(layer "F.Cu")
		(net "FAN_1_INS_N")
	)
	(segment
		(start 214.31758 -170.9801)
		(end 216.12225 -169.17543)
		(width 0.17145)
		(layer "F.Cu")
		(net "FAN_1_INS_N")
	)
	(segment
		(start 204.85989 -171.75734)
		(end 206.711804 -171.75734)
		(width 0.17145)
		(layer "F.Cu")
		(net "FAN_1_INS_N")
	)
	(segment
		(start 211.322412 -170.9801)
		(end 212.69706 -170.9801)
		(width 0.17145)
		(layer "F.Cu")
		(net "FAN_1_INS_N")
	)
	(segment
		(start 159.639 -372.0465)
		(end 159.639 -372.999)
		(width 0.17145)
		(layer "F.Cu")
		(net "FAN_1_INS_N")
	)
	(segment
		(start 159.639 -372.0465)
		(end 159.1945 -372.0465)
		(width 0.17145)
		(layer "F.Cu")
		(net "FAN_1_INS_N")
	)
	(segment
		(start 210.737958 -171.564554)
		(end 211.322412 -170.9801)
		(width 0.17145)
		(layer "F.Cu")
		(net "FAN_1_INS_N")
	)
	(segment
		(start 216.846658 -156.780992)
		(end 230.90505 -142.7226)
		(width 0.17145)
		(layer "F.Cu")
		(net "FAN_1_INS_N")
	)
	(segment
		(start 231.23144 -93.72854)
		(end 231.23144 -92.33408)
		(width 0.17145)
		(layer "F.Cu")
		(net "FAN_1_INS_N")
	)
	(segment
		(start 230.90886 -141.353794)
		(end 230.90886 -94.05112)
		(width 0.17145)
		(layer "F.Cu")
		(net "FAN_1_INS_N")
	)
	(segment
		(start 230.90505 -142.7226)
		(end 230.90505 -141.357604)
		(width 0.17145)
		(layer "F.Cu")
		(net "FAN_1_INS_N")
	)
	(segment
		(start 203.80706 -171.75734)
		(end 202.2348 -173.3296)
		(width 0.17145)
		(layer "F.Cu")
		(net "FAN_1_INS_N")
	)
	(segment
		(start 206.90459 -171.564554)
		(end 210.737958 -171.564554)
		(width 0.17145)
		(layer "F.Cu")
		(net "FAN_1_INS_N")
	)
	(segment
		(start 147.599908 -374.701816)
		(end 147.599908 -372.599966)
		(width 0.17145)
		(layer "F.Cu")
		(net "FAN_1_INS_N")
	)
	(segment
		(start 149.19452 -376.296428)
		(end 147.599908 -374.701816)
		(width 0.17145)
		(layer "F.Cu")
		(net "FAN_1_INS_N")
	)
	(segment
		(start 230.90505 -141.357604)
		(end 230.90886 -141.353794)
		(width 0.17145)
		(layer "F.Cu")
		(net "FAN_1_INS_N")
	)
	(segment
		(start 231.23144 -92.33408)
		(end 231.22382 -92.32646)
		(width 0.17145)
		(layer "F.Cu")
		(net "FAN_1_INS_N")
	)
	(segment
		(start 154.944572 -376.296428)
		(end 149.19452 -376.296428)
		(width 0.17145)
		(layer "F.Cu")
		(net "FAN_1_INS_N")
	)
	(segment
		(start 216.24417 -165.393878)
		(end 216.244424 -165.393878)
		(width 0.17145)
		(layer "F.Cu")
		(net "FAN_1_INS_N")
	)
	(segment
		(start 204.85989 -171.75734)
		(end 203.80706 -171.75734)
		(width 0.17145)
		(layer "F.Cu")
		(net "FAN_1_INS_N")
	)
	(segment
		(start 216.12225 -169.17543)
		(end 216.12225 -165.515798)
		(width 0.17145)
		(layer "F.Cu")
		(net "FAN_1_INS_N")
	)
	(segment
		(start 206.711804 -171.75734)
		(end 206.90459 -171.564554)
		(width 0.17145)
		(layer "F.Cu")
		(net "FAN_1_INS_N")
	)
	(via
		(at 202.2348 -173.3296)
		(size 0.5588)
		(drill 0.3048)
		(layers "F.Cu" "B.Cu")
		(net "FAN_1_INS_N")
	)
	(via
		(at 204.85989 -171.75734)
		(size 0.6604)
		(drill 0.3302)
		(layers "F.Cu" "B.Cu")
		(net "FAN_1_INS_N")
	)
	(via
		(at 159.639 -372.999)
		(size 0.5588)
		(drill 0.3048)
		(layers "F.Cu" "B.Cu")
		(net "FAN_1_INS_N")
	)
	(via
		(at 231.22382 -92.32646)
		(size 0.5588)
		(drill 0.3048)
		(layers "F.Cu" "B.Cu")
		(net "FAN_1_INS_N")
	)
	(via
		(at 189.23 -371.602)
		(size 0.5588)
		(drill 0.3048)
		(layers "F.Cu" "B.Cu")
		(net "FAN_1_INS_N")
	)
	(segment
		(start 191.938148 -293.350696)
		(end 196.719952 -288.568892)
		(width 0.14605)
		(layer "In2.Cu")
		(net "FAN_1_INS_N")
	)
	(segment
		(start 229.659688 -87.984584)
		(end 229.659688 -89.642188)
		(width 0.14605)
		(layer "In2.Cu")
		(net "FAN_1_INS_N")
	)
	(segment
		(start 201.622152 -173.942248)
		(end 202.2348 -173.3296)
		(width 0.14605)
		(layer "In2.Cu")
		(net "FAN_1_INS_N")
	)
	(segment
		(start 196.719952 -222.049086)
		(end 199.717406 -219.051632)
		(width 0.14605)
		(layer "In2.Cu")
		(net "FAN_1_INS_N")
	)
	(segment
		(start 189.23 -371.602)
		(end 189.23 -369.316)
		(width 0.14605)
		(layer "In2.Cu")
		(net "FAN_1_INS_N")
	)
	(segment
		(start 231.22382 -91.20632)
		(end 231.22382 -92.32646)
		(width 0.14605)
		(layer "In2.Cu")
		(net "FAN_1_INS_N")
	)
	(segment
		(start 204.748892 -325.460614)
		(end 191.938148 -312.64987)
		(width 0.14605)
		(layer "In2.Cu")
		(net "FAN_1_INS_N")
	)
	(segment
		(start 187.25388 -367.33988)
		(end 187.25388 -361.497626)
		(width 0.14605)
		(layer "In2.Cu")
		(net "FAN_1_INS_N")
	)
	(segment
		(start 228.000052 -66.999866)
		(end 228.033326 -66.999866)
		(width 0.14605)
		(layer "In2.Cu")
		(net "FAN_1_INS_N")
	)
	(segment
		(start 199.717406 -192.977516)
		(end 201.622152 -191.07277)
		(width 0.14605)
		(layer "In2.Cu")
		(net "FAN_1_INS_N")
	)
	(segment
		(start 196.719952 -288.568892)
		(end 196.719952 -222.049086)
		(width 0.14605)
		(layer "In2.Cu")
		(net "FAN_1_INS_N")
	)
	(segment
		(start 189.113414 -359.638092)
		(end 203.13015 -359.638092)
		(width 0.14605)
		(layer "In2.Cu")
		(net "FAN_1_INS_N")
	)
	(segment
		(start 229.157276 -87.482172)
		(end 229.659688 -87.984584)
		(width 0.14605)
		(layer "In2.Cu")
		(net "FAN_1_INS_N")
	)
	(segment
		(start 229.659688 -89.642188)
		(end 231.22382 -91.20632)
		(width 0.14605)
		(layer "In2.Cu")
		(net "FAN_1_INS_N")
	)
	(segment
		(start 187.25388 -361.497626)
		(end 189.113414 -359.638092)
		(width 0.14605)
		(layer "In2.Cu")
		(net "FAN_1_INS_N")
	)
	(segment
		(start 229.157276 -68.123816)
		(end 229.157276 -87.482172)
		(width 0.14605)
		(layer "In2.Cu")
		(net "FAN_1_INS_N")
	)
	(segment
		(start 228.033326 -66.999866)
		(end 229.157276 -68.123816)
		(width 0.14605)
		(layer "In2.Cu")
		(net "FAN_1_INS_N")
	)
	(segment
		(start 199.717406 -219.051632)
		(end 199.717406 -192.977516)
		(width 0.14605)
		(layer "In2.Cu")
		(net "FAN_1_INS_N")
	)
	(segment
		(start 191.938148 -312.64987)
		(end 191.938148 -293.350696)
		(width 0.14605)
		(layer "In2.Cu")
		(net "FAN_1_INS_N")
	)
	(segment
		(start 201.622152 -191.07277)
		(end 201.622152 -173.942248)
		(width 0.14605)
		(layer "In2.Cu")
		(net "FAN_1_INS_N")
	)
	(segment
		(start 203.13015 -359.638092)
		(end 204.748892 -358.01935)
		(width 0.14605)
		(layer "In2.Cu")
		(net "FAN_1_INS_N")
	)
	(segment
		(start 204.748892 -358.01935)
		(end 204.748892 -325.460614)
		(width 0.14605)
		(layer "In2.Cu")
		(net "FAN_1_INS_N")
	)
	(segment
		(start 189.23 -369.316)
		(end 187.25388 -367.33988)
		(width 0.14605)
		(layer "In2.Cu")
		(net "FAN_1_INS_N")
	)
	(segment
		(start 182.106062 -373.312182)
		(end 187.646818 -373.312182)
		(width 0.14605)
		(layer "In5.Cu")
		(net "FAN_1_INS_N")
	)
	(segment
		(start 162.5346 -375.8946)
		(end 179.523644 -375.8946)
		(width 0.14605)
		(layer "In5.Cu")
		(net "FAN_1_INS_N")
	)
	(segment
		(start 179.523644 -375.8946)
		(end 182.106062 -373.312182)
		(width 0.14605)
		(layer "In5.Cu")
		(net "FAN_1_INS_N")
	)
	(segment
		(start 189.23 -371.729)
		(end 189.23 -371.602)
		(width 0.14605)
		(layer "In5.Cu")
		(net "FAN_1_INS_N")
	)
	(segment
		(start 159.639 -372.999)
		(end 162.5346 -375.8946)
		(width 0.14605)
		(layer "In5.Cu")
		(net "FAN_1_INS_N")
	)
	(segment
		(start 187.646818 -373.312182)
		(end 189.23 -371.729)
		(width 0.14605)
		(layer "In5.Cu")
		(net "FAN_1_INS_N")
	)
	(segment
		(start 38.956996 -365.4425)
		(end 38.995096 -365.4806)
		(width 0.254)
		(layer "F.Cu")
		(net "FAN_0_TACH1")
	)
	(segment
		(start 36.861496 -365.4425)
		(end 37.940996 -365.4425)
		(width 0.254)
		(layer "F.Cu")
		(net "FAN_0_TACH1")
	)
	(segment
		(start 42.599864 -367.09985)
		(end 42.542714 -367.157)
		(width 0.254)
		(layer "F.Cu")
		(net "FAN_0_TACH1")
	)
	(segment
		(start 36.797996 -365.379)
		(end 36.861496 -365.4425)
		(width 0.254)
		(layer "F.Cu")
		(net "FAN_0_TACH1")
	)
	(segment
		(start 42.542714 -367.157)
		(end 38.995096 -367.157)
		(width 0.254)
		(layer "F.Cu")
		(net "FAN_0_TACH1")
	)
	(segment
		(start 37.940996 -365.4425)
		(end 38.956996 -365.4425)
		(width 0.254)
		(layer "F.Cu")
		(net "FAN_0_TACH1")
	)
	(segment
		(start 38.995096 -365.4806)
		(end 38.995096 -367.157)
		(width 0.254)
		(layer "F.Cu")
		(net "FAN_0_TACH1")
	)
	(segment
		(start 38.995096 -370.1796)
		(end 38.995096 -371.856)
		(width 0.254)
		(layer "F.Cu")
		(net "FAN_0_TACH0")
	)
	(segment
		(start 39.739062 -372.599966)
		(end 38.995096 -371.856)
		(width 0.254)
		(layer "F.Cu")
		(net "FAN_0_TACH0")
	)
	(segment
		(start 36.861496 -370.1415)
		(end 37.940996 -370.1415)
		(width 0.254)
		(layer "F.Cu")
		(net "FAN_0_TACH0")
	)
	(segment
		(start 36.797996 -370.078)
		(end 36.861496 -370.1415)
		(width 0.254)
		(layer "F.Cu")
		(net "FAN_0_TACH0")
	)
	(segment
		(start 42.599864 -372.599966)
		(end 39.739062 -372.599966)
		(width 0.254)
		(layer "F.Cu")
		(net "FAN_0_TACH0")
	)
	(segment
		(start 38.956996 -370.1415)
		(end 38.995096 -370.1796)
		(width 0.254)
		(layer "F.Cu")
		(net "FAN_0_TACH0")
	)
	(segment
		(start 37.940996 -370.1415)
		(end 38.956996 -370.1415)
		(width 0.254)
		(layer "F.Cu")
		(net "FAN_0_TACH0")
	)
	(segment
		(start 38.663118 -374.777)
		(end 38.002718 -374.1166)
		(width 0.254)
		(layer "F.Cu")
		(net "FAN_0_PWM")
	)
	(segment
		(start 38.002718 -374.1166)
		(end 35.870896 -374.1166)
		(width 0.254)
		(layer "F.Cu")
		(net "FAN_0_PWM")
	)
	(segment
		(start 46.800008 -367.09985)
		(end 46.800008 -372.599966)
		(width 0.254)
		(layer "F.Cu")
		(net "FAN_0_PWM")
	)
	(segment
		(start 46.800008 -372.599966)
		(end 44.622974 -374.777)
		(width 0.254)
		(layer "F.Cu")
		(net "FAN_0_PWM")
	)
	(segment
		(start 44.622974 -374.777)
		(end 38.663118 -374.777)
		(width 0.254)
		(layer "F.Cu")
		(net "FAN_0_PWM")
	)
	(segment
		(start 201.425556 -173.89729)
		(end 206.05623 -173.89729)
		(width 0.17145)
		(layer "F.Cu")
		(net "FAN_0_INS_N")
	)
	(segment
		(start 38.304978 -375.4755)
		(end 37.897308 -375.06783)
		(width 0.17145)
		(layer "F.Cu")
		(net "FAN_0_INS_N")
	)
	(segment
		(start 207.874616 -172.078904)
		(end 210.951064 -172.078904)
		(width 0.17145)
		(layer "F.Cu")
		(net "FAN_0_INS_N")
	)
	(segment
		(start 211.399628 -171.63034)
		(end 212.69706 -171.63034)
		(width 0.17145)
		(layer "F.Cu")
		(net "FAN_0_INS_N")
	)
	(segment
		(start 33.283144 -374.542304)
		(end 34.21634 -375.4755)
		(width 0.17145)
		(layer "F.Cu")
		(net "FAN_0_INS_N")
	)
	(segment
		(start 217.361008 -159.072072)
		(end 219.31122 -157.12186)
		(width 0.17145)
		(layer "F.Cu")
		(net "FAN_0_INS_N")
	)
	(segment
		(start 38.75151 -375.884948)
		(end 38.342062 -375.4755)
		(width 0.17145)
		(layer "F.Cu")
		(net "FAN_0_INS_N")
	)
	(segment
		(start 38.342062 -375.4755)
		(end 38.304978 -375.4755)
		(width 0.17145)
		(layer "F.Cu")
		(net "FAN_0_INS_N")
	)
	(segment
		(start 35.473894 -375.4755)
		(end 35.400996 -375.4755)
		(width 0.17145)
		(layer "F.Cu")
		(net "FAN_0_INS_N")
	)
	(segment
		(start 214.60714 -171.63034)
		(end 216.6366 -169.60088)
		(width 0.17145)
		(layer "F.Cu")
		(net "FAN_0_INS_N")
	)
	(segment
		(start 35.881564 -375.06783)
		(end 35.473894 -375.4755)
		(width 0.17145)
		(layer "F.Cu")
		(net "FAN_0_INS_N")
	)
	(segment
		(start 217.361008 -165.00475)
		(end 217.361008 -159.072072)
		(width 0.17145)
		(layer "F.Cu")
		(net "FAN_0_INS_N")
	)
	(segment
		(start 206.05623 -173.89729)
		(end 207.290416 -172.663104)
		(width 0.17145)
		(layer "F.Cu")
		(net "FAN_0_INS_N")
	)
	(segment
		(start 200.518268 -172.990002)
		(end 201.425556 -173.89729)
		(width 0.17145)
		(layer "F.Cu")
		(net "FAN_0_INS_N")
	)
	(segment
		(start 37.897308 -375.06783)
		(end 35.881564 -375.06783)
		(width 0.17145)
		(layer "F.Cu")
		(net "FAN_0_INS_N")
	)
	(segment
		(start 216.6366 -165.729158)
		(end 217.361008 -165.00475)
		(width 0.17145)
		(layer "F.Cu")
		(net "FAN_0_INS_N")
	)
	(segment
		(start 33.283144 -367.985548)
		(end 33.283144 -374.542304)
		(width 0.17145)
		(layer "F.Cu")
		(net "FAN_0_INS_N")
	)
	(segment
		(start 50.999898 -372.599966)
		(end 47.714916 -375.884948)
		(width 0.17145)
		(layer "F.Cu")
		(net "FAN_0_INS_N")
	)
	(segment
		(start 210.951064 -172.078904)
		(end 211.399628 -171.63034)
		(width 0.17145)
		(layer "F.Cu")
		(net "FAN_0_INS_N")
	)
	(segment
		(start 212.69706 -171.63034)
		(end 214.60714 -171.63034)
		(width 0.17145)
		(layer "F.Cu")
		(net "FAN_0_INS_N")
	)
	(segment
		(start 216.6366 -169.60088)
		(end 216.6366 -165.729158)
		(width 0.17145)
		(layer "F.Cu")
		(net "FAN_0_INS_N")
	)
	(segment
		(start 47.714916 -375.884948)
		(end 38.75151 -375.884948)
		(width 0.17145)
		(layer "F.Cu")
		(net "FAN_0_INS_N")
	)
	(segment
		(start 31.717996 -366.4204)
		(end 33.283144 -367.985548)
		(width 0.17145)
		(layer "F.Cu")
		(net "FAN_0_INS_N")
	)
	(segment
		(start 207.290416 -172.663104)
		(end 207.874616 -172.078904)
		(width 0.17145)
		(layer "F.Cu")
		(net "FAN_0_INS_N")
	)
	(segment
		(start 34.21634 -375.4755)
		(end 35.400996 -375.4755)
		(width 0.17145)
		(layer "F.Cu")
		(net "FAN_0_INS_N")
	)
	(via
		(at 200.518268 -172.990002)
		(size 0.5588)
		(drill 0.3048)
		(layers "F.Cu" "B.Cu")
		(net "FAN_0_INS_N")
	)
	(via
		(at 31.717996 -366.4204)
		(size 0.5588)
		(drill 0.3048)
		(layers "F.Cu" "B.Cu")
		(net "FAN_0_INS_N")
	)
	(via
		(at 207.290416 -172.663104)
		(size 0.6604)
		(drill 0.3302)
		(layers "F.Cu" "B.Cu")
		(net "FAN_0_INS_N")
	)
	(via
		(at 219.31122 -157.12186)
		(size 0.5588)
		(drill 0.3048)
		(layers "F.Cu" "B.Cu")
		(net "FAN_0_INS_N")
	)
	(segment
		(start 30.803596 -362.0008)
		(end 34.000948 -358.803448)
		(width 0.14605)
		(layer "In2.Cu")
		(net "FAN_0_INS_N")
	)
	(segment
		(start 226.85121 -73.98385)
		(end 226.85121 -105.595674)
		(width 0.14605)
		(layer "In2.Cu")
		(net "FAN_0_INS_N")
	)
	(segment
		(start 219.239592 -157.050232)
		(end 219.31122 -157.12186)
		(width 0.14605)
		(layer "In2.Cu")
		(net "FAN_0_INS_N")
	)
	(segment
		(start 218.826588 -119.70639)
		(end 218.826588 -120.069102)
		(width 0.14605)
		(layer "In2.Cu")
		(net "FAN_0_INS_N")
	)
	(segment
		(start 227.24872 -66.351404)
		(end 227.24872 -73.58634)
		(width 0.14605)
		(layer "In2.Cu")
		(net "FAN_0_INS_N")
	)
	(segment
		(start 34.000948 -358.803448)
		(end 34.000948 -323.631052)
		(width 0.14605)
		(layer "In2.Cu")
		(net "FAN_0_INS_N")
	)
	(segment
		(start 195.068698 -288.090102)
		(end 195.068698 -221.40418)
		(width 0.14605)
		(layer "In2.Cu")
		(net "FAN_0_INS_N")
	)
	(segment
		(start 219.239592 -153.44013)
		(end 219.239592 -157.050232)
		(width 0.14605)
		(layer "In2.Cu")
		(net "FAN_0_INS_N")
	)
	(segment
		(start 228.000052 -65.600072)
		(end 227.24872 -66.351404)
		(width 0.14605)
		(layer "In2.Cu")
		(net "FAN_0_INS_N")
	)
	(segment
		(start 219.808044 -112.638586)
		(end 219.808044 -118.724934)
		(width 0.14605)
		(layer "In2.Cu")
		(net "FAN_0_INS_N")
	)
	(segment
		(start 200.205848 -173.302422)
		(end 200.518268 -172.990002)
		(width 0.14605)
		(layer "In2.Cu")
		(net "FAN_0_INS_N")
	)
	(segment
		(start 30.803596 -365.506)
		(end 30.803596 -362.0008)
		(width 0.14605)
		(layer "In2.Cu")
		(net "FAN_0_INS_N")
	)
	(segment
		(start 218.157044 -152.357582)
		(end 219.239592 -153.44013)
		(width 0.14605)
		(layer "In2.Cu")
		(net "FAN_0_INS_N")
	)
	(segment
		(start 219.808044 -118.724934)
		(end 218.826588 -119.70639)
		(width 0.14605)
		(layer "In2.Cu")
		(net "FAN_0_INS_N")
	)
	(segment
		(start 198.300848 -192.297812)
		(end 200.205848 -190.392812)
		(width 0.14605)
		(layer "In2.Cu")
		(net "FAN_0_INS_N")
	)
	(segment
		(start 197.158102 -219.314776)
		(end 197.158102 -213.258146)
		(width 0.14605)
		(layer "In2.Cu")
		(net "FAN_0_INS_N")
	)
	(segment
		(start 198.300848 -212.1154)
		(end 198.300848 -192.297812)
		(width 0.14605)
		(layer "In2.Cu")
		(net "FAN_0_INS_N")
	)
	(segment
		(start 220.064584 -112.3823)
		(end 220.06433 -112.3823)
		(width 0.14605)
		(layer "In2.Cu")
		(net "FAN_0_INS_N")
	)
	(segment
		(start 46.609 -311.023)
		(end 172.1358 -311.023)
		(width 0.14605)
		(layer "In2.Cu")
		(net "FAN_0_INS_N")
	)
	(segment
		(start 34.000948 -323.631052)
		(end 46.609 -311.023)
		(width 0.14605)
		(layer "In2.Cu")
		(net "FAN_0_INS_N")
	)
	(segment
		(start 218.826588 -120.069102)
		(end 218.826842 -120.069356)
		(width 0.14605)
		(layer "In2.Cu")
		(net "FAN_0_INS_N")
	)
	(segment
		(start 218.157044 -124.611638)
		(end 218.157044 -152.357582)
		(width 0.14605)
		(layer "In2.Cu")
		(net "FAN_0_INS_N")
	)
	(segment
		(start 31.717996 -366.4204)
		(end 30.803596 -365.506)
		(width 0.14605)
		(layer "In2.Cu")
		(net "FAN_0_INS_N")
	)
	(segment
		(start 218.826842 -123.94184)
		(end 218.157044 -124.611638)
		(width 0.14605)
		(layer "In2.Cu")
		(net "FAN_0_INS_N")
	)
	(segment
		(start 195.068698 -221.40418)
		(end 197.158102 -219.314776)
		(width 0.14605)
		(layer "In2.Cu")
		(net "FAN_0_INS_N")
	)
	(segment
		(start 226.85121 -105.595674)
		(end 220.064584 -112.3823)
		(width 0.14605)
		(layer "In2.Cu")
		(net "FAN_0_INS_N")
	)
	(segment
		(start 172.1358 -311.023)
		(end 195.068698 -288.090102)
		(width 0.14605)
		(layer "In2.Cu")
		(net "FAN_0_INS_N")
	)
	(segment
		(start 197.158102 -213.258146)
		(end 198.300848 -212.1154)
		(width 0.14605)
		(layer "In2.Cu")
		(net "FAN_0_INS_N")
	)
	(segment
		(start 200.205848 -190.392812)
		(end 200.205848 -173.302422)
		(width 0.14605)
		(layer "In2.Cu")
		(net "FAN_0_INS_N")
	)
	(segment
		(start 220.06433 -112.3823)
		(end 219.808044 -112.638586)
		(width 0.14605)
		(layer "In2.Cu")
		(net "FAN_0_INS_N")
	)
	(segment
		(start 227.24872 -73.58634)
		(end 226.85121 -73.98385)
		(width 0.14605)
		(layer "In2.Cu")
		(net "FAN_0_INS_N")
	)
	(segment
		(start 218.826842 -120.069356)
		(end 218.826842 -123.94184)
		(width 0.14605)
		(layer "In2.Cu")
		(net "FAN_0_INS_N")
	)
	(segment
		(start 410.300424 -181.130194)
		(end 410.300424 -208.91246)
		(width 0.254)
		(layer "F.Cu")
		(net "DRV_ACT_9")
	)
	(segment
		(start 410.464 -213.487)
		(end 410.464 -212.102954)
		(width 0.254)
		(layer "F.Cu")
		(net "DRV_ACT_9")
	)
	(segment
		(start 410.464 -212.102954)
		(end 410.300424 -211.939378)
		(width 0.254)
		(layer "F.Cu")
		(net "DRV_ACT_9")
	)
	(segment
		(start 410.300424 -211.939378)
		(end 410.300424 -208.91246)
		(width 0.254)
		(layer "F.Cu")
		(net "DRV_ACT_9")
	)
	(via
		(at 410.300424 -208.91246)
		(size 0.6604)
		(drill 0.3302)
		(layers "F.Cu" "B.Cu")
		(net "DRV_ACT_9")
	)
	(segment
		(start 378.750322 -210.76158)
		(end 378.750322 -208.6229)
		(width 0.254)
		(layer "F.Cu")
		(net "DRV_ACT_8")
	)
	(segment
		(start 378.968 -213.487)
		(end 378.968 -210.979258)
		(width 0.254)
		(layer "F.Cu")
		(net "DRV_ACT_8")
	)
	(segment
		(start 378.968 -210.979258)
		(end 378.750322 -210.76158)
		(width 0.254)
		(layer "F.Cu")
		(net "DRV_ACT_8")
	)
	(segment
		(start 378.750322 -181.130194)
		(end 378.750322 -208.6229)
		(width 0.254)
		(layer "F.Cu")
		(net "DRV_ACT_8")
	)
	(via
		(at 378.750322 -208.6229)
		(size 0.6604)
		(drill 0.3302)
		(layers "F.Cu" "B.Cu")
		(net "DRV_ACT_8")
	)
	(segment
		(start 347.345 -213.614)
		(end 347.345 -210.841336)
		(width 0.254)
		(layer "F.Cu")
		(net "DRV_ACT_7")
	)
	(segment
		(start 347.200474 -181.130194)
		(end 347.200474 -208.494376)
		(width 0.254)
		(layer "F.Cu")
		(net "DRV_ACT_7")
	)
	(segment
		(start 347.200474 -210.69681)
		(end 347.200474 -208.494376)
		(width 0.254)
		(layer "F.Cu")
		(net "DRV_ACT_7")
	)
	(segment
		(start 347.345 -210.841336)
		(end 347.200474 -210.69681)
		(width 0.254)
		(layer "F.Cu")
		(net "DRV_ACT_7")
	)
	(via
		(at 347.200474 -208.494376)
		(size 0.6604)
		(drill 0.3302)
		(layers "F.Cu" "B.Cu")
		(net "DRV_ACT_7")
	)
	(segment
		(start 315.650372 -212.202776)
		(end 315.650372 -208.494884)
		(width 0.254)
		(layer "F.Cu")
		(net "DRV_ACT_6")
	)
	(segment
		(start 315.839348 -212.391752)
		(end 315.650372 -212.202776)
		(width 0.254)
		(layer "F.Cu")
		(net "DRV_ACT_6")
	)
	(segment
		(start 315.650372 -181.130194)
		(end 315.650372 -208.494884)
		(width 0.254)
		(layer "F.Cu")
		(net "DRV_ACT_6")
	)
	(via
		(at 315.650372 -208.494884)
		(size 0.6604)
		(drill 0.3302)
		(layers "F.Cu" "B.Cu")
		(net "DRV_ACT_6")
	)
	(segment
		(start 174.117 -193.929)
		(end 174.117 -196.502274)
		(width 0.254)
		(layer "F.Cu")
		(net "DRV_ACT_5")
	)
	(segment
		(start 176.050448 -191.995552)
		(end 174.117 -193.929)
		(width 0.254)
		(layer "F.Cu")
		(net "DRV_ACT_5")
	)
	(segment
		(start 174.117 -196.502274)
		(end 174.117 -213.487)
		(width 0.254)
		(layer "F.Cu")
		(net "DRV_ACT_5")
	)
	(segment
		(start 176.050448 -181.130194)
		(end 176.050448 -191.995552)
		(width 0.254)
		(layer "F.Cu")
		(net "DRV_ACT_5")
	)
	(via
		(at 174.117 -196.502274)
		(size 0.6604)
		(drill 0.3302)
		(layers "F.Cu" "B.Cu")
		(net "DRV_ACT_5")
	)
	(segment
		(start 144.500346 -181.130194)
		(end 144.526 -181.155848)
		(width 0.254)
		(layer "F.Cu")
		(net "DRV_ACT_4")
	)
	(segment
		(start 144.526 -206.949294)
		(end 144.526 -213.487)
		(width 0.254)
		(layer "F.Cu")
		(net "DRV_ACT_4")
	)
	(segment
		(start 144.526 -181.155848)
		(end 144.526 -206.949294)
		(width 0.254)
		(layer "F.Cu")
		(net "DRV_ACT_4")
	)
	(via
		(at 144.526 -206.949294)
		(size 0.6604)
		(drill 0.3302)
		(layers "F.Cu" "B.Cu")
		(net "DRV_ACT_4")
	)
	(segment
		(start 112.950498 -205.146148)
		(end 112.950498 -181.130194)
		(width 0.254)
		(layer "F.Cu")
		(net "DRV_ACT_3")
	)
	(segment
		(start 113.03 -213.487)
		(end 113.03 -212.5218)
		(width 0.254)
		(layer "F.Cu")
		(net "DRV_ACT_3")
	)
	(segment
		(start 112.950498 -212.442298)
		(end 112.950498 -205.146148)
		(width 0.254)
		(layer "F.Cu")
		(net "DRV_ACT_3")
	)
	(segment
		(start 113.03 -212.5218)
		(end 112.950498 -212.442298)
		(width 0.254)
		(layer "F.Cu")
		(net "DRV_ACT_3")
	)
	(via
		(at 112.950498 -205.146148)
		(size 0.6604)
		(drill 0.3302)
		(layers "F.Cu" "B.Cu")
		(net "DRV_ACT_3")
	)
	(segment
		(start 81.400396 -181.130194)
		(end 81.400396 -206.417926)
		(width 0.254)
		(layer "F.Cu")
		(net "DRV_ACT_2")
	)
	(segment
		(start 81.407 -209.519266)
		(end 81.400396 -209.512662)
		(width 0.254)
		(layer "F.Cu")
		(net "DRV_ACT_2")
	)
	(segment
		(start 81.407 -213.487)
		(end 81.407 -209.519266)
		(width 0.254)
		(layer "F.Cu")
		(net "DRV_ACT_2")
	)
	(segment
		(start 81.400396 -209.512662)
		(end 81.400396 -206.417926)
		(width 0.254)
		(layer "F.Cu")
		(net "DRV_ACT_2")
	)
	(via
		(at 81.400396 -206.417926)
		(size 0.6604)
		(drill 0.3302)
		(layers "F.Cu" "B.Cu")
		(net "DRV_ACT_2")
	)
	(segment
		(start 21.480018 -98.639884)
		(end 21.480018 -93.818964)
		(width 0.254)
		(layer "F.Cu")
		(net "DRV_ACT_12")
	)
	(segment
		(start 21.480018 -93.818964)
		(end 18.300446 -90.639392)
		(width 0.254)
		(layer "F.Cu")
		(net "DRV_ACT_12")
	)
	(segment
		(start 18.300446 -90.639392)
		(end 18.300446 -88.815418)
		(width 0.254)
		(layer "F.Cu")
		(net "DRV_ACT_12")
	)
	(segment
		(start 18.300446 -66.13017)
		(end 18.300446 -88.815418)
		(width 0.254)
		(layer "F.Cu")
		(net "DRV_ACT_12")
	)
	(via
		(at 18.300446 -88.815418)
		(size 0.6604)
		(drill 0.3302)
		(layers "F.Cu" "B.Cu")
		(net "DRV_ACT_12")
	)
	(segment
		(start 473.400374 -181.130194)
		(end 473.400374 -208.655158)
		(width 0.254)
		(layer "F.Cu")
		(net "DRV_ACT_11")
	)
	(segment
		(start 473.583 -213.487)
		(end 473.583 -211.20354)
		(width 0.254)
		(layer "F.Cu")
		(net "DRV_ACT_11")
	)
	(segment
		(start 473.583 -211.20354)
		(end 473.400374 -211.020914)
		(width 0.254)
		(layer "F.Cu")
		(net "DRV_ACT_11")
	)
	(segment
		(start 473.400374 -211.020914)
		(end 473.400374 -208.655158)
		(width 0.254)
		(layer "F.Cu")
		(net "DRV_ACT_11")
	)
	(via
		(at 473.400374 -208.655158)
		(size 0.6604)
		(drill 0.3302)
		(layers "F.Cu" "B.Cu")
		(net "DRV_ACT_11")
	)
	(segment
		(start 441.850272 -212.132926)
		(end 441.850272 -210.443318)
		(width 0.254)
		(layer "F.Cu")
		(net "DRV_ACT_10")
	)
	(segment
		(start 441.850272 -210.443318)
		(end 441.850272 -181.130194)
		(width 0.254)
		(layer "F.Cu")
		(net "DRV_ACT_10")
	)
	(segment
		(start 441.96 -213.487)
		(end 441.96 -212.242654)
		(width 0.254)
		(layer "F.Cu")
		(net "DRV_ACT_10")
	)
	(segment
		(start 441.96 -212.242654)
		(end 441.850272 -212.132926)
		(width 0.254)
		(layer "F.Cu")
		(net "DRV_ACT_10")
	)
	(via
		(at 441.850272 -210.443318)
		(size 0.6604)
		(drill 0.3302)
		(layers "F.Cu" "B.Cu")
		(net "DRV_ACT_10")
	)
	(segment
		(start 49.850294 -181.130194)
		(end 49.850294 -205.194662)
		(width 0.254)
		(layer "F.Cu")
		(net "DRV_ACT_1")
	)
	(segment
		(start 49.850294 -213.420706)
		(end 49.850294 -205.194662)
		(width 0.254)
		(layer "F.Cu")
		(net "DRV_ACT_1")
	)
	(segment
		(start 49.784 -213.487)
		(end 49.850294 -213.420706)
		(width 0.254)
		(layer "F.Cu")
		(net "DRV_ACT_1")
	)
	(via
		(at 49.850294 -205.194662)
		(size 0.6604)
		(drill 0.3302)
		(layers "F.Cu" "B.Cu")
		(net "DRV_ACT_1")
	)
	(segment
		(start 18.300446 -181.130194)
		(end 18.300446 -205.25867)
		(width 0.254)
		(layer "F.Cu")
		(net "DRV_ACT_0")
	)
	(segment
		(start 18.669 -208.99247)
		(end 18.300446 -208.623916)
		(width 0.254)
		(layer "F.Cu")
		(net "DRV_ACT_0")
	)
	(segment
		(start 18.300446 -208.623916)
		(end 18.300446 -205.25867)
		(width 0.254)
		(layer "F.Cu")
		(net "DRV_ACT_0")
	)
	(segment
		(start 18.669 -213.487)
		(end 18.669 -208.99247)
		(width 0.254)
		(layer "F.Cu")
		(net "DRV_ACT_0")
	)
	(via
		(at 18.300446 -205.25867)
		(size 0.6604)
		(drill 0.3302)
		(layers "F.Cu" "B.Cu")
		(net "DRV_ACT_0")
	)
	(segment
		(start 430.403 -243.1415)
		(end 431.292 -243.1415)
		(width 0.17145)
		(layer "F.Cu")
		(net "DRIVE_B_9_PWR")
	)
	(segment
		(start 269.792196 -256.861818)
		(end 270.727678 -257.7973)
		(width 0.17145)
		(layer "F.Cu")
		(net "DRIVE_B_9_PWR")
	)
	(segment
		(start 434.213 -228.7778)
		(end 322.555616 -228.7778)
		(width 0.17145)
		(layer "F.Cu")
		(net "DRIVE_B_9_PWR")
	)
	(segment
		(start 269.715742 -256.861818)
		(end 269.792196 -256.861818)
		(width 0.17145)
		(layer "F.Cu")
		(net "DRIVE_B_9_PWR")
	)
	(segment
		(start 240.954052 -234.8484)
		(end 247.702324 -234.8484)
		(width 0.17145)
		(layer "F.Cu")
		(net "DRIVE_B_9_PWR")
	)
	(segment
		(start 270.727678 -257.873754)
		(end 275.136356 -262.282432)
		(width 0.17145)
		(layer "F.Cu")
		(net "DRIVE_B_9_PWR")
	)
	(segment
		(start 304.803302 -262.282432)
		(end 294.719756 -262.282432)
		(width 0.17145)
		(layer "F.Cu")
		(net "DRIVE_B_9_PWR")
	)
	(segment
		(start 234.000802 -226.593146)
		(end 235.174282 -227.766626)
		(width 0.17145)
		(layer "F.Cu")
		(net "DRIVE_B_9_PWR")
	)
	(segment
		(start 235.174282 -227.766626)
		(end 235.174282 -229.06863)
		(width 0.17145)
		(layer "F.Cu")
		(net "DRIVE_B_9_PWR")
	)
	(segment
		(start 226.57308 -223.612456)
		(end 226.57308 -224.9043)
		(width 0.17145)
		(layer "F.Cu")
		(net "DRIVE_B_9_PWR")
	)
	(segment
		(start 313.24042 -238.092996)
		(end 313.24042 -253.845314)
		(width 0.17145)
		(layer "F.Cu")
		(net "DRIVE_B_9_PWR")
	)
	(segment
		(start 235.174282 -229.06863)
		(end 240.954052 -234.8484)
		(width 0.17145)
		(layer "F.Cu")
		(net "DRIVE_B_9_PWR")
	)
	(segment
		(start 322.555616 -228.7778)
		(end 313.24042 -238.092996)
		(width 0.17145)
		(layer "F.Cu")
		(net "DRIVE_B_9_PWR")
	)
	(segment
		(start 226.57308 -224.9043)
		(end 228.261926 -226.593146)
		(width 0.17145)
		(layer "F.Cu")
		(net "DRIVE_B_9_PWR")
	)
	(segment
		(start 270.727678 -257.7973)
		(end 270.727678 -257.873754)
		(width 0.17145)
		(layer "F.Cu")
		(net "DRIVE_B_9_PWR")
	)
	(segment
		(start 228.261926 -226.593146)
		(end 234.000802 -226.593146)
		(width 0.17145)
		(layer "F.Cu")
		(net "DRIVE_B_9_PWR")
	)
	(segment
		(start 247.702324 -234.8484)
		(end 269.715742 -256.861818)
		(width 0.17145)
		(layer "F.Cu")
		(net "DRIVE_B_9_PWR")
	)
	(segment
		(start 313.24042 -253.845314)
		(end 304.803302 -262.282432)
		(width 0.17145)
		(layer "F.Cu")
		(net "DRIVE_B_9_PWR")
	)
	(segment
		(start 275.136356 -262.282432)
		(end 294.719756 -262.282432)
		(width 0.17145)
		(layer "F.Cu")
		(net "DRIVE_B_9_PWR")
	)
	(via
		(at 431.292 -243.1415)
		(size 0.5588)
		(drill 0.3048)
		(layers "F.Cu" "B.Cu")
		(net "DRIVE_B_9_PWR")
	)
	(via
		(at 294.719756 -262.282432)
		(size 0.6604)
		(drill 0.3302)
		(layers "F.Cu" "B.Cu")
		(net "DRIVE_B_9_PWR")
	)
	(via
		(at 434.213 -228.7778)
		(size 0.5588)
		(drill 0.3048)
		(layers "F.Cu" "B.Cu")
		(net "DRIVE_B_9_PWR")
	)
	(segment
		(start 431.292 -243.1415)
		(end 431.67808 -242.75542)
		(width 0.14605)
		(layer "In2.Cu")
		(net "DRIVE_B_9_PWR")
	)
	(segment
		(start 431.67808 -231.31272)
		(end 434.213 -228.7778)
		(width 0.14605)
		(layer "In2.Cu")
		(net "DRIVE_B_9_PWR")
	)
	(segment
		(start 431.67808 -242.75542)
		(end 431.67808 -231.31272)
		(width 0.14605)
		(layer "In2.Cu")
		(net "DRIVE_B_9_PWR")
	)
	(segment
		(start 232.055416 -247.74525)
		(end 232.055416 -250.154694)
		(width 0.17145)
		(layer "F.Cu")
		(net "DRIVE_B_9_INS")
	)
	(segment
		(start 226.223576 -241.91341)
		(end 232.055416 -247.74525)
		(width 0.17145)
		(layer "F.Cu")
		(net "DRIVE_B_9_INS")
	)
	(segment
		(start 407.895044 -234.498134)
		(end 408.402536 -235.005626)
		(width 0.17145)
		(layer "F.Cu")
		(net "DRIVE_B_9_INS")
	)
	(segment
		(start 412.8516 -260.5786)
		(end 412.8516 -257.5052)
		(width 0.17145)
		(layer "F.Cu")
		(net "DRIVE_B_9_INS")
	)
	(segment
		(start 204.905102 -241.91341)
		(end 226.223576 -241.91341)
		(width 0.17145)
		(layer "F.Cu")
		(net "DRIVE_B_9_INS")
	)
	(segment
		(start 337.103212 -232.7021)
		(end 338.899246 -234.498134)
		(width 0.17145)
		(layer "F.Cu")
		(net "DRIVE_B_9_INS")
	)
	(segment
		(start 203.6953 -238.84382)
		(end 203.6953 -240.703608)
		(width 0.17145)
		(layer "F.Cu")
		(net "DRIVE_B_9_INS")
	)
	(segment
		(start 316.558168 -254.892302)
		(end 316.558168 -239.140238)
		(width 0.17145)
		(layer "F.Cu")
		(net "DRIVE_B_9_INS")
	)
	(segment
		(start 412.8516 -257.5052)
		(end 410.972 -255.6256)
		(width 0.17145)
		(layer "F.Cu")
		(net "DRIVE_B_9_INS")
	)
	(segment
		(start 316.558168 -239.140238)
		(end 322.996306 -232.7021)
		(width 0.17145)
		(layer "F.Cu")
		(net "DRIVE_B_9_INS")
	)
	(segment
		(start 203.6953 -240.703608)
		(end 204.905102 -241.91341)
		(width 0.17145)
		(layer "F.Cu")
		(net "DRIVE_B_9_INS")
	)
	(segment
		(start 338.899246 -234.498134)
		(end 407.895044 -234.498134)
		(width 0.17145)
		(layer "F.Cu")
		(net "DRIVE_B_9_INS")
	)
	(segment
		(start 247.526302 -265.62558)
		(end 305.82489 -265.62558)
		(width 0.17145)
		(layer "F.Cu")
		(net "DRIVE_B_9_INS")
	)
	(segment
		(start 322.996306 -232.7021)
		(end 337.103212 -232.7021)
		(width 0.17145)
		(layer "F.Cu")
		(net "DRIVE_B_9_INS")
	)
	(segment
		(start 410.972 -237.57509)
		(end 408.402536 -235.005626)
		(width 0.17145)
		(layer "F.Cu")
		(net "DRIVE_B_9_INS")
	)
	(segment
		(start 305.82489 -265.62558)
		(end 316.558168 -254.892302)
		(width 0.17145)
		(layer "F.Cu")
		(net "DRIVE_B_9_INS")
	)
	(segment
		(start 232.055416 -250.154694)
		(end 247.526302 -265.62558)
		(width 0.17145)
		(layer "F.Cu")
		(net "DRIVE_B_9_INS")
	)
	(segment
		(start 410.972 -255.6256)
		(end 410.972 -237.57509)
		(width 0.17145)
		(layer "F.Cu")
		(net "DRIVE_B_9_INS")
	)
	(via
		(at 408.402536 -235.005626)
		(size 0.6604)
		(drill 0.3302)
		(layers "F.Cu" "B.Cu")
		(net "DRIVE_B_9_INS")
	)
	(segment
		(start 400.936206 -217.173048)
		(end 402.330158 -218.567)
		(width 0.17145)
		(layer "F.Cu")
		(net "DRIVE_B_9_FLT_LED")
	)
	(segment
		(start 317.60541 -165.259258)
		(end 322.234052 -169.8879)
		(width 0.17145)
		(layer "F.Cu")
		(net "DRIVE_B_9_FLT_LED")
	)
	(segment
		(start 223.573086 -211.12734)
		(end 227.171504 -207.528922)
		(width 0.17145)
		(layer "F.Cu")
		(net "DRIVE_B_9_FLT_LED")
	)
	(segment
		(start 227.171504 -179.383182)
		(end 241.295428 -165.259258)
		(width 0.17145)
		(layer "F.Cu")
		(net "DRIVE_B_9_FLT_LED")
	)
	(segment
		(start 407.005028 -218.567)
		(end 407.538428 -218.0336)
		(width 0.17145)
		(layer "F.Cu")
		(net "DRIVE_B_9_FLT_LED")
	)
	(segment
		(start 400.936206 -209.197194)
		(end 400.936206 -217.173048)
		(width 0.17145)
		(layer "F.Cu")
		(net "DRIVE_B_9_FLT_LED")
	)
	(segment
		(start 217.162634 -217.537792)
		(end 223.573086 -211.12734)
		(width 0.17145)
		(layer "F.Cu")
		(net "DRIVE_B_9_FLT_LED")
	)
	(segment
		(start 217.162634 -218.054174)
		(end 217.162634 -217.537792)
		(width 0.17145)
		(layer "F.Cu")
		(net "DRIVE_B_9_FLT_LED")
	)
	(segment
		(start 227.171504 -207.528922)
		(end 227.171504 -179.383182)
		(width 0.17145)
		(layer "F.Cu")
		(net "DRIVE_B_9_FLT_LED")
	)
	(segment
		(start 397.749014 -169.8879)
		(end 402.1582 -174.297086)
		(width 0.17145)
		(layer "F.Cu")
		(net "DRIVE_B_9_FLT_LED")
	)
	(segment
		(start 322.234052 -169.8879)
		(end 397.749014 -169.8879)
		(width 0.17145)
		(layer "F.Cu")
		(net "DRIVE_B_9_FLT_LED")
	)
	(segment
		(start 217.41638 -218.30792)
		(end 217.162634 -218.054174)
		(width 0.17145)
		(layer "F.Cu")
		(net "DRIVE_B_9_FLT_LED")
	)
	(segment
		(start 402.330158 -218.567)
		(end 407.005028 -218.567)
		(width 0.17145)
		(layer "F.Cu")
		(net "DRIVE_B_9_FLT_LED")
	)
	(segment
		(start 241.295428 -165.259258)
		(end 317.60541 -165.259258)
		(width 0.17145)
		(layer "F.Cu")
		(net "DRIVE_B_9_FLT_LED")
	)
	(segment
		(start 402.1582 -174.297086)
		(end 402.1582 -207.9752)
		(width 0.17145)
		(layer "F.Cu")
		(net "DRIVE_B_9_FLT_LED")
	)
	(segment
		(start 407.538428 -217.413586)
		(end 407.538428 -215.7095)
		(width 0.17145)
		(layer "F.Cu")
		(net "DRIVE_B_9_FLT_LED")
	)
	(segment
		(start 402.1582 -207.9752)
		(end 400.936206 -209.197194)
		(width 0.17145)
		(layer "F.Cu")
		(net "DRIVE_B_9_FLT_LED")
	)
	(segment
		(start 218.5924 -218.30792)
		(end 217.41638 -218.30792)
		(width 0.17145)
		(layer "F.Cu")
		(net "DRIVE_B_9_FLT_LED")
	)
	(segment
		(start 407.538428 -218.0336)
		(end 407.538428 -217.413586)
		(width 0.17145)
		(layer "F.Cu")
		(net "DRIVE_B_9_FLT_LED")
	)
	(via
		(at 223.573086 -211.12734)
		(size 0.6604)
		(drill 0.3302)
		(layers "F.Cu" "B.Cu")
		(net "DRIVE_B_9_FLT_LED")
	)
	(segment
		(start 403.796246 -209.969354)
		(end 404.2156 -209.55)
		(width 0.17145)
		(layer "F.Cu")
		(net "DRIVE_B_9_ACT")
	)
	(segment
		(start 282.472638 -201.530458)
		(end 298.474638 -201.530458)
		(width 0.17145)
		(layer "F.Cu")
		(net "DRIVE_B_9_ACT")
	)
	(segment
		(start 403.796246 -212.390228)
		(end 403.796246 -210.6549)
		(width 0.17145)
		(layer "F.Cu")
		(net "DRIVE_B_9_ACT")
	)
	(segment
		(start 403.796246 -210.6549)
		(end 403.796246 -209.969354)
		(width 0.17145)
		(layer "F.Cu")
		(net "DRIVE_B_9_ACT")
	)
	(segment
		(start 403.796246 -213.876128)
		(end 403.796246 -212.390228)
		(width 0.17145)
		(layer "F.Cu")
		(net "DRIVE_B_9_ACT")
	)
	(segment
		(start 298.474638 -201.530458)
		(end 299.64126 -202.69708)
		(width 0.17145)
		(layer "F.Cu")
		(net "DRIVE_B_9_ACT")
	)
	(segment
		(start 281.836622 -200.894442)
		(end 282.472638 -201.530458)
		(width 0.17145)
		(layer "F.Cu")
		(net "DRIVE_B_9_ACT")
	)
	(via
		(at 403.796246 -210.6549)
		(size 0.6604)
		(drill 0.3302)
		(layers "F.Cu" "B.Cu")
		(net "DRIVE_B_9_ACT")
	)
	(via
		(at 299.64126 -202.69708)
		(size 0.5588)
		(drill 0.3048)
		(layers "F.Cu" "B.Cu")
		(net "DRIVE_B_9_ACT")
	)
	(via
		(at 404.2156 -209.55)
		(size 0.5588)
		(drill 0.3048)
		(layers "F.Cu" "B.Cu")
		(net "DRIVE_B_9_ACT")
	)
	(segment
		(start 344.578432 -208.779872)
		(end 338.49564 -202.69708)
		(width 0.14605)
		(layer "In2.Cu")
		(net "DRIVE_B_9_ACT")
	)
	(segment
		(start 372.314724 -208.779872)
		(end 344.578432 -208.779872)
		(width 0.14605)
		(layer "In2.Cu")
		(net "DRIVE_B_9_ACT")
	)
	(segment
		(start 338.49564 -202.69708)
		(end 299.64126 -202.69708)
		(width 0.14605)
		(layer "In2.Cu")
		(net "DRIVE_B_9_ACT")
	)
	(segment
		(start 404.2156 -209.55)
		(end 373.084852 -209.55)
		(width 0.14605)
		(layer "In2.Cu")
		(net "DRIVE_B_9_ACT")
	)
	(segment
		(start 373.084852 -209.55)
		(end 372.314724 -208.779872)
		(width 0.14605)
		(layer "In2.Cu")
		(net "DRIVE_B_9_ACT")
	)
	(segment
		(start 225.92284 -223.612456)
		(end 225.92284 -225.15068)
		(width 0.17145)
		(layer "F.Cu")
		(net "DRIVE_B_8_PWR")
	)
	(segment
		(start 269.57909 -257.376168)
		(end 270.213328 -258.010406)
		(width 0.17145)
		(layer "F.Cu")
		(net "DRIVE_B_8_PWR")
	)
	(segment
		(start 269.502636 -257.376168)
		(end 269.57909 -257.376168)
		(width 0.17145)
		(layer "F.Cu")
		(net "DRIVE_B_8_PWR")
	)
	(segment
		(start 270.213328 -258.010406)
		(end 270.213328 -258.08686)
		(width 0.17145)
		(layer "F.Cu")
		(net "DRIVE_B_8_PWR")
	)
	(segment
		(start 313.755024 -254.058166)
		(end 304.959004 -262.854186)
		(width 0.17145)
		(layer "F.Cu")
		(net "DRIVE_B_8_PWR")
	)
	(segment
		(start 247.508268 -235.3818)
		(end 269.502636 -257.376168)
		(width 0.17145)
		(layer "F.Cu")
		(net "DRIVE_B_8_PWR")
	)
	(segment
		(start 225.92284 -225.15068)
		(end 227.879656 -227.107496)
		(width 0.17145)
		(layer "F.Cu")
		(net "DRIVE_B_8_PWR")
	)
	(segment
		(start 234.659932 -227.979732)
		(end 234.659932 -229.281736)
		(width 0.17145)
		(layer "F.Cu")
		(net "DRIVE_B_8_PWR")
	)
	(segment
		(start 313.755024 -238.305848)
		(end 313.755024 -254.058166)
		(width 0.17145)
		(layer "F.Cu")
		(net "DRIVE_B_8_PWR")
	)
	(segment
		(start 304.959004 -262.854186)
		(end 285.711392 -262.854186)
		(width 0.17145)
		(layer "F.Cu")
		(net "DRIVE_B_8_PWR")
	)
	(segment
		(start 322.724272 -229.3366)
		(end 313.755024 -238.305848)
		(width 0.17145)
		(layer "F.Cu")
		(net "DRIVE_B_8_PWR")
	)
	(segment
		(start 398.907 -243.1415)
		(end 399.796 -243.1415)
		(width 0.17145)
		(layer "F.Cu")
		(net "DRIVE_B_8_PWR")
	)
	(segment
		(start 227.879656 -227.107496)
		(end 233.787696 -227.107496)
		(width 0.17145)
		(layer "F.Cu")
		(net "DRIVE_B_8_PWR")
	)
	(segment
		(start 274.980654 -262.854186)
		(end 285.711392 -262.854186)
		(width 0.17145)
		(layer "F.Cu")
		(net "DRIVE_B_8_PWR")
	)
	(segment
		(start 399.5166 -229.3366)
		(end 322.724272 -229.3366)
		(width 0.17145)
		(layer "F.Cu")
		(net "DRIVE_B_8_PWR")
	)
	(segment
		(start 240.759996 -235.3818)
		(end 247.508268 -235.3818)
		(width 0.17145)
		(layer "F.Cu")
		(net "DRIVE_B_8_PWR")
	)
	(segment
		(start 270.213328 -258.08686)
		(end 274.980654 -262.854186)
		(width 0.17145)
		(layer "F.Cu")
		(net "DRIVE_B_8_PWR")
	)
	(segment
		(start 233.787696 -227.107496)
		(end 234.659932 -227.979732)
		(width 0.17145)
		(layer "F.Cu")
		(net "DRIVE_B_8_PWR")
	)
	(segment
		(start 234.659932 -229.281736)
		(end 240.759996 -235.3818)
		(width 0.17145)
		(layer "F.Cu")
		(net "DRIVE_B_8_PWR")
	)
	(via
		(at 399.796 -243.1415)
		(size 0.5588)
		(drill 0.3048)
		(layers "F.Cu" "B.Cu")
		(net "DRIVE_B_8_PWR")
	)
	(via
		(at 399.5166 -229.3366)
		(size 0.5588)
		(drill 0.3048)
		(layers "F.Cu" "B.Cu")
		(net "DRIVE_B_8_PWR")
	)
	(via
		(at 285.711392 -262.854186)
		(size 0.6604)
		(drill 0.3302)
		(layers "F.Cu" "B.Cu")
		(net "DRIVE_B_8_PWR")
	)
	(segment
		(start 399.5166 -229.3366)
		(end 399.5166 -242.8621)
		(width 0.14605)
		(layer "In2.Cu")
		(net "DRIVE_B_8_PWR")
	)
	(segment
		(start 399.5166 -242.8621)
		(end 399.796 -243.1415)
		(width 0.14605)
		(layer "In2.Cu")
		(net "DRIVE_B_8_PWR")
	)
	(segment
		(start 247.313196 -266.13993)
		(end 306.037996 -266.13993)
		(width 0.17145)
		(layer "F.Cu")
		(net "DRIVE_B_8_INS")
	)
	(segment
		(start 338.68614 -235.012484)
		(end 372.642638 -235.012484)
		(width 0.17145)
		(layer "F.Cu")
		(net "DRIVE_B_8_INS")
	)
	(segment
		(start 204.499718 -242.42776)
		(end 226.01047 -242.42776)
		(width 0.17145)
		(layer "F.Cu")
		(net "DRIVE_B_8_INS")
	)
	(segment
		(start 231.540812 -250.367546)
		(end 247.313196 -266.13993)
		(width 0.17145)
		(layer "F.Cu")
		(net "DRIVE_B_8_INS")
	)
	(segment
		(start 372.642638 -235.012484)
		(end 374.052084 -236.42193)
		(width 0.17145)
		(layer "F.Cu")
		(net "DRIVE_B_8_INS")
	)
	(segment
		(start 203.04506 -240.973102)
		(end 204.499718 -242.42776)
		(width 0.17145)
		(layer "F.Cu")
		(net "DRIVE_B_8_INS")
	)
	(segment
		(start 231.540812 -247.958102)
		(end 231.540812 -250.367546)
		(width 0.17145)
		(layer "F.Cu")
		(net "DRIVE_B_8_INS")
	)
	(segment
		(start 317.072518 -239.353344)
		(end 323.209412 -233.21645)
		(width 0.17145)
		(layer "F.Cu")
		(net "DRIVE_B_8_INS")
	)
	(segment
		(start 336.890106 -233.21645)
		(end 338.68614 -235.012484)
		(width 0.17145)
		(layer "F.Cu")
		(net "DRIVE_B_8_INS")
	)
	(segment
		(start 203.04506 -238.84382)
		(end 203.04506 -240.973102)
		(width 0.17145)
		(layer "F.Cu")
		(net "DRIVE_B_8_INS")
	)
	(segment
		(start 226.01047 -242.42776)
		(end 231.540812 -247.958102)
		(width 0.17145)
		(layer "F.Cu")
		(net "DRIVE_B_8_INS")
	)
	(segment
		(start 381.1778 -255.825244)
		(end 377.041156 -251.6886)
		(width 0.17145)
		(layer "F.Cu")
		(net "DRIVE_B_8_INS")
	)
	(segment
		(start 381.1778 -260.5532)
		(end 381.1778 -255.825244)
		(width 0.17145)
		(layer "F.Cu")
		(net "DRIVE_B_8_INS")
	)
	(segment
		(start 317.072518 -255.105408)
		(end 317.072518 -239.353344)
		(width 0.17145)
		(layer "F.Cu")
		(net "DRIVE_B_8_INS")
	)
	(segment
		(start 323.209412 -233.21645)
		(end 336.890106 -233.21645)
		(width 0.17145)
		(layer "F.Cu")
		(net "DRIVE_B_8_INS")
	)
	(segment
		(start 377.041156 -251.6886)
		(end 377.041156 -239.411002)
		(width 0.17145)
		(layer "F.Cu")
		(net "DRIVE_B_8_INS")
	)
	(segment
		(start 306.037996 -266.13993)
		(end 317.072518 -255.105408)
		(width 0.17145)
		(layer "F.Cu")
		(net "DRIVE_B_8_INS")
	)
	(segment
		(start 377.041156 -239.411002)
		(end 374.052084 -236.42193)
		(width 0.17145)
		(layer "F.Cu")
		(net "DRIVE_B_8_INS")
	)
	(via
		(at 374.052084 -236.42193)
		(size 0.6604)
		(drill 0.3302)
		(layers "F.Cu" "B.Cu")
		(net "DRIVE_B_8_INS")
	)
	(segment
		(start 368.046 -216.535)
		(end 370.111782 -218.600782)
		(width 0.17145)
		(layer "F.Cu")
		(net "DRIVE_B_8_FLT_LED")
	)
	(segment
		(start 218.5924 -216.911936)
		(end 224.141538 -211.362798)
		(width 0.17145)
		(layer "F.Cu")
		(net "DRIVE_B_8_FLT_LED")
	)
	(segment
		(start 218.5924 -217.65768)
		(end 218.5924 -216.911936)
		(width 0.17145)
		(layer "F.Cu")
		(net "DRIVE_B_8_FLT_LED")
	)
	(segment
		(start 375.988326 -217.96375)
		(end 375.988326 -217.413586)
		(width 0.17145)
		(layer "F.Cu")
		(net "DRIVE_B_8_FLT_LED")
	)
	(segment
		(start 375.351294 -218.600782)
		(end 375.988326 -217.96375)
		(width 0.17145)
		(layer "F.Cu")
		(net "DRIVE_B_8_FLT_LED")
	)
	(segment
		(start 375.988326 -217.413586)
		(end 375.988326 -215.7095)
		(width 0.17145)
		(layer "F.Cu")
		(net "DRIVE_B_8_FLT_LED")
	)
	(segment
		(start 368.046 -175.5648)
		(end 368.046 -216.535)
		(width 0.17145)
		(layer "F.Cu")
		(net "DRIVE_B_8_FLT_LED")
	)
	(segment
		(start 225.192082 -210.2358)
		(end 225.5774 -210.2358)
		(width 0.17145)
		(layer "F.Cu")
		(net "DRIVE_B_8_FLT_LED")
	)
	(segment
		(start 362.88345 -170.40225)
		(end 368.046 -175.5648)
		(width 0.17145)
		(layer "F.Cu")
		(net "DRIVE_B_8_FLT_LED")
	)
	(segment
		(start 370.111782 -218.600782)
		(end 375.351294 -218.600782)
		(width 0.17145)
		(layer "F.Cu")
		(net "DRIVE_B_8_FLT_LED")
	)
	(segment
		(start 225.5774 -210.2358)
		(end 227.685854 -208.127346)
		(width 0.17145)
		(layer "F.Cu")
		(net "DRIVE_B_8_FLT_LED")
	)
	(segment
		(start 321.590162 -170.40225)
		(end 362.88345 -170.40225)
		(width 0.17145)
		(layer "F.Cu")
		(net "DRIVE_B_8_FLT_LED")
	)
	(segment
		(start 316.96152 -165.773608)
		(end 321.590162 -170.40225)
		(width 0.17145)
		(layer "F.Cu")
		(net "DRIVE_B_8_FLT_LED")
	)
	(segment
		(start 241.508534 -165.773608)
		(end 316.96152 -165.773608)
		(width 0.17145)
		(layer "F.Cu")
		(net "DRIVE_B_8_FLT_LED")
	)
	(segment
		(start 227.685854 -179.596288)
		(end 241.508534 -165.773608)
		(width 0.17145)
		(layer "F.Cu")
		(net "DRIVE_B_8_FLT_LED")
	)
	(segment
		(start 224.141538 -211.286344)
		(end 225.192082 -210.2358)
		(width 0.17145)
		(layer "F.Cu")
		(net "DRIVE_B_8_FLT_LED")
	)
	(segment
		(start 224.141538 -211.362798)
		(end 224.141538 -211.286344)
		(width 0.17145)
		(layer "F.Cu")
		(net "DRIVE_B_8_FLT_LED")
	)
	(segment
		(start 227.685854 -208.127346)
		(end 227.685854 -179.596288)
		(width 0.17145)
		(layer "F.Cu")
		(net "DRIVE_B_8_FLT_LED")
	)
	(via
		(at 225.5774 -210.2358)
		(size 0.6604)
		(drill 0.3302)
		(layers "F.Cu" "B.Cu")
		(net "DRIVE_B_8_FLT_LED")
	)
	(segment
		(start 283.23667 -200.894442)
		(end 283.87421 -200.256902)
		(width 0.17145)
		(layer "F.Cu")
		(net "DRIVE_B_8_ACT")
	)
	(segment
		(start 372.246144 -210.6549)
		(end 372.246144 -209.55)
		(width 0.17145)
		(layer "F.Cu")
		(net "DRIVE_B_8_ACT")
	)
	(segment
		(start 372.246144 -212.390228)
		(end 372.246144 -210.6549)
		(width 0.17145)
		(layer "F.Cu")
		(net "DRIVE_B_8_ACT")
	)
	(segment
		(start 299.225462 -200.256902)
		(end 299.85208 -200.88352)
		(width 0.17145)
		(layer "F.Cu")
		(net "DRIVE_B_8_ACT")
	)
	(segment
		(start 283.87421 -200.256902)
		(end 299.225462 -200.256902)
		(width 0.17145)
		(layer "F.Cu")
		(net "DRIVE_B_8_ACT")
	)
	(segment
		(start 372.246144 -213.876128)
		(end 372.246144 -212.390228)
		(width 0.17145)
		(layer "F.Cu")
		(net "DRIVE_B_8_ACT")
	)
	(via
		(at 372.246144 -210.6549)
		(size 0.6604)
		(drill 0.3302)
		(layers "F.Cu" "B.Cu")
		(net "DRIVE_B_8_ACT")
	)
	(via
		(at 372.246144 -209.55)
		(size 0.5588)
		(drill 0.3048)
		(layers "F.Cu" "B.Cu")
		(net "DRIVE_B_8_ACT")
	)
	(via
		(at 299.85208 -200.88352)
		(size 0.5588)
		(drill 0.3048)
		(layers "F.Cu" "B.Cu")
		(net "DRIVE_B_8_ACT")
	)
	(segment
		(start 298.9326 -202.702414)
		(end 298.9326 -201.7776)
		(width 0.14605)
		(layer "In2.Cu")
		(net "DRIVE_B_8_ACT")
	)
	(segment
		(start 372.246144 -209.55)
		(end 344.7288 -209.55)
		(width 0.14605)
		(layer "In2.Cu")
		(net "DRIVE_B_8_ACT")
	)
	(segment
		(start 299.6946 -203.454)
		(end 299.442632 -203.202032)
		(width 0.14605)
		(layer "In2.Cu")
		(net "DRIVE_B_8_ACT")
	)
	(segment
		(start 338.6328 -203.454)
		(end 299.6946 -203.454)
		(width 0.14605)
		(layer "In2.Cu")
		(net "DRIVE_B_8_ACT")
	)
	(segment
		(start 344.7288 -209.55)
		(end 338.6328 -203.454)
		(width 0.14605)
		(layer "In2.Cu")
		(net "DRIVE_B_8_ACT")
	)
	(segment
		(start 299.82668 -200.88352)
		(end 299.85208 -200.88352)
		(width 0.14605)
		(layer "In2.Cu")
		(net "DRIVE_B_8_ACT")
	)
	(segment
		(start 299.442632 -203.202032)
		(end 299.432218 -203.202032)
		(width 0.14605)
		(layer "In2.Cu")
		(net "DRIVE_B_8_ACT")
	)
	(segment
		(start 298.9326 -201.7776)
		(end 299.82668 -200.88352)
		(width 0.14605)
		(layer "In2.Cu")
		(net "DRIVE_B_8_ACT")
	)
	(segment
		(start 299.432218 -203.202032)
		(end 298.9326 -202.702414)
		(width 0.14605)
		(layer "In2.Cu")
		(net "DRIVE_B_8_ACT")
	)
	(segment
		(start 240.58499 -235.93425)
		(end 247.333262 -235.93425)
		(width 0.17145)
		(layer "F.Cu")
		(net "DRIVE_B_7_PWR")
	)
	(segment
		(start 322.92798 -229.860348)
		(end 314.315856 -238.472472)
		(width 0.17145)
		(layer "F.Cu")
		(net "DRIVE_B_7_PWR")
	)
	(segment
		(start 269.698978 -258.299966)
		(end 274.91309 -263.514078)
		(width 0.17145)
		(layer "F.Cu")
		(net "DRIVE_B_7_PWR")
	)
	(segment
		(start 305.026568 -263.514078)
		(end 277.706328 -263.514078)
		(width 0.17145)
		(layer "F.Cu")
		(net "DRIVE_B_7_PWR")
	)
	(segment
		(start 274.91309 -263.514078)
		(end 277.706328 -263.514078)
		(width 0.17145)
		(layer "F.Cu")
		(net "DRIVE_B_7_PWR")
	)
	(segment
		(start 247.333262 -235.93425)
		(end 269.28953 -257.890518)
		(width 0.17145)
		(layer "F.Cu")
		(net "DRIVE_B_7_PWR")
	)
	(segment
		(start 269.28953 -257.890518)
		(end 269.365984 -257.890518)
		(width 0.17145)
		(layer "F.Cu")
		(net "DRIVE_B_7_PWR")
	)
	(segment
		(start 367.7539 -243.1415)
		(end 368.3254 -243.713)
		(width 0.17145)
		(layer "F.Cu")
		(net "DRIVE_B_7_PWR")
	)
	(segment
		(start 366.773968 -229.860348)
		(end 322.92798 -229.860348)
		(width 0.17145)
		(layer "F.Cu")
		(net "DRIVE_B_7_PWR")
	)
	(segment
		(start 314.315856 -254.22479)
		(end 305.026568 -263.514078)
		(width 0.17145)
		(layer "F.Cu")
		(net "DRIVE_B_7_PWR")
	)
	(segment
		(start 226.57308 -229.251256)
		(end 226.57308 -227.98532)
		(width 0.17145)
		(layer "F.Cu")
		(net "DRIVE_B_7_PWR")
	)
	(segment
		(start 226.936554 -227.621846)
		(end 233.57459 -227.621846)
		(width 0.17145)
		(layer "F.Cu")
		(net "DRIVE_B_7_PWR")
	)
	(segment
		(start 314.315856 -238.472472)
		(end 314.315856 -254.22479)
		(width 0.17145)
		(layer "F.Cu")
		(net "DRIVE_B_7_PWR")
	)
	(segment
		(start 234.145582 -228.192838)
		(end 234.145582 -229.494842)
		(width 0.17145)
		(layer "F.Cu")
		(net "DRIVE_B_7_PWR")
	)
	(segment
		(start 233.57459 -227.621846)
		(end 234.145582 -228.192838)
		(width 0.17145)
		(layer "F.Cu")
		(net "DRIVE_B_7_PWR")
	)
	(segment
		(start 226.57308 -227.98532)
		(end 226.936554 -227.621846)
		(width 0.17145)
		(layer "F.Cu")
		(net "DRIVE_B_7_PWR")
	)
	(segment
		(start 269.698978 -258.223512)
		(end 269.698978 -258.299966)
		(width 0.17145)
		(layer "F.Cu")
		(net "DRIVE_B_7_PWR")
	)
	(segment
		(start 367.284 -243.1415)
		(end 367.7539 -243.1415)
		(width 0.17145)
		(layer "F.Cu")
		(net "DRIVE_B_7_PWR")
	)
	(segment
		(start 234.145582 -229.494842)
		(end 240.58499 -235.93425)
		(width 0.17145)
		(layer "F.Cu")
		(net "DRIVE_B_7_PWR")
	)
	(segment
		(start 269.365984 -257.890518)
		(end 269.698978 -258.223512)
		(width 0.17145)
		(layer "F.Cu")
		(net "DRIVE_B_7_PWR")
	)
	(via
		(at 366.773968 -229.860348)
		(size 0.5588)
		(drill 0.3048)
		(layers "F.Cu" "B.Cu")
		(net "DRIVE_B_7_PWR")
	)
	(via
		(at 368.3254 -243.713)
		(size 0.5588)
		(drill 0.3048)
		(layers "F.Cu" "B.Cu")
		(net "DRIVE_B_7_PWR")
	)
	(via
		(at 277.706328 -263.514078)
		(size 0.6604)
		(drill 0.3302)
		(layers "F.Cu" "B.Cu")
		(net "DRIVE_B_7_PWR")
	)
	(segment
		(start 368.3254 -243.713)
		(end 368.3254 -243.2939)
		(width 0.14605)
		(layer "In2.Cu")
		(net "DRIVE_B_7_PWR")
	)
	(segment
		(start 368.3254 -243.2939)
		(end 366.773968 -241.742468)
		(width 0.14605)
		(layer "In2.Cu")
		(net "DRIVE_B_7_PWR")
	)
	(segment
		(start 366.773968 -241.742468)
		(end 366.773968 -229.860348)
		(width 0.14605)
		(layer "In2.Cu")
		(net "DRIVE_B_7_PWR")
	)
	(segment
		(start 323.422518 -233.7308)
		(end 336.677 -233.7308)
		(width 0.17145)
		(layer "F.Cu")
		(net "DRIVE_B_7_INS")
	)
	(segment
		(start 203.6953 -244.48262)
		(end 203.6953 -243.638578)
		(width 0.17145)
		(layer "F.Cu")
		(net "DRIVE_B_7_INS")
	)
	(segment
		(start 336.677 -233.7308)
		(end 338.473034 -235.526834)
		(width 0.17145)
		(layer "F.Cu")
		(net "DRIVE_B_7_INS")
	)
	(segment
		(start 231.026462 -250.580652)
		(end 247.10009 -266.65428)
		(width 0.17145)
		(layer "F.Cu")
		(net "DRIVE_B_7_INS")
	)
	(segment
		(start 247.10009 -266.65428)
		(end 306.251102 -266.65428)
		(width 0.17145)
		(layer "F.Cu")
		(net "DRIVE_B_7_INS")
	)
	(segment
		(start 225.848672 -242.993418)
		(end 231.026462 -248.171208)
		(width 0.17145)
		(layer "F.Cu")
		(net "DRIVE_B_7_INS")
	)
	(segment
		(start 349.7326 -260.5532)
		(end 349.7326 -249.606562)
		(width 0.17145)
		(layer "F.Cu")
		(net "DRIVE_B_7_INS")
	)
	(segment
		(start 345.236038 -240.732818)
		(end 340.442296 -235.939076)
		(width 0.17145)
		(layer "F.Cu")
		(net "DRIVE_B_7_INS")
	)
	(segment
		(start 204.34046 -242.993418)
		(end 225.848672 -242.993418)
		(width 0.17145)
		(layer "F.Cu")
		(net "DRIVE_B_7_INS")
	)
	(segment
		(start 306.251102 -266.65428)
		(end 317.587122 -255.31826)
		(width 0.17145)
		(layer "F.Cu")
		(net "DRIVE_B_7_INS")
	)
	(segment
		(start 338.473034 -235.526834)
		(end 340.030054 -235.526834)
		(width 0.17145)
		(layer "F.Cu")
		(net "DRIVE_B_7_INS")
	)
	(segment
		(start 345.236038 -245.11)
		(end 345.236038 -240.732818)
		(width 0.17145)
		(layer "F.Cu")
		(net "DRIVE_B_7_INS")
	)
	(segment
		(start 203.6953 -243.638578)
		(end 204.34046 -242.993418)
		(width 0.17145)
		(layer "F.Cu")
		(net "DRIVE_B_7_INS")
	)
	(segment
		(start 317.587122 -239.566196)
		(end 323.422518 -233.7308)
		(width 0.17145)
		(layer "F.Cu")
		(net "DRIVE_B_7_INS")
	)
	(segment
		(start 340.030054 -235.526834)
		(end 340.442296 -235.939076)
		(width 0.17145)
		(layer "F.Cu")
		(net "DRIVE_B_7_INS")
	)
	(segment
		(start 317.587122 -255.31826)
		(end 317.587122 -239.566196)
		(width 0.17145)
		(layer "F.Cu")
		(net "DRIVE_B_7_INS")
	)
	(segment
		(start 349.7326 -249.606562)
		(end 345.236038 -245.11)
		(width 0.17145)
		(layer "F.Cu")
		(net "DRIVE_B_7_INS")
	)
	(segment
		(start 231.026462 -248.171208)
		(end 231.026462 -250.580652)
		(width 0.17145)
		(layer "F.Cu")
		(net "DRIVE_B_7_INS")
	)
	(via
		(at 340.442296 -235.939076)
		(size 0.6604)
		(drill 0.3302)
		(layers "F.Cu" "B.Cu")
		(net "DRIVE_B_7_INS")
	)
	(segment
		(start 336.5754 -171.1452)
		(end 338.001864 -172.571664)
		(width 0.17145)
		(layer "F.Cu")
		(net "DRIVE_B_7_FLT_LED")
	)
	(segment
		(start 321.605656 -171.1452)
		(end 336.5754 -171.1452)
		(width 0.17145)
		(layer "F.Cu")
		(net "DRIVE_B_7_FLT_LED")
	)
	(segment
		(start 344.438478 -218.480132)
		(end 344.438478 -217.413586)
		(width 0.17145)
		(layer "F.Cu")
		(net "DRIVE_B_7_FLT_LED")
	)
	(segment
		(start 344.438478 -217.413586)
		(end 344.438478 -215.7095)
		(width 0.17145)
		(layer "F.Cu")
		(net "DRIVE_B_7_FLT_LED")
	)
	(segment
		(start 228.200204 -179.809394)
		(end 241.72164 -166.287958)
		(width 0.17145)
		(layer "F.Cu")
		(net "DRIVE_B_7_FLT_LED")
	)
	(segment
		(start 344.206068 -218.712542)
		(end 344.438478 -218.480132)
		(width 0.17145)
		(layer "F.Cu")
		(net "DRIVE_B_7_FLT_LED")
	)
	(segment
		(start 212.9536 -218.30792)
		(end 210.33232 -218.30792)
		(width 0.17145)
		(layer "F.Cu")
		(net "DRIVE_B_7_FLT_LED")
	)
	(segment
		(start 228.200204 -209.002122)
		(end 228.200204 -179.809394)
		(width 0.17145)
		(layer "F.Cu")
		(net "DRIVE_B_7_FLT_LED")
	)
	(segment
		(start 223.952308 -213.070186)
		(end 224.13214 -213.070186)
		(width 0.17145)
		(layer "F.Cu")
		(net "DRIVE_B_7_FLT_LED")
	)
	(segment
		(start 225.130868 -212.071458)
		(end 228.200204 -209.002122)
		(width 0.17145)
		(layer "F.Cu")
		(net "DRIVE_B_7_FLT_LED")
	)
	(segment
		(start 241.72164 -166.287958)
		(end 316.748414 -166.287958)
		(width 0.17145)
		(layer "F.Cu")
		(net "DRIVE_B_7_FLT_LED")
	)
	(segment
		(start 338.001864 -172.571664)
		(end 338.001864 -217.555064)
		(width 0.17145)
		(layer "F.Cu")
		(net "DRIVE_B_7_FLT_LED")
	)
	(segment
		(start 224.13214 -213.070186)
		(end 225.130868 -212.071458)
		(width 0.17145)
		(layer "F.Cu")
		(net "DRIVE_B_7_FLT_LED")
	)
	(segment
		(start 339.159342 -218.712542)
		(end 344.206068 -218.712542)
		(width 0.17145)
		(layer "F.Cu")
		(net "DRIVE_B_7_FLT_LED")
	)
	(segment
		(start 316.748414 -166.287958)
		(end 321.605656 -171.1452)
		(width 0.17145)
		(layer "F.Cu")
		(net "DRIVE_B_7_FLT_LED")
	)
	(segment
		(start 338.001864 -217.555064)
		(end 339.159342 -218.712542)
		(width 0.17145)
		(layer "F.Cu")
		(net "DRIVE_B_7_FLT_LED")
	)
	(segment
		(start 210.33232 -218.30792)
		(end 209.804 -217.7796)
		(width 0.17145)
		(layer "F.Cu")
		(net "DRIVE_B_7_FLT_LED")
	)
	(via
		(at 209.804 -217.7796)
		(size 0.5588)
		(drill 0.3048)
		(layers "F.Cu" "B.Cu")
		(net "DRIVE_B_7_FLT_LED")
	)
	(via
		(at 223.952308 -213.070186)
		(size 0.5588)
		(drill 0.3048)
		(layers "F.Cu" "B.Cu")
		(net "DRIVE_B_7_FLT_LED")
	)
	(via
		(at 225.130868 -212.071458)
		(size 0.6604)
		(drill 0.3302)
		(layers "F.Cu" "B.Cu")
		(net "DRIVE_B_7_FLT_LED")
	)
	(segment
		(start 219.399612 -213.070186)
		(end 218.621102 -213.848696)
		(width 0.14605)
		(layer "In5.Cu")
		(net "DRIVE_B_7_FLT_LED")
	)
	(segment
		(start 218.621102 -213.848696)
		(end 213.734904 -213.848696)
		(width 0.14605)
		(layer "In5.Cu")
		(net "DRIVE_B_7_FLT_LED")
	)
	(segment
		(start 213.734904 -213.848696)
		(end 209.804 -217.7796)
		(width 0.14605)
		(layer "In5.Cu")
		(net "DRIVE_B_7_FLT_LED")
	)
	(segment
		(start 223.952308 -213.070186)
		(end 219.399612 -213.070186)
		(width 0.14605)
		(layer "In5.Cu")
		(net "DRIVE_B_7_FLT_LED")
	)
	(segment
		(start 340.696296 -210.6549)
		(end 340.696296 -209.55)
		(width 0.17145)
		(layer "F.Cu")
		(net "DRIVE_B_7_ACT")
	)
	(segment
		(start 340.696296 -213.876128)
		(end 340.696296 -212.390228)
		(width 0.17145)
		(layer "F.Cu")
		(net "DRIVE_B_7_ACT")
	)
	(segment
		(start 340.696296 -212.390228)
		(end 340.696296 -210.6549)
		(width 0.17145)
		(layer "F.Cu")
		(net "DRIVE_B_7_ACT")
	)
	(segment
		(start 283.80944 -203.66736)
		(end 298.24172 -203.66736)
		(width 0.17145)
		(layer "F.Cu")
		(net "DRIVE_B_7_ACT")
	)
	(segment
		(start 282.83662 -202.69454)
		(end 283.80944 -203.66736)
		(width 0.17145)
		(layer "F.Cu")
		(net "DRIVE_B_7_ACT")
	)
	(segment
		(start 298.24172 -203.66736)
		(end 299.0342 -204.45984)
		(width 0.17145)
		(layer "F.Cu")
		(net "DRIVE_B_7_ACT")
	)
	(via
		(at 340.696296 -209.55)
		(size 0.5588)
		(drill 0.3048)
		(layers "F.Cu" "B.Cu")
		(net "DRIVE_B_7_ACT")
	)
	(via
		(at 340.696296 -210.6549)
		(size 0.6604)
		(drill 0.3302)
		(layers "F.Cu" "B.Cu")
		(net "DRIVE_B_7_ACT")
	)
	(via
		(at 299.0342 -204.45984)
		(size 0.5588)
		(drill 0.3048)
		(layers "F.Cu" "B.Cu")
		(net "DRIVE_B_7_ACT")
	)
	(segment
		(start 335.606136 -204.45984)
		(end 299.0342 -204.45984)
		(width 0.14605)
		(layer "In2.Cu")
		(net "DRIVE_B_7_ACT")
	)
	(segment
		(start 340.696296 -209.55)
		(end 335.606136 -204.45984)
		(width 0.14605)
		(layer "In2.Cu")
		(net "DRIVE_B_7_ACT")
	)
	(segment
		(start 274.754086 -264.08253)
		(end 269.130526 -258.45897)
		(width 0.17145)
		(layer "F.Cu")
		(net "DRIVE_B_6_PWR")
	)
	(segment
		(start 240.371884 -236.4486)
		(end 247.120156 -236.4486)
		(width 0.17145)
		(layer "F.Cu")
		(net "DRIVE_B_6_PWR")
	)
	(segment
		(start 227.22332 -229.251256)
		(end 227.22332 -228.35108)
		(width 0.17145)
		(layer "F.Cu")
		(net "DRIVE_B_6_PWR")
	)
	(segment
		(start 227.22332 -228.35108)
		(end 227.438204 -228.136196)
		(width 0.17145)
		(layer "F.Cu")
		(net "DRIVE_B_6_PWR")
	)
	(segment
		(start 323.137784 -230.378)
		(end 314.830206 -238.685578)
		(width 0.17145)
		(layer "F.Cu")
		(net "DRIVE_B_6_PWR")
	)
	(segment
		(start 247.120156 -236.4486)
		(end 269.130526 -258.45897)
		(width 0.17145)
		(layer "F.Cu")
		(net "DRIVE_B_6_PWR")
	)
	(segment
		(start 336.677 -230.378)
		(end 323.137784 -230.378)
		(width 0.17145)
		(layer "F.Cu")
		(net "DRIVE_B_6_PWR")
	)
	(segment
		(start 314.830206 -238.685578)
		(end 314.830206 -254.437896)
		(width 0.17145)
		(layer "F.Cu")
		(net "DRIVE_B_6_PWR")
	)
	(segment
		(start 314.830206 -254.437896)
		(end 305.185572 -264.08253)
		(width 0.17145)
		(layer "F.Cu")
		(net "DRIVE_B_6_PWR")
	)
	(segment
		(start 233.361484 -228.136196)
		(end 233.631232 -228.405944)
		(width 0.17145)
		(layer "F.Cu")
		(net "DRIVE_B_6_PWR")
	)
	(segment
		(start 335.788 -243.1415)
		(end 336.677 -243.1415)
		(width 0.17145)
		(layer "F.Cu")
		(net "DRIVE_B_6_PWR")
	)
	(segment
		(start 233.631232 -229.707948)
		(end 240.371884 -236.4486)
		(width 0.17145)
		(layer "F.Cu")
		(net "DRIVE_B_6_PWR")
	)
	(segment
		(start 227.438204 -228.136196)
		(end 233.361484 -228.136196)
		(width 0.17145)
		(layer "F.Cu")
		(net "DRIVE_B_6_PWR")
	)
	(segment
		(start 305.185572 -264.08253)
		(end 274.754086 -264.08253)
		(width 0.17145)
		(layer "F.Cu")
		(net "DRIVE_B_6_PWR")
	)
	(segment
		(start 233.631232 -228.405944)
		(end 233.631232 -229.707948)
		(width 0.17145)
		(layer "F.Cu")
		(net "DRIVE_B_6_PWR")
	)
	(via
		(at 269.130526 -258.45897)
		(size 0.6604)
		(drill 0.3302)
		(layers "F.Cu" "B.Cu")
		(net "DRIVE_B_6_PWR")
	)
	(via
		(at 336.677 -230.378)
		(size 0.5588)
		(drill 0.3048)
		(layers "F.Cu" "B.Cu")
		(net "DRIVE_B_6_PWR")
	)
	(via
		(at 336.677 -243.1415)
		(size 0.5588)
		(drill 0.3048)
		(layers "F.Cu" "B.Cu")
		(net "DRIVE_B_6_PWR")
	)
	(segment
		(start 336.677 -243.1415)
		(end 336.677 -230.378)
		(width 0.14605)
		(layer "In2.Cu")
		(net "DRIVE_B_6_PWR")
	)
	(segment
		(start 204.34554 -243.715794)
		(end 204.553566 -243.507768)
		(width 0.17145)
		(layer "F.Cu")
		(net "DRIVE_B_6_INS")
	)
	(segment
		(start 314.325508 -267.461492)
		(end 310.803036 -267.461492)
		(width 0.17145)
		(layer "F.Cu")
		(net "DRIVE_B_6_INS")
	)
	(segment
		(start 239.736376 -267.461492)
		(end 310.803036 -267.461492)
		(width 0.17145)
		(layer "F.Cu")
		(net "DRIVE_B_6_INS")
	)
	(segment
		(start 204.34554 -244.48262)
		(end 204.34554 -243.715794)
		(width 0.17145)
		(layer "F.Cu")
		(net "DRIVE_B_6_INS")
	)
	(segment
		(start 230.512112 -248.384314)
		(end 230.512112 -258.237228)
		(width 0.17145)
		(layer "F.Cu")
		(net "DRIVE_B_6_INS")
	)
	(segment
		(start 318.2112 -263.5758)
		(end 314.325508 -267.461492)
		(width 0.17145)
		(layer "F.Cu")
		(net "DRIVE_B_6_INS")
	)
	(segment
		(start 204.553566 -243.507768)
		(end 225.635566 -243.507768)
		(width 0.17145)
		(layer "F.Cu")
		(net "DRIVE_B_6_INS")
	)
	(segment
		(start 230.512112 -258.237228)
		(end 239.736376 -267.461492)
		(width 0.17145)
		(layer "F.Cu")
		(net "DRIVE_B_6_INS")
	)
	(segment
		(start 225.635566 -243.507768)
		(end 230.512112 -248.384314)
		(width 0.17145)
		(layer "F.Cu")
		(net "DRIVE_B_6_INS")
	)
	(via
		(at 310.803036 -267.461492)
		(size 0.6604)
		(drill 0.3302)
		(layers "F.Cu" "B.Cu")
		(net "DRIVE_B_6_INS")
	)
	(segment
		(start 313.715908 -166.802308)
		(end 319.8114 -172.8978)
		(width 0.17145)
		(layer "F.Cu")
		(net "DRIVE_B_6_FLT_LED")
	)
	(segment
		(start 228.714554 -180.0225)
		(end 241.934746 -166.802308)
		(width 0.17145)
		(layer "F.Cu")
		(net "DRIVE_B_6_FLT_LED")
	)
	(segment
		(start 212.9536 -218.95816)
		(end 209.7786 -218.95816)
		(width 0.17145)
		(layer "F.Cu")
		(net "DRIVE_B_6_FLT_LED")
	)
	(segment
		(start 224.422462 -213.90737)
		(end 227.655882 -210.67395)
		(width 0.17145)
		(layer "F.Cu")
		(net "DRIVE_B_6_FLT_LED")
	)
	(segment
		(start 241.934746 -166.802308)
		(end 313.715908 -166.802308)
		(width 0.17145)
		(layer "F.Cu")
		(net "DRIVE_B_6_FLT_LED")
	)
	(segment
		(start 222.722948 -213.90737)
		(end 224.422462 -213.90737)
		(width 0.17145)
		(layer "F.Cu")
		(net "DRIVE_B_6_FLT_LED")
	)
	(segment
		(start 228.714554 -209.615278)
		(end 228.714554 -180.0225)
		(width 0.17145)
		(layer "F.Cu")
		(net "DRIVE_B_6_FLT_LED")
	)
	(segment
		(start 312.888376 -217.413586)
		(end 312.888376 -215.7095)
		(width 0.17145)
		(layer "F.Cu")
		(net "DRIVE_B_6_FLT_LED")
	)
	(segment
		(start 318.958214 -217.413586)
		(end 312.888376 -217.413586)
		(width 0.17145)
		(layer "F.Cu")
		(net "DRIVE_B_6_FLT_LED")
	)
	(segment
		(start 319.8114 -216.5604)
		(end 318.958214 -217.413586)
		(width 0.17145)
		(layer "F.Cu")
		(net "DRIVE_B_6_FLT_LED")
	)
	(segment
		(start 227.655882 -210.67395)
		(end 228.714554 -209.615278)
		(width 0.17145)
		(layer "F.Cu")
		(net "DRIVE_B_6_FLT_LED")
	)
	(segment
		(start 319.8114 -172.8978)
		(end 319.8114 -216.5604)
		(width 0.17145)
		(layer "F.Cu")
		(net "DRIVE_B_6_FLT_LED")
	)
	(via
		(at 222.722948 -213.90737)
		(size 0.5588)
		(drill 0.3048)
		(layers "F.Cu" "B.Cu")
		(net "DRIVE_B_6_FLT_LED")
	)
	(via
		(at 227.655882 -210.67395)
		(size 0.6604)
		(drill 0.3302)
		(layers "F.Cu" "B.Cu")
		(net "DRIVE_B_6_FLT_LED")
	)
	(via
		(at 209.7786 -218.95816)
		(size 0.5588)
		(drill 0.3048)
		(layers "F.Cu" "B.Cu")
		(net "DRIVE_B_6_FLT_LED")
	)
	(segment
		(start 210.3374 -218.39936)
		(end 209.7786 -218.95816)
		(width 0.14605)
		(layer "In5.Cu")
		(net "DRIVE_B_6_FLT_LED")
	)
	(segment
		(start 222.722948 -213.90737)
		(end 222.343472 -214.286846)
		(width 0.14605)
		(layer "In5.Cu")
		(net "DRIVE_B_6_FLT_LED")
	)
	(segment
		(start 213.916514 -214.286846)
		(end 210.3374 -217.86596)
		(width 0.14605)
		(layer "In5.Cu")
		(net "DRIVE_B_6_FLT_LED")
	)
	(segment
		(start 222.343472 -214.286846)
		(end 213.916514 -214.286846)
		(width 0.14605)
		(layer "In5.Cu")
		(net "DRIVE_B_6_FLT_LED")
	)
	(segment
		(start 210.3374 -217.86596)
		(end 210.3374 -218.39936)
		(width 0.14605)
		(layer "In5.Cu")
		(net "DRIVE_B_6_FLT_LED")
	)
	(segment
		(start 297.611292 -202.057508)
		(end 297.61561 -202.05319)
		(width 0.17145)
		(layer "F.Cu")
		(net "DRIVE_B_6_ACT")
	)
	(segment
		(start 284.236668 -202.69454)
		(end 284.8737 -202.057508)
		(width 0.17145)
		(layer "F.Cu")
		(net "DRIVE_B_6_ACT")
	)
	(segment
		(start 309.146194 -213.876128)
		(end 309.146194 -212.390228)
		(width 0.17145)
		(layer "F.Cu")
		(net "DRIVE_B_6_ACT")
	)
	(segment
		(start 309.146194 -212.390228)
		(end 309.146194 -210.6549)
		(width 0.17145)
		(layer "F.Cu")
		(net "DRIVE_B_6_ACT")
	)
	(segment
		(start 309.146194 -210.6549)
		(end 309.146194 -209.55)
		(width 0.17145)
		(layer "F.Cu")
		(net "DRIVE_B_6_ACT")
	)
	(segment
		(start 297.61561 -202.05319)
		(end 298.19346 -202.63104)
		(width 0.17145)
		(layer "F.Cu")
		(net "DRIVE_B_6_ACT")
	)
	(segment
		(start 284.8737 -202.057508)
		(end 297.611292 -202.057508)
		(width 0.17145)
		(layer "F.Cu")
		(net "DRIVE_B_6_ACT")
	)
	(via
		(at 298.19346 -202.63104)
		(size 0.5588)
		(drill 0.3048)
		(layers "F.Cu" "B.Cu")
		(net "DRIVE_B_6_ACT")
	)
	(via
		(at 309.146194 -209.55)
		(size 0.5588)
		(drill 0.3048)
		(layers "F.Cu" "B.Cu")
		(net "DRIVE_B_6_ACT")
	)
	(via
		(at 309.146194 -210.6549)
		(size 0.6604)
		(drill 0.3302)
		(layers "F.Cu" "B.Cu")
		(net "DRIVE_B_6_ACT")
	)
	(segment
		(start 298.19346 -208.35366)
		(end 298.19346 -202.63104)
		(width 0.14605)
		(layer "In2.Cu")
		(net "DRIVE_B_6_ACT")
	)
	(segment
		(start 299.3898 -209.55)
		(end 298.19346 -208.35366)
		(width 0.14605)
		(layer "In2.Cu")
		(net "DRIVE_B_6_ACT")
	)
	(segment
		(start 309.146194 -209.55)
		(end 299.3898 -209.55)
		(width 0.14605)
		(layer "In2.Cu")
		(net "DRIVE_B_6_ACT")
	)
	(segment
		(start 227.87356 -229.96144)
		(end 227.87356 -229.251256)
		(width 0.17145)
		(layer "F.Cu")
		(net "DRIVE_B_5_PWR")
	)
	(segment
		(start 226.1362 -231.6988)
		(end 227.87356 -229.96144)
		(width 0.17145)
		(layer "F.Cu")
		(net "DRIVE_B_5_PWR")
	)
	(segment
		(start 186.410854 -228.86924)
		(end 186.40933 -228.867716)
		(width 0.17145)
		(layer "F.Cu")
		(net "DRIVE_B_5_PWR")
	)
	(segment
		(start 217.51544 -228.86924)
		(end 220.345 -231.6988)
		(width 0.17145)
		(layer "F.Cu")
		(net "DRIVE_B_5_PWR")
	)
	(segment
		(start 220.345 -231.6988)
		(end 226.1362 -231.6988)
		(width 0.17145)
		(layer "F.Cu")
		(net "DRIVE_B_5_PWR")
	)
	(segment
		(start 181.4576 -246.2784)
		(end 180.5813 -246.2784)
		(width 0.17145)
		(layer "F.Cu")
		(net "DRIVE_B_5_PWR")
	)
	(segment
		(start 188.052456 -228.86924)
		(end 186.410854 -228.86924)
		(width 0.17145)
		(layer "F.Cu")
		(net "DRIVE_B_5_PWR")
	)
	(segment
		(start 188.052456 -228.86924)
		(end 217.51544 -228.86924)
		(width 0.17145)
		(layer "F.Cu")
		(net "DRIVE_B_5_PWR")
	)
	(via
		(at 186.40933 -228.867716)
		(size 0.5588)
		(drill 0.3048)
		(layers "F.Cu" "B.Cu")
		(net "DRIVE_B_5_PWR")
	)
	(via
		(at 188.052456 -228.86924)
		(size 0.6604)
		(drill 0.3302)
		(layers "F.Cu" "B.Cu")
		(net "DRIVE_B_5_PWR")
	)
	(via
		(at 181.4576 -246.2784)
		(size 0.5588)
		(drill 0.3048)
		(layers "F.Cu" "B.Cu")
		(net "DRIVE_B_5_PWR")
	)
	(segment
		(start 184.694322 -228.867716)
		(end 182.270654 -231.291384)
		(width 0.14605)
		(layer "In2.Cu")
		(net "DRIVE_B_5_PWR")
	)
	(segment
		(start 186.40933 -228.867716)
		(end 184.694322 -228.867716)
		(width 0.14605)
		(layer "In2.Cu")
		(net "DRIVE_B_5_PWR")
	)
	(segment
		(start 182.270654 -245.465346)
		(end 181.4576 -246.2784)
		(width 0.14605)
		(layer "In2.Cu")
		(net "DRIVE_B_5_PWR")
	)
	(segment
		(start 182.270654 -231.291384)
		(end 182.270654 -245.465346)
		(width 0.14605)
		(layer "In2.Cu")
		(net "DRIVE_B_5_PWR")
	)
	(segment
		(start 204.99578 -244.48262)
		(end 204.99578 -245.863872)
		(width 0.17145)
		(layer "F.Cu")
		(net "DRIVE_B_5_INS")
	)
	(segment
		(start 204.99578 -245.863872)
		(end 203.781406 -247.078246)
		(width 0.17145)
		(layer "F.Cu")
		(net "DRIVE_B_5_INS")
	)
	(segment
		(start 203.781406 -263.271508)
		(end 202.558142 -264.494772)
		(width 0.17145)
		(layer "F.Cu")
		(net "DRIVE_B_5_INS")
	)
	(segment
		(start 191.135 -267.843)
		(end 199.209914 -267.843)
		(width 0.17145)
		(layer "F.Cu")
		(net "DRIVE_B_5_INS")
	)
	(segment
		(start 199.209914 -267.843)
		(end 202.558142 -264.494772)
		(width 0.17145)
		(layer "F.Cu")
		(net "DRIVE_B_5_INS")
	)
	(segment
		(start 203.781406 -247.078246)
		(end 203.781406 -263.271508)
		(width 0.17145)
		(layer "F.Cu")
		(net "DRIVE_B_5_INS")
	)
	(via
		(at 202.558142 -264.494772)
		(size 0.6604)
		(drill 0.3302)
		(layers "F.Cu" "B.Cu")
		(net "DRIVE_B_5_INS")
	)
	(segment
		(start 172.147484 -219.291154)
		(end 171.65066 -218.79433)
		(width 0.17145)
		(layer "F.Cu")
		(net "DRIVE_B_5_FLT_LED")
	)
	(segment
		(start 171.29125 -218.43492)
		(end 171.29125 -217.337386)
		(width 0.17145)
		(layer "F.Cu")
		(net "DRIVE_B_5_FLT_LED")
	)
	(segment
		(start 212.9536 -219.6084)
		(end 198.6534 -219.6084)
		(width 0.17145)
		(layer "F.Cu")
		(net "DRIVE_B_5_FLT_LED")
	)
	(segment
		(start 198.336154 -219.291154)
		(end 172.147484 -219.291154)
		(width 0.17145)
		(layer "F.Cu")
		(net "DRIVE_B_5_FLT_LED")
	)
	(segment
		(start 198.6534 -219.6084)
		(end 198.336154 -219.291154)
		(width 0.17145)
		(layer "F.Cu")
		(net "DRIVE_B_5_FLT_LED")
	)
	(segment
		(start 171.29125 -217.337386)
		(end 171.29125 -215.6587)
		(width 0.17145)
		(layer "F.Cu")
		(net "DRIVE_B_5_FLT_LED")
	)
	(segment
		(start 171.65066 -218.79433)
		(end 171.29125 -218.43492)
		(width 0.17145)
		(layer "F.Cu")
		(net "DRIVE_B_5_FLT_LED")
	)
	(via
		(at 171.65066 -218.79433)
		(size 0.6604)
		(drill 0.3302)
		(layers "F.Cu" "B.Cu")
		(net "DRIVE_B_5_FLT_LED")
	)
	(segment
		(start 167.549068 -213.799928)
		(end 167.549068 -212.314028)
		(width 0.17145)
		(layer "F.Cu")
		(net "DRIVE_B_5_ACT")
	)
	(segment
		(start 234.921044 -203.860146)
		(end 234.295696 -204.485494)
		(width 0.17145)
		(layer "F.Cu")
		(net "DRIVE_B_5_ACT")
	)
	(segment
		(start 281.199844 -203.857606)
		(end 276.098 -203.857606)
		(width 0.17145)
		(layer "F.Cu")
		(net "DRIVE_B_5_ACT")
	)
	(segment
		(start 232.497376 -205.223618)
		(end 231.646476 -205.223618)
		(width 0.17145)
		(layer "F.Cu")
		(net "DRIVE_B_5_ACT")
	)
	(segment
		(start 231.132634 -206.612998)
		(end 230.684832 -207.0608)
		(width 0.17145)
		(layer "F.Cu")
		(net "DRIVE_B_5_ACT")
	)
	(segment
		(start 281.836622 -204.494384)
		(end 281.199844 -203.857606)
		(width 0.17145)
		(layer "F.Cu")
		(net "DRIVE_B_5_ACT")
	)
	(segment
		(start 231.646476 -205.223618)
		(end 231.132634 -205.73746)
		(width 0.17145)
		(layer "F.Cu")
		(net "DRIVE_B_5_ACT")
	)
	(segment
		(start 229.729538 -207.0608)
		(end 229.25024 -206.581502)
		(width 0.17145)
		(layer "F.Cu")
		(net "DRIVE_B_5_ACT")
	)
	(segment
		(start 233.2355 -204.485494)
		(end 232.497376 -205.223618)
		(width 0.17145)
		(layer "F.Cu")
		(net "DRIVE_B_5_ACT")
	)
	(segment
		(start 234.295696 -204.485494)
		(end 233.2355 -204.485494)
		(width 0.17145)
		(layer "F.Cu")
		(net "DRIVE_B_5_ACT")
	)
	(segment
		(start 276.098 -203.857606)
		(end 276.035262 -203.920344)
		(width 0.17145)
		(layer "F.Cu")
		(net "DRIVE_B_5_ACT")
	)
	(segment
		(start 231.132634 -205.73746)
		(end 231.132634 -206.612998)
		(width 0.17145)
		(layer "F.Cu")
		(net "DRIVE_B_5_ACT")
	)
	(segment
		(start 230.684832 -207.0608)
		(end 229.729538 -207.0608)
		(width 0.17145)
		(layer "F.Cu")
		(net "DRIVE_B_5_ACT")
	)
	(segment
		(start 242.67795 -202.923902)
		(end 241.741706 -203.860146)
		(width 0.17145)
		(layer "F.Cu")
		(net "DRIVE_B_5_ACT")
	)
	(segment
		(start 255.576832 -202.923902)
		(end 242.67795 -202.923902)
		(width 0.17145)
		(layer "F.Cu")
		(net "DRIVE_B_5_ACT")
	)
	(segment
		(start 167.549068 -212.314028)
		(end 167.549068 -210.5787)
		(width 0.17145)
		(layer "F.Cu")
		(net "DRIVE_B_5_ACT")
	)
	(segment
		(start 256.573274 -203.920344)
		(end 255.576832 -202.923902)
		(width 0.17145)
		(layer "F.Cu")
		(net "DRIVE_B_5_ACT")
	)
	(segment
		(start 276.035262 -203.920344)
		(end 256.573274 -203.920344)
		(width 0.17145)
		(layer "F.Cu")
		(net "DRIVE_B_5_ACT")
	)
	(segment
		(start 167.549068 -210.5787)
		(end 167.549068 -209.4738)
		(width 0.17145)
		(layer "F.Cu")
		(net "DRIVE_B_5_ACT")
	)
	(segment
		(start 241.741706 -203.860146)
		(end 234.921044 -203.860146)
		(width 0.17145)
		(layer "F.Cu")
		(net "DRIVE_B_5_ACT")
	)
	(via
		(at 229.25024 -206.581502)
		(size 0.5588)
		(drill 0.3048)
		(layers "F.Cu" "B.Cu")
		(net "DRIVE_B_5_ACT")
	)
	(via
		(at 167.549068 -210.5787)
		(size 0.6604)
		(drill 0.3302)
		(layers "F.Cu" "B.Cu")
		(net "DRIVE_B_5_ACT")
	)
	(via
		(at 167.549068 -209.4738)
		(size 0.5588)
		(drill 0.3048)
		(layers "F.Cu" "B.Cu")
		(net "DRIVE_B_5_ACT")
	)
	(segment
		(start 167.549068 -211.745068)
		(end 167.549068 -209.4738)
		(width 0.14605)
		(layer "In5.Cu")
		(net "DRIVE_B_5_ACT")
	)
	(segment
		(start 173.180756 -217.376756)
		(end 167.549068 -211.745068)
		(width 0.14605)
		(layer "In5.Cu")
		(net "DRIVE_B_5_ACT")
	)
	(segment
		(start 229.0572 -206.581502)
		(end 225.95967 -209.679032)
		(width 0.14605)
		(layer "In5.Cu")
		(net "DRIVE_B_5_ACT")
	)
	(segment
		(start 207.170782 -209.679032)
		(end 199.473058 -217.376756)
		(width 0.14605)
		(layer "In5.Cu")
		(net "DRIVE_B_5_ACT")
	)
	(segment
		(start 229.25024 -206.581502)
		(end 229.0572 -206.581502)
		(width 0.14605)
		(layer "In5.Cu")
		(net "DRIVE_B_5_ACT")
	)
	(segment
		(start 225.95967 -209.679032)
		(end 207.170782 -209.679032)
		(width 0.14605)
		(layer "In5.Cu")
		(net "DRIVE_B_5_ACT")
	)
	(segment
		(start 199.473058 -217.376756)
		(end 173.180756 -217.376756)
		(width 0.14605)
		(layer "In5.Cu")
		(net "DRIVE_B_5_ACT")
	)
	(segment
		(start 203.13269 -229.54615)
		(end 203.26731 -229.41153)
		(width 0.17145)
		(layer "F.Cu")
		(net "DRIVE_B_4_PWR")
	)
	(segment
		(start 152.883616 -228.84384)
		(end 154.992578 -228.84384)
		(width 0.17145)
		(layer "F.Cu")
		(net "DRIVE_B_4_PWR")
	)
	(segment
		(start 159.336232 -229.54615)
		(end 203.13269 -229.54615)
		(width 0.17145)
		(layer "F.Cu")
		(net "DRIVE_B_4_PWR")
	)
	(segment
		(start 226.443794 -232.31094)
		(end 228.5238 -230.230934)
		(width 0.17145)
		(layer "F.Cu")
		(net "DRIVE_B_4_PWR")
	)
	(segment
		(start 203.26731 -229.41153)
		(end 217.16873 -229.41153)
		(width 0.17145)
		(layer "F.Cu")
		(net "DRIVE_B_4_PWR")
	)
	(segment
		(start 154.992578 -228.84384)
		(end 158.633922 -228.84384)
		(width 0.17145)
		(layer "F.Cu")
		(net "DRIVE_B_4_PWR")
	)
	(segment
		(start 217.16873 -229.41153)
		(end 220.06814 -232.31094)
		(width 0.17145)
		(layer "F.Cu")
		(net "DRIVE_B_4_PWR")
	)
	(segment
		(start 148.9837 -246.253)
		(end 149.9108 -246.253)
		(width 0.17145)
		(layer "F.Cu")
		(net "DRIVE_B_4_PWR")
	)
	(segment
		(start 158.633922 -228.84384)
		(end 159.336232 -229.54615)
		(width 0.17145)
		(layer "F.Cu")
		(net "DRIVE_B_4_PWR")
	)
	(segment
		(start 228.5238 -230.230934)
		(end 228.5238 -229.251256)
		(width 0.17145)
		(layer "F.Cu")
		(net "DRIVE_B_4_PWR")
	)
	(segment
		(start 220.06814 -232.31094)
		(end 226.443794 -232.31094)
		(width 0.17145)
		(layer "F.Cu")
		(net "DRIVE_B_4_PWR")
	)
	(via
		(at 152.883616 -228.84384)
		(size 0.5588)
		(drill 0.3048)
		(layers "F.Cu" "B.Cu")
		(net "DRIVE_B_4_PWR")
	)
	(via
		(at 154.992578 -228.84384)
		(size 0.6604)
		(drill 0.3302)
		(layers "F.Cu" "B.Cu")
		(net "DRIVE_B_4_PWR")
	)
	(via
		(at 149.9108 -246.253)
		(size 0.5588)
		(drill 0.3048)
		(layers "F.Cu" "B.Cu")
		(net "DRIVE_B_4_PWR")
	)
	(segment
		(start 150.97506 -230.752396)
		(end 152.883616 -228.84384)
		(width 0.14605)
		(layer "In2.Cu")
		(net "DRIVE_B_4_PWR")
	)
	(segment
		(start 150.97506 -245.18874)
		(end 150.97506 -230.752396)
		(width 0.14605)
		(layer "In2.Cu")
		(net "DRIVE_B_4_PWR")
	)
	(segment
		(start 149.9108 -246.253)
		(end 150.97506 -245.18874)
		(width 0.14605)
		(layer "In2.Cu")
		(net "DRIVE_B_4_PWR")
	)
	(segment
		(start 190.16853 -284.353)
		(end 195.893944 -278.627586)
		(width 0.17145)
		(layer "F.Cu")
		(net "DRIVE_B_4_INS")
	)
	(segment
		(start 165.227 -284.353)
		(end 190.16853 -284.353)
		(width 0.17145)
		(layer "F.Cu")
		(net "DRIVE_B_4_INS")
	)
	(segment
		(start 162.687 -266.065)
		(end 162.687 -281.813)
		(width 0.17145)
		(layer "F.Cu")
		(net "DRIVE_B_4_INS")
	)
	(segment
		(start 162.687 -281.813)
		(end 165.227 -284.353)
		(width 0.17145)
		(layer "F.Cu")
		(net "DRIVE_B_4_INS")
	)
	(segment
		(start 205.64602 -246.340122)
		(end 204.650848 -247.335294)
		(width 0.17145)
		(layer "F.Cu")
		(net "DRIVE_B_4_INS")
	)
	(segment
		(start 205.64602 -244.48262)
		(end 205.64602 -246.340122)
		(width 0.17145)
		(layer "F.Cu")
		(net "DRIVE_B_4_INS")
	)
	(segment
		(start 204.650848 -269.870682)
		(end 195.893944 -278.627586)
		(width 0.17145)
		(layer "F.Cu")
		(net "DRIVE_B_4_INS")
	)
	(segment
		(start 204.650848 -247.335294)
		(end 204.650848 -269.870682)
		(width 0.17145)
		(layer "F.Cu")
		(net "DRIVE_B_4_INS")
	)
	(via
		(at 195.893944 -278.627586)
		(size 0.6604)
		(drill 0.3302)
		(layers "F.Cu" "B.Cu")
		(net "DRIVE_B_4_INS")
	)
	(segment
		(start 197.778624 -219.805504)
		(end 152.845008 -219.805504)
		(width 0.17145)
		(layer "F.Cu")
		(net "DRIVE_B_4_FLT_LED")
	)
	(segment
		(start 152.13838 -219.09913)
		(end 151.77897 -218.73972)
		(width 0.17145)
		(layer "F.Cu")
		(net "DRIVE_B_4_FLT_LED")
	)
	(segment
		(start 198.23176 -220.25864)
		(end 197.778624 -219.805504)
		(width 0.17145)
		(layer "F.Cu")
		(net "DRIVE_B_4_FLT_LED")
	)
	(segment
		(start 151.77897 -218.73972)
		(end 151.77897 -217.642186)
		(width 0.17145)
		(layer "F.Cu")
		(net "DRIVE_B_4_FLT_LED")
	)
	(segment
		(start 152.845008 -219.805504)
		(end 152.13838 -219.09913)
		(width 0.17145)
		(layer "F.Cu")
		(net "DRIVE_B_4_FLT_LED")
	)
	(segment
		(start 151.77897 -217.642186)
		(end 151.77897 -215.9635)
		(width 0.17145)
		(layer "F.Cu")
		(net "DRIVE_B_4_FLT_LED")
	)
	(segment
		(start 212.9536 -220.25864)
		(end 198.23176 -220.25864)
		(width 0.17145)
		(layer "F.Cu")
		(net "DRIVE_B_4_FLT_LED")
	)
	(via
		(at 152.13838 -219.09913)
		(size 0.6604)
		(drill 0.3302)
		(layers "F.Cu" "B.Cu")
		(net "DRIVE_B_4_FLT_LED")
	)
	(segment
		(start 256.78638 -203.405994)
		(end 275.692362 -203.405994)
		(width 0.17145)
		(layer "F.Cu")
		(net "DRIVE_B_4_ACT")
	)
	(segment
		(start 230.166164 -206.447136)
		(end 230.166164 -205.824836)
		(width 0.17145)
		(layer "F.Cu")
		(net "DRIVE_B_4_ACT")
	)
	(segment
		(start 275.692362 -203.405994)
		(end 275.7678 -203.330556)
		(width 0.17145)
		(layer "F.Cu")
		(net "DRIVE_B_4_ACT")
	)
	(segment
		(start 234.610656 -203.345796)
		(end 241.5286 -203.345796)
		(width 0.17145)
		(layer "F.Cu")
		(net "DRIVE_B_4_ACT")
	)
	(segment
		(start 242.464844 -202.409552)
		(end 255.789938 -202.409552)
		(width 0.17145)
		(layer "F.Cu")
		(net "DRIVE_B_4_ACT")
	)
	(segment
		(start 147.992592 -213.93277)
		(end 147.992592 -212.44687)
		(width 0.17145)
		(layer "F.Cu")
		(net "DRIVE_B_4_ACT")
	)
	(segment
		(start 241.5286 -203.345796)
		(end 242.464844 -202.409552)
		(width 0.17145)
		(layer "F.Cu")
		(net "DRIVE_B_4_ACT")
	)
	(segment
		(start 233.031284 -203.943458)
		(end 234.012994 -203.943458)
		(width 0.17145)
		(layer "F.Cu")
		(net "DRIVE_B_4_ACT")
	)
	(segment
		(start 282.072842 -203.330556)
		(end 283.23667 -204.494384)
		(width 0.17145)
		(layer "F.Cu")
		(net "DRIVE_B_4_ACT")
	)
	(segment
		(start 147.992592 -212.44687)
		(end 147.992592 -210.711542)
		(width 0.17145)
		(layer "F.Cu")
		(net "DRIVE_B_4_ACT")
	)
	(segment
		(start 232.278428 -204.696314)
		(end 233.031284 -203.943458)
		(width 0.17145)
		(layer "F.Cu")
		(net "DRIVE_B_4_ACT")
	)
	(segment
		(start 255.789938 -202.409552)
		(end 256.78638 -203.405994)
		(width 0.17145)
		(layer "F.Cu")
		(net "DRIVE_B_4_ACT")
	)
	(segment
		(start 275.7678 -203.330556)
		(end 282.072842 -203.330556)
		(width 0.17145)
		(layer "F.Cu")
		(net "DRIVE_B_4_ACT")
	)
	(segment
		(start 234.012994 -203.943458)
		(end 234.610656 -203.345796)
		(width 0.17145)
		(layer "F.Cu")
		(net "DRIVE_B_4_ACT")
	)
	(segment
		(start 147.992592 -210.711542)
		(end 147.992592 -209.606642)
		(width 0.17145)
		(layer "F.Cu")
		(net "DRIVE_B_4_ACT")
	)
	(segment
		(start 231.294686 -204.696314)
		(end 232.278428 -204.696314)
		(width 0.17145)
		(layer "F.Cu")
		(net "DRIVE_B_4_ACT")
	)
	(segment
		(start 230.166164 -205.824836)
		(end 231.294686 -204.696314)
		(width 0.17145)
		(layer "F.Cu")
		(net "DRIVE_B_4_ACT")
	)
	(via
		(at 147.992592 -210.711542)
		(size 0.6604)
		(drill 0.3302)
		(layers "F.Cu" "B.Cu")
		(net "DRIVE_B_4_ACT")
	)
	(via
		(at 147.992592 -209.606642)
		(size 0.5588)
		(drill 0.3048)
		(layers "F.Cu" "B.Cu")
		(net "DRIVE_B_4_ACT")
	)
	(via
		(at 230.166164 -206.447136)
		(size 0.5588)
		(drill 0.3048)
		(layers "F.Cu" "B.Cu")
		(net "DRIVE_B_4_ACT")
	)
	(segment
		(start 229.998524 -206.656178)
		(end 229.998524 -206.614776)
		(width 0.14605)
		(layer "In5.Cu")
		(net "DRIVE_B_4_ACT")
	)
	(segment
		(start 226.53752 -210.117182)
		(end 229.998524 -206.656178)
		(width 0.14605)
		(layer "In5.Cu")
		(net "DRIVE_B_4_ACT")
	)
	(segment
		(start 156.200856 -217.814906)
		(end 199.654668 -217.814906)
		(width 0.14605)
		(layer "In5.Cu")
		(net "DRIVE_B_4_ACT")
	)
	(segment
		(start 147.992592 -209.606642)
		(end 156.200856 -217.814906)
		(width 0.14605)
		(layer "In5.Cu")
		(net "DRIVE_B_4_ACT")
	)
	(segment
		(start 207.352392 -210.117182)
		(end 226.53752 -210.117182)
		(width 0.14605)
		(layer "In5.Cu")
		(net "DRIVE_B_4_ACT")
	)
	(segment
		(start 199.654668 -217.814906)
		(end 207.352392 -210.117182)
		(width 0.14605)
		(layer "In5.Cu")
		(net "DRIVE_B_4_ACT")
	)
	(segment
		(start 229.998524 -206.614776)
		(end 230.166164 -206.447136)
		(width 0.14605)
		(layer "In5.Cu")
		(net "DRIVE_B_4_ACT")
	)
	(segment
		(start 243.61394 -226.17176)
		(end 244.89918 -227.457)
		(width 0.17145)
		(layer "F.Cu")
		(net "DRIVE_B_35_PWR")
	)
	(segment
		(start 311.616598 -222.308928)
		(end 311.616598 -253.286514)
		(width 0.17145)
		(layer "F.Cu")
		(net "DRIVE_B_35_PWR")
	)
	(segment
		(start 306.317396 -258.58597)
		(end 306.016406 -258.88696)
		(width 0.17145)
		(layer "F.Cu")
		(net "DRIVE_B_35_PWR")
	)
	(segment
		(start 311.616598 -253.286514)
		(end 306.317396 -258.585716)
		(width 0.17145)
		(layer "F.Cu")
		(net "DRIVE_B_35_PWR")
	)
	(segment
		(start 311.616598 -203.581)
		(end 305.293268 -209.90433)
		(width 0.17145)
		(layer "F.Cu")
		(net "DRIVE_B_35_PWR")
	)
	(segment
		(start 305.293268 -215.985598)
		(end 311.616598 -222.308928)
		(width 0.17145)
		(layer "F.Cu")
		(net "DRIVE_B_35_PWR")
	)
	(segment
		(start 243.61394 -224.34042)
		(end 243.61394 -226.17176)
		(width 0.17145)
		(layer "F.Cu")
		(net "DRIVE_B_35_PWR")
	)
	(segment
		(start 305.293268 -209.90433)
		(end 305.293268 -215.985598)
		(width 0.17145)
		(layer "F.Cu")
		(net "DRIVE_B_35_PWR")
	)
	(segment
		(start 311.616598 -180.878226)
		(end 311.616598 -203.581)
		(width 0.17145)
		(layer "F.Cu")
		(net "DRIVE_B_35_PWR")
	)
	(segment
		(start 306.317396 -258.585716)
		(end 306.317396 -258.58597)
		(width 0.17145)
		(layer "F.Cu")
		(net "DRIVE_B_35_PWR")
	)
	(segment
		(start 246.591836 -229.149656)
		(end 244.89918 -227.457)
		(width 0.17145)
		(layer "F.Cu")
		(net "DRIVE_B_35_PWR")
	)
	(segment
		(start 275.20265 -258.88696)
		(end 246.591836 -230.276146)
		(width 0.17145)
		(layer "F.Cu")
		(net "DRIVE_B_35_PWR")
	)
	(segment
		(start 307.411882 -176.67351)
		(end 311.616598 -180.878226)
		(width 0.17145)
		(layer "F.Cu")
		(net "DRIVE_B_35_PWR")
	)
	(segment
		(start 475.7166 -11.6205)
		(end 475.7166 -12.446)
		(width 0.17145)
		(layer "F.Cu")
		(net "DRIVE_B_35_PWR")
	)
	(segment
		(start 306.016406 -258.88696)
		(end 275.20265 -258.88696)
		(width 0.17145)
		(layer "F.Cu")
		(net "DRIVE_B_35_PWR")
	)
	(segment
		(start 246.591836 -230.276146)
		(end 246.591836 -229.149656)
		(width 0.17145)
		(layer "F.Cu")
		(net "DRIVE_B_35_PWR")
	)
	(via
		(at 244.89918 -227.457)
		(size 0.6604)
		(drill 0.3302)
		(layers "F.Cu" "B.Cu")
		(net "DRIVE_B_35_PWR")
	)
	(via
		(at 307.411882 -176.67351)
		(size 0.5588)
		(drill 0.3048)
		(layers "F.Cu" "B.Cu")
		(net "DRIVE_B_35_PWR")
	)
	(via
		(at 475.7166 -12.446)
		(size 0.5588)
		(drill 0.3048)
		(layers "F.Cu" "B.Cu")
		(net "DRIVE_B_35_PWR")
	)
	(segment
		(start 473.078556 -37.993066)
		(end 473.078556 -31.561024)
		(width 0.14605)
		(layer "In2.Cu")
		(net "DRIVE_B_35_PWR")
	)
	(segment
		(start 306.924202 -132.825998)
		(end 327.933812 -111.816388)
		(width 0.14605)
		(layer "In2.Cu")
		(net "DRIVE_B_35_PWR")
	)
	(segment
		(start 379.128274 -55.898796)
		(end 409.363926 -55.898796)
		(width 0.14605)
		(layer "In2.Cu")
		(net "DRIVE_B_35_PWR")
	)
	(segment
		(start 475.33687 -12.82573)
		(end 475.7166 -12.446)
		(width 0.14605)
		(layer "In2.Cu")
		(net "DRIVE_B_35_PWR")
	)
	(segment
		(start 409.363926 -55.898796)
		(end 415.272474 -49.990248)
		(width 0.14605)
		(layer "In2.Cu")
		(net "DRIVE_B_35_PWR")
	)
	(segment
		(start 466.694266 -44.377356)
		(end 473.078556 -37.993066)
		(width 0.14605)
		(layer "In2.Cu")
		(net "DRIVE_B_35_PWR")
	)
	(segment
		(start 345.482926 -89.544144)
		(end 379.128274 -55.898796)
		(width 0.14605)
		(layer "In2.Cu")
		(net "DRIVE_B_35_PWR")
	)
	(segment
		(start 327.933812 -111.816388)
		(end 327.933812 -90.518488)
		(width 0.14605)
		(layer "In2.Cu")
		(net "DRIVE_B_35_PWR")
	)
	(segment
		(start 328.908156 -89.544144)
		(end 345.482926 -89.544144)
		(width 0.14605)
		(layer "In2.Cu")
		(net "DRIVE_B_35_PWR")
	)
	(segment
		(start 307.411882 -176.67351)
		(end 306.924202 -176.18583)
		(width 0.14605)
		(layer "In2.Cu")
		(net "DRIVE_B_35_PWR")
	)
	(segment
		(start 476.952818 -16.59382)
		(end 475.33687 -14.977872)
		(width 0.14605)
		(layer "In2.Cu")
		(net "DRIVE_B_35_PWR")
	)
	(segment
		(start 415.272474 -49.990248)
		(end 442.9252 -49.990248)
		(width 0.14605)
		(layer "In2.Cu")
		(net "DRIVE_B_35_PWR")
	)
	(segment
		(start 475.33687 -14.977872)
		(end 475.33687 -12.82573)
		(width 0.14605)
		(layer "In2.Cu")
		(net "DRIVE_B_35_PWR")
	)
	(segment
		(start 442.9252 -49.990248)
		(end 448.538092 -44.377356)
		(width 0.14605)
		(layer "In2.Cu")
		(net "DRIVE_B_35_PWR")
	)
	(segment
		(start 448.538092 -44.377356)
		(end 466.694266 -44.377356)
		(width 0.14605)
		(layer "In2.Cu")
		(net "DRIVE_B_35_PWR")
	)
	(segment
		(start 473.078556 -31.561024)
		(end 476.952818 -27.686762)
		(width 0.14605)
		(layer "In2.Cu")
		(net "DRIVE_B_35_PWR")
	)
	(segment
		(start 306.924202 -176.18583)
		(end 306.924202 -132.825998)
		(width 0.14605)
		(layer "In2.Cu")
		(net "DRIVE_B_35_PWR")
	)
	(segment
		(start 476.952818 -27.686762)
		(end 476.952818 -16.59382)
		(width 0.14605)
		(layer "In2.Cu")
		(net "DRIVE_B_35_PWR")
	)
	(segment
		(start 327.933812 -90.518488)
		(end 328.908156 -89.544144)
		(width 0.14605)
		(layer "In2.Cu")
		(net "DRIVE_B_35_PWR")
	)
	(segment
		(start 218.33586 -169.02938)
		(end 223.689164 -169.02938)
		(width 0.17145)
		(layer "F.Cu")
		(net "DRIVE_B_35_INS")
	)
	(segment
		(start 223.689164 -169.02938)
		(end 236.97311 -155.745434)
		(width 0.17145)
		(layer "F.Cu")
		(net "DRIVE_B_35_INS")
	)
	(segment
		(start 299.428154 -155.745434)
		(end 306.17541 -148.998178)
		(width 0.17145)
		(layer "F.Cu")
		(net "DRIVE_B_35_INS")
	)
	(segment
		(start 475.563692 -17.506188)
		(end 474.6244 -17.506188)
		(width 0.17145)
		(layer "F.Cu")
		(net "DRIVE_B_35_INS")
	)
	(segment
		(start 306.17541 -145.353532)
		(end 306.314094 -145.214848)
		(width 0.17145)
		(layer "F.Cu")
		(net "DRIVE_B_35_INS")
	)
	(segment
		(start 319.278 -110.3884)
		(end 319.278 -110.39094)
		(width 0.17145)
		(layer "F.Cu")
		(net "DRIVE_B_35_INS")
	)
	(segment
		(start 306.17541 -148.998178)
		(end 306.17541 -145.353532)
		(width 0.17145)
		(layer "F.Cu")
		(net "DRIVE_B_35_INS")
	)
	(segment
		(start 236.97311 -155.745434)
		(end 299.428154 -155.745434)
		(width 0.17145)
		(layer "F.Cu")
		(net "DRIVE_B_35_INS")
	)
	(segment
		(start 306.314094 -123.354846)
		(end 317.191136 -112.477804)
		(width 0.17145)
		(layer "F.Cu")
		(net "DRIVE_B_35_INS")
	)
	(segment
		(start 306.314094 -145.214848)
		(end 306.314094 -123.354846)
		(width 0.17145)
		(layer "F.Cu")
		(net "DRIVE_B_35_INS")
	)
	(segment
		(start 319.278 -110.39094)
		(end 317.191136 -112.477804)
		(width 0.17145)
		(layer "F.Cu")
		(net "DRIVE_B_35_INS")
	)
	(via
		(at 317.191136 -112.477804)
		(size 0.6604)
		(drill 0.3302)
		(layers "F.Cu" "B.Cu")
		(net "DRIVE_B_35_INS")
	)
	(via
		(at 319.278 -110.3884)
		(size 0.5588)
		(drill 0.3048)
		(layers "F.Cu" "B.Cu")
		(net "DRIVE_B_35_INS")
	)
	(via
		(at 474.6244 -17.506188)
		(size 0.5588)
		(drill 0.3048)
		(layers "F.Cu" "B.Cu")
		(net "DRIVE_B_35_INS")
	)
	(segment
		(start 475.62135 -26.68905)
		(end 475.62135 -21.850096)
		(width 0.14605)
		(layer "In2.Cu")
		(net "DRIVE_B_35_INS")
	)
	(segment
		(start 324.894956 -87.445596)
		(end 338.503768 -87.445596)
		(width 0.14605)
		(layer "In2.Cu")
		(net "DRIVE_B_35_INS")
	)
	(segment
		(start 325.524876 -94.192344)
		(end 324.615048 -93.282516)
		(width 0.14605)
		(layer "In2.Cu")
		(net "DRIVE_B_35_INS")
	)
	(segment
		(start 319.278 -110.39094)
		(end 325.524876 -104.144064)
		(width 0.14605)
		(layer "In2.Cu")
		(net "DRIVE_B_35_INS")
	)
	(segment
		(start 325.524876 -104.144064)
		(end 325.524876 -94.192344)
		(width 0.14605)
		(layer "In2.Cu")
		(net "DRIVE_B_35_INS")
	)
	(segment
		(start 324.615048 -87.725504)
		(end 324.894956 -87.445596)
		(width 0.14605)
		(layer "In2.Cu")
		(net "DRIVE_B_35_INS")
	)
	(segment
		(start 475.62135 -21.850096)
		(end 476.123 -21.348446)
		(width 0.14605)
		(layer "In2.Cu")
		(net "DRIVE_B_35_INS")
	)
	(segment
		(start 324.615048 -93.282516)
		(end 324.615048 -87.725504)
		(width 0.14605)
		(layer "In2.Cu")
		(net "DRIVE_B_35_INS")
	)
	(segment
		(start 400.932904 -53.844444)
		(end 411.936946 -42.840402)
		(width 0.14605)
		(layer "In2.Cu")
		(net "DRIVE_B_35_INS")
	)
	(segment
		(start 462.277714 -40.005)
		(end 469.5444 -40.005)
		(width 0.14605)
		(layer "In2.Cu")
		(net "DRIVE_B_35_INS")
	)
	(segment
		(start 338.503768 -87.445596)
		(end 339.471 -86.478364)
		(width 0.14605)
		(layer "In2.Cu")
		(net "DRIVE_B_35_INS")
	)
	(segment
		(start 472.1352 -30.1752)
		(end 475.62135 -26.68905)
		(width 0.14605)
		(layer "In2.Cu")
		(net "DRIVE_B_35_INS")
	)
	(segment
		(start 339.471 -86.478364)
		(end 343.190576 -86.478364)
		(width 0.14605)
		(layer "In2.Cu")
		(net "DRIVE_B_35_INS")
	)
	(segment
		(start 476.123 -21.348446)
		(end 476.123 -19.004788)
		(width 0.14605)
		(layer "In2.Cu")
		(net "DRIVE_B_35_INS")
	)
	(segment
		(start 459.442312 -42.840402)
		(end 462.277714 -40.005)
		(width 0.14605)
		(layer "In2.Cu")
		(net "DRIVE_B_35_INS")
	)
	(segment
		(start 472.1352 -37.4142)
		(end 472.1352 -30.1752)
		(width 0.14605)
		(layer "In2.Cu")
		(net "DRIVE_B_35_INS")
	)
	(segment
		(start 469.5444 -40.005)
		(end 472.1352 -37.4142)
		(width 0.14605)
		(layer "In2.Cu")
		(net "DRIVE_B_35_INS")
	)
	(segment
		(start 411.936946 -42.840402)
		(end 459.442312 -42.840402)
		(width 0.14605)
		(layer "In2.Cu")
		(net "DRIVE_B_35_INS")
	)
	(segment
		(start 319.278 -110.3884)
		(end 319.278 -110.39094)
		(width 0.14605)
		(layer "In2.Cu")
		(net "DRIVE_B_35_INS")
	)
	(segment
		(start 375.824496 -53.844444)
		(end 400.932904 -53.844444)
		(width 0.14605)
		(layer "In2.Cu")
		(net "DRIVE_B_35_INS")
	)
	(segment
		(start 343.190576 -86.478364)
		(end 375.824496 -53.844444)
		(width 0.14605)
		(layer "In2.Cu")
		(net "DRIVE_B_35_INS")
	)
	(segment
		(start 476.123 -19.004788)
		(end 474.6244 -17.506188)
		(width 0.14605)
		(layer "In2.Cu")
		(net "DRIVE_B_35_INS")
	)
	(via
		(at 287.2232 -120.1166)
		(size 0.5588)
		(drill 0.3048)
		(layers "F.Cu" "B.Cu")
		(net "DRIVE_B_35_ACT")
	)
	(segment
		(start 290.141914 -145.536158)
		(end 290.172902 -145.50517)
		(width 0.14605)
		(layer "In2.Cu")
		(net "DRIVE_B_35_ACT")
	)
	(segment
		(start 282.83662 -177.494438)
		(end 283.572458 -176.7586)
		(width 0.14605)
		(layer "In2.Cu")
		(net "DRIVE_B_35_ACT")
	)
	(segment
		(start 288.21888 -176.7586)
		(end 288.88817 -176.08931)
		(width 0.14605)
		(layer "In2.Cu")
		(net "DRIVE_B_35_ACT")
	)
	(segment
		(start 290.148264 -126.724664)
		(end 287.2232 -123.7996)
		(width 0.14605)
		(layer "In2.Cu")
		(net "DRIVE_B_35_ACT")
	)
	(segment
		(start 290.172902 -135.158734)
		(end 290.148264 -135.134096)
		(width 0.14605)
		(layer "In2.Cu")
		(net "DRIVE_B_35_ACT")
	)
	(segment
		(start 283.572458 -176.7586)
		(end 288.21888 -176.7586)
		(width 0.14605)
		(layer "In2.Cu")
		(net "DRIVE_B_35_ACT")
	)
	(segment
		(start 287.2232 -123.7996)
		(end 287.2232 -120.1166)
		(width 0.14605)
		(layer "In2.Cu")
		(net "DRIVE_B_35_ACT")
	)
	(segment
		(start 290.172902 -145.50517)
		(end 290.172902 -135.158734)
		(width 0.14605)
		(layer "In2.Cu")
		(net "DRIVE_B_35_ACT")
	)
	(segment
		(start 288.88817 -176.08931)
		(end 288.88817 -170.5864)
		(width 0.14605)
		(layer "In2.Cu")
		(net "DRIVE_B_35_ACT")
	)
	(segment
		(start 290.141914 -169.332656)
		(end 290.141914 -145.536158)
		(width 0.14605)
		(layer "In2.Cu")
		(net "DRIVE_B_35_ACT")
	)
	(segment
		(start 290.148264 -135.134096)
		(end 290.148264 -126.724664)
		(width 0.14605)
		(layer "In2.Cu")
		(net "DRIVE_B_35_ACT")
	)
	(segment
		(start 288.88817 -170.5864)
		(end 290.141914 -169.332656)
		(width 0.14605)
		(layer "In2.Cu")
		(net "DRIVE_B_35_ACT")
	)
	(segment
		(start 229.80015 -80.847692)
		(end 251.81306 -102.860602)
		(width 0.14605)
		(layer "In5.Cu")
		(net "DRIVE_B_35_ACT")
	)
	(segment
		(start 285.801054 -118.694454)
		(end 287.2232 -120.1166)
		(width 0.14605)
		(layer "In5.Cu")
		(net "DRIVE_B_35_ACT")
	)
	(segment
		(start 277.678134 -118.694454)
		(end 285.801054 -118.694454)
		(width 0.14605)
		(layer "In5.Cu")
		(net "DRIVE_B_35_ACT")
	)
	(segment
		(start 251.81306 -102.860602)
		(end 261.844282 -102.860602)
		(width 0.14605)
		(layer "In5.Cu")
		(net "DRIVE_B_35_ACT")
	)
	(segment
		(start 261.844282 -102.860602)
		(end 277.678134 -118.694454)
		(width 0.14605)
		(layer "In5.Cu")
		(net "DRIVE_B_35_ACT")
	)
	(segment
		(start 229.80015 -80.099916)
		(end 229.80015 -80.847692)
		(width 0.14605)
		(layer "In5.Cu")
		(net "DRIVE_B_35_ACT")
	)
	(segment
		(start 304.778918 -209.691224)
		(end 304.778918 -216.198704)
		(width 0.17145)
		(layer "F.Cu")
		(net "DRIVE_B_34_PWR")
	)
	(segment
		(start 465.9884 -20.5232)
		(end 461.8228 -16.3576)
		(width 0.17145)
		(layer "F.Cu")
		(net "DRIVE_B_34_PWR")
	)
	(segment
		(start 310.814466 -222.234252)
		(end 310.814466 -253.36119)
		(width 0.17145)
		(layer "F.Cu")
		(net "DRIVE_B_34_PWR")
	)
	(segment
		(start 310.814466 -180.806852)
		(end 310.814466 -203.655676)
		(width 0.17145)
		(layer "F.Cu")
		(net "DRIVE_B_34_PWR")
	)
	(segment
		(start 244.26418 -224.34042)
		(end 244.26418 -225.89109)
		(width 0.17145)
		(layer "F.Cu")
		(net "DRIVE_B_34_PWR")
	)
	(segment
		(start 465.9884 -28.0162)
		(end 465.9884 -20.5232)
		(width 0.17145)
		(layer "F.Cu")
		(net "DRIVE_B_34_PWR")
	)
	(segment
		(start 310.814466 -203.655676)
		(end 304.778918 -209.691224)
		(width 0.17145)
		(layer "F.Cu")
		(net "DRIVE_B_34_PWR")
	)
	(segment
		(start 465.840572 -34.35096)
		(end 465.540852 -34.05124)
		(width 0.17145)
		(layer "F.Cu")
		(net "DRIVE_B_34_PWR")
	)
	(segment
		(start 247.723152 -230.680006)
		(end 247.723152 -229.350316)
		(width 0.17145)
		(layer "F.Cu")
		(net "DRIVE_B_34_PWR")
	)
	(segment
		(start 247.723152 -229.350316)
		(end 247.104916 -228.73208)
		(width 0.17145)
		(layer "F.Cu")
		(net "DRIVE_B_34_PWR")
	)
	(segment
		(start 244.832632 -226.459796)
		(end 247.104916 -228.73208)
		(width 0.17145)
		(layer "F.Cu")
		(net "DRIVE_B_34_PWR")
	)
	(segment
		(start 275.415756 -258.37261)
		(end 247.723152 -230.680006)
		(width 0.17145)
		(layer "F.Cu")
		(net "DRIVE_B_34_PWR")
	)
	(segment
		(start 307.289962 -177.282348)
		(end 310.814466 -180.806852)
		(width 0.17145)
		(layer "F.Cu")
		(net "DRIVE_B_34_PWR")
	)
	(segment
		(start 304.778918 -216.198704)
		(end 310.814466 -222.234252)
		(width 0.17145)
		(layer "F.Cu")
		(net "DRIVE_B_34_PWR")
	)
	(segment
		(start 465.540852 -28.463748)
		(end 465.9884 -28.0162)
		(width 0.17145)
		(layer "F.Cu")
		(net "DRIVE_B_34_PWR")
	)
	(segment
		(start 244.26418 -225.89109)
		(end 244.832632 -226.459542)
		(width 0.17145)
		(layer "F.Cu")
		(net "DRIVE_B_34_PWR")
	)
	(segment
		(start 465.840572 -43.124882)
		(end 465.840572 -34.35096)
		(width 0.17145)
		(layer "F.Cu")
		(net "DRIVE_B_34_PWR")
	)
	(segment
		(start 310.814466 -253.36119)
		(end 305.803046 -258.37261)
		(width 0.17145)
		(layer "F.Cu")
		(net "DRIVE_B_34_PWR")
	)
	(segment
		(start 461.8228 -16.3576)
		(end 461.3275 -16.3576)
		(width 0.17145)
		(layer "F.Cu")
		(net "DRIVE_B_34_PWR")
	)
	(segment
		(start 305.803046 -258.37261)
		(end 275.415756 -258.37261)
		(width 0.17145)
		(layer "F.Cu")
		(net "DRIVE_B_34_PWR")
	)
	(segment
		(start 465.540852 -34.05124)
		(end 465.540852 -28.463748)
		(width 0.17145)
		(layer "F.Cu")
		(net "DRIVE_B_34_PWR")
	)
	(segment
		(start 244.832632 -226.459542)
		(end 244.832632 -226.459796)
		(width 0.17145)
		(layer "F.Cu")
		(net "DRIVE_B_34_PWR")
	)
	(segment
		(start 306.696872 -177.282348)
		(end 307.289962 -177.282348)
		(width 0.17145)
		(layer "F.Cu")
		(net "DRIVE_B_34_PWR")
	)
	(via
		(at 306.696872 -177.282348)
		(size 0.5588)
		(drill 0.3048)
		(layers "F.Cu" "B.Cu")
		(net "DRIVE_B_34_PWR")
	)
	(via
		(at 247.104916 -228.73208)
		(size 0.6604)
		(drill 0.3302)
		(layers "F.Cu" "B.Cu")
		(net "DRIVE_B_34_PWR")
	)
	(via
		(at 465.840572 -43.124882)
		(size 0.5588)
		(drill 0.3048)
		(layers "F.Cu" "B.Cu")
		(net "DRIVE_B_34_PWR")
	)
	(segment
		(start 378.932186 -55.425848)
		(end 409.217114 -55.425848)
		(width 0.14605)
		(layer "In2.Cu")
		(net "DRIVE_B_34_PWR")
	)
	(segment
		(start 465.061046 -43.904408)
		(end 465.840572 -43.124882)
		(width 0.14605)
		(layer "In2.Cu")
		(net "DRIVE_B_34_PWR")
	)
	(segment
		(start 409.217114 -55.425848)
		(end 415.090864 -49.552098)
		(width 0.14605)
		(layer "In2.Cu")
		(net "DRIVE_B_34_PWR")
	)
	(segment
		(start 306.486052 -177.071528)
		(end 306.486052 -132.594858)
		(width 0.14605)
		(layer "In2.Cu")
		(net "DRIVE_B_34_PWR")
	)
	(segment
		(start 345.286838 -89.071196)
		(end 378.932186 -55.425848)
		(width 0.14605)
		(layer "In2.Cu")
		(net "DRIVE_B_34_PWR")
	)
	(segment
		(start 306.486052 -132.594858)
		(end 315.773308 -123.307856)
		(width 0.14605)
		(layer "In2.Cu")
		(net "DRIVE_B_34_PWR")
	)
	(segment
		(start 327.460864 -111.6203)
		(end 327.460864 -90.3224)
		(width 0.14605)
		(layer "In2.Cu")
		(net "DRIVE_B_34_PWR")
	)
	(segment
		(start 327.460864 -90.3224)
		(end 328.712068 -89.071196)
		(width 0.14605)
		(layer "In2.Cu")
		(net "DRIVE_B_34_PWR")
	)
	(segment
		(start 315.773308 -123.307856)
		(end 327.460864 -111.6203)
		(width 0.14605)
		(layer "In2.Cu")
		(net "DRIVE_B_34_PWR")
	)
	(segment
		(start 448.342004 -43.904408)
		(end 465.061046 -43.904408)
		(width 0.14605)
		(layer "In2.Cu")
		(net "DRIVE_B_34_PWR")
	)
	(segment
		(start 328.712068 -89.071196)
		(end 345.286838 -89.071196)
		(width 0.14605)
		(layer "In2.Cu")
		(net "DRIVE_B_34_PWR")
	)
	(segment
		(start 415.090864 -49.552098)
		(end 442.694314 -49.552098)
		(width 0.14605)
		(layer "In2.Cu")
		(net "DRIVE_B_34_PWR")
	)
	(segment
		(start 306.696872 -177.282348)
		(end 306.486052 -177.071528)
		(width 0.14605)
		(layer "In2.Cu")
		(net "DRIVE_B_34_PWR")
	)
	(segment
		(start 442.694314 -49.552098)
		(end 448.342004 -43.904408)
		(width 0.14605)
		(layer "In2.Cu")
		(net "DRIVE_B_34_PWR")
	)
	(segment
		(start 305.799744 -122.575828)
		(end 313.09564 -115.279932)
		(width 0.17145)
		(layer "F.Cu")
		(net "DRIVE_B_34_INS")
	)
	(segment
		(start 305.522884 -147.97659)
		(end 305.522884 -145.278602)
		(width 0.17145)
		(layer "F.Cu")
		(net "DRIVE_B_34_INS")
	)
	(segment
		(start 218.33586 -168.37914)
		(end 223.611948 -168.37914)
		(width 0.17145)
		(layer "F.Cu")
		(net "DRIVE_B_34_INS")
	)
	(segment
		(start 321.38493 -106.990642)
		(end 313.09564 -115.279932)
		(width 0.17145)
		(layer "F.Cu")
		(net "DRIVE_B_34_INS")
	)
	(segment
		(start 237.026704 -154.964384)
		(end 298.53509 -154.964384)
		(width 0.17145)
		(layer "F.Cu")
		(net "DRIVE_B_34_INS")
	)
	(segment
		(start 223.611948 -168.37914)
		(end 237.026704 -154.964384)
		(width 0.17145)
		(layer "F.Cu")
		(net "DRIVE_B_34_INS")
	)
	(segment
		(start 298.53509 -154.964384)
		(end 305.522884 -147.97659)
		(width 0.17145)
		(layer "F.Cu")
		(net "DRIVE_B_34_INS")
	)
	(segment
		(start 305.799744 -145.001742)
		(end 305.799744 -122.575828)
		(width 0.17145)
		(layer "F.Cu")
		(net "DRIVE_B_34_INS")
	)
	(segment
		(start 305.522884 -145.278602)
		(end 305.799744 -145.001742)
		(width 0.17145)
		(layer "F.Cu")
		(net "DRIVE_B_34_INS")
	)
	(segment
		(start 444.4238 -33.5026)
		(end 444.4238 -34.4424)
		(width 0.17145)
		(layer "F.Cu")
		(net "DRIVE_B_34_INS")
	)
	(via
		(at 444.4238 -34.4424)
		(size 0.5588)
		(drill 0.3048)
		(layers "F.Cu" "B.Cu")
		(net "DRIVE_B_34_INS")
	)
	(via
		(at 321.38493 -106.990642)
		(size 0.5588)
		(drill 0.3048)
		(layers "F.Cu" "B.Cu")
		(net "DRIVE_B_34_INS")
	)
	(via
		(at 313.09564 -115.279932)
		(size 0.6604)
		(drill 0.3302)
		(layers "F.Cu" "B.Cu")
		(net "DRIVE_B_34_INS")
	)
	(segment
		(start 324.176898 -87.543894)
		(end 324.176898 -93.464126)
		(width 0.14605)
		(layer "In2.Cu")
		(net "DRIVE_B_34_INS")
	)
	(segment
		(start 444.4238 -35.1282)
		(end 437.69407 -41.85793)
		(width 0.14605)
		(layer "In2.Cu")
		(net "DRIVE_B_34_INS")
	)
	(segment
		(start 339.28939 -86.040214)
		(end 338.322158 -87.007446)
		(width 0.14605)
		(layer "In2.Cu")
		(net "DRIVE_B_34_INS")
	)
	(segment
		(start 324.713346 -87.007446)
		(end 324.176898 -87.543894)
		(width 0.14605)
		(layer "In2.Cu")
		(net "DRIVE_B_34_INS")
	)
	(segment
		(start 444.4238 -34.4424)
		(end 444.4238 -35.1282)
		(width 0.14605)
		(layer "In2.Cu")
		(net "DRIVE_B_34_INS")
	)
	(segment
		(start 325.086726 -103.288846)
		(end 321.38493 -106.990642)
		(width 0.14605)
		(layer "In2.Cu")
		(net "DRIVE_B_34_INS")
	)
	(segment
		(start 338.322158 -87.007446)
		(end 324.713346 -87.007446)
		(width 0.14605)
		(layer "In2.Cu")
		(net "DRIVE_B_34_INS")
	)
	(segment
		(start 342.335358 -86.040214)
		(end 339.28939 -86.040214)
		(width 0.14605)
		(layer "In2.Cu")
		(net "DRIVE_B_34_INS")
	)
	(segment
		(start 411.830266 -41.85793)
		(end 400.363944 -53.324252)
		(width 0.14605)
		(layer "In2.Cu")
		(net "DRIVE_B_34_INS")
	)
	(segment
		(start 400.363944 -53.324252)
		(end 375.05132 -53.324252)
		(width 0.14605)
		(layer "In2.Cu")
		(net "DRIVE_B_34_INS")
	)
	(segment
		(start 437.69407 -41.85793)
		(end 411.830266 -41.85793)
		(width 0.14605)
		(layer "In2.Cu")
		(net "DRIVE_B_34_INS")
	)
	(segment
		(start 324.176898 -93.464126)
		(end 325.086726 -94.373954)
		(width 0.14605)
		(layer "In2.Cu")
		(net "DRIVE_B_34_INS")
	)
	(segment
		(start 375.05132 -53.324252)
		(end 342.335358 -86.040214)
		(width 0.14605)
		(layer "In2.Cu")
		(net "DRIVE_B_34_INS")
	)
	(segment
		(start 325.086726 -94.373954)
		(end 325.086726 -103.288846)
		(width 0.14605)
		(layer "In2.Cu")
		(net "DRIVE_B_34_INS")
	)
	(via
		(at 269.129002 -107.981242)
		(size 0.6096)
		(drill 0.3048)
		(layers "F.Cu" "B.Cu")
		(net "DRIVE_B_34_ACT")
	)
	(via
		(at 288.36874 -120.09628)
		(size 0.5588)
		(drill 0.3048)
		(layers "F.Cu" "B.Cu")
		(net "DRIVE_B_34_ACT")
	)
	(segment
		(start 242.3414 -84.9376)
		(end 248.63552 -91.23172)
		(width 0.17145)
		(layer "B.Cu")
		(net "DRIVE_B_34_ACT")
	)
	(segment
		(start 279.031954 -117.884194)
		(end 286.156654 -117.884194)
		(width 0.17145)
		(layer "B.Cu")
		(net "DRIVE_B_34_ACT")
	)
	(segment
		(start 235.06176 -84.9376)
		(end 242.3414 -84.9376)
		(width 0.17145)
		(layer "B.Cu")
		(net "DRIVE_B_34_ACT")
	)
	(segment
		(start 269.129002 -107.981242)
		(end 279.031954 -117.884194)
		(width 0.17145)
		(layer "B.Cu")
		(net "DRIVE_B_34_ACT")
	)
	(segment
		(start 230.4288 -80.30464)
		(end 235.06176 -84.9376)
		(width 0.17145)
		(layer "B.Cu")
		(net "DRIVE_B_34_ACT")
	)
	(segment
		(start 229.80015 -78.999842)
		(end 230.4288 -79.628492)
		(width 0.17145)
		(layer "B.Cu")
		(net "DRIVE_B_34_ACT")
	)
	(segment
		(start 252.37948 -91.23172)
		(end 269.129002 -107.981242)
		(width 0.17145)
		(layer "B.Cu")
		(net "DRIVE_B_34_ACT")
	)
	(segment
		(start 248.63552 -91.23172)
		(end 252.37948 -91.23172)
		(width 0.17145)
		(layer "B.Cu")
		(net "DRIVE_B_34_ACT")
	)
	(segment
		(start 230.4288 -79.628492)
		(end 230.4288 -80.30464)
		(width 0.17145)
		(layer "B.Cu")
		(net "DRIVE_B_34_ACT")
	)
	(segment
		(start 286.156654 -117.884194)
		(end 288.36874 -120.09628)
		(width 0.17145)
		(layer "B.Cu")
		(net "DRIVE_B_34_ACT")
	)
	(segment
		(start 290.591494 -126.228094)
		(end 288.36874 -124.00534)
		(width 0.14605)
		(layer "In2.Cu")
		(net "DRIVE_B_34_ACT")
	)
	(segment
		(start 290.580064 -145.717768)
		(end 290.611052 -145.68678)
		(width 0.14605)
		(layer "In2.Cu")
		(net "DRIVE_B_34_ACT")
	)
	(segment
		(start 290.611052 -134.977124)
		(end 290.591494 -134.957566)
		(width 0.14605)
		(layer "In2.Cu")
		(net "DRIVE_B_34_ACT")
	)
	(segment
		(start 289.204146 -178.140106)
		(end 290.580064 -176.764188)
		(width 0.14605)
		(layer "In2.Cu")
		(net "DRIVE_B_34_ACT")
	)
	(segment
		(start 290.591494 -134.957566)
		(end 290.591494 -126.228094)
		(width 0.14605)
		(layer "In2.Cu")
		(net "DRIVE_B_34_ACT")
	)
	(segment
		(start 288.36874 -124.00534)
		(end 288.36874 -120.09628)
		(width 0.14605)
		(layer "In2.Cu")
		(net "DRIVE_B_34_ACT")
	)
	(segment
		(start 290.580064 -176.764188)
		(end 290.580064 -145.717768)
		(width 0.14605)
		(layer "In2.Cu")
		(net "DRIVE_B_34_ACT")
	)
	(segment
		(start 284.236668 -177.494438)
		(end 284.882336 -178.140106)
		(width 0.14605)
		(layer "In2.Cu")
		(net "DRIVE_B_34_ACT")
	)
	(segment
		(start 284.882336 -178.140106)
		(end 289.204146 -178.140106)
		(width 0.14605)
		(layer "In2.Cu")
		(net "DRIVE_B_34_ACT")
	)
	(segment
		(start 290.611052 -145.68678)
		(end 290.611052 -134.977124)
		(width 0.14605)
		(layer "In2.Cu")
		(net "DRIVE_B_34_ACT")
	)
	(segment
		(start 249.042936 -231.056434)
		(end 249.042936 -229.751636)
		(width 0.17145)
		(layer "F.Cu")
		(net "DRIVE_B_33_PWR")
	)
	(segment
		(start 310.300116 -222.447358)
		(end 310.300116 -253.148084)
		(width 0.17145)
		(layer "F.Cu")
		(net "DRIVE_B_33_PWR")
	)
	(segment
		(start 305.58994 -257.85826)
		(end 275.844762 -257.85826)
		(width 0.17145)
		(layer "F.Cu")
		(net "DRIVE_B_33_PWR")
	)
	(segment
		(start 244.91442 -225.62312)
		(end 244.91442 -224.34042)
		(width 0.17145)
		(layer "F.Cu")
		(net "DRIVE_B_33_PWR")
	)
	(segment
		(start 434.98135 -15.69847)
		(end 432.42738 -13.1445)
		(width 0.17145)
		(layer "F.Cu")
		(net "DRIVE_B_33_PWR")
	)
	(segment
		(start 432.42738 -13.1445)
		(end 430.403 -13.1445)
		(width 0.17145)
		(layer "F.Cu")
		(net "DRIVE_B_33_PWR")
	)
	(segment
		(start 307.322474 -178.208432)
		(end 310.300116 -181.186074)
		(width 0.17145)
		(layer "F.Cu")
		(net "DRIVE_B_33_PWR")
	)
	(segment
		(start 434.98135 -48.582072)
		(end 434.98135 -15.69847)
		(width 0.17145)
		(layer "F.Cu")
		(net "DRIVE_B_33_PWR")
	)
	(segment
		(start 304.264568 -216.41181)
		(end 310.300116 -222.447358)
		(width 0.17145)
		(layer "F.Cu")
		(net "DRIVE_B_33_PWR")
	)
	(segment
		(start 304.264568 -209.478118)
		(end 304.264568 -216.41181)
		(width 0.17145)
		(layer "F.Cu")
		(net "DRIVE_B_33_PWR")
	)
	(segment
		(start 310.300116 -203.44257)
		(end 304.264568 -209.478118)
		(width 0.17145)
		(layer "F.Cu")
		(net "DRIVE_B_33_PWR")
	)
	(segment
		(start 310.300116 -253.148084)
		(end 305.58994 -257.85826)
		(width 0.17145)
		(layer "F.Cu")
		(net "DRIVE_B_33_PWR")
	)
	(segment
		(start 275.844762 -257.85826)
		(end 249.042936 -231.056434)
		(width 0.17145)
		(layer "F.Cu")
		(net "DRIVE_B_33_PWR")
	)
	(segment
		(start 248.420382 -229.129082)
		(end 244.91442 -225.62312)
		(width 0.17145)
		(layer "F.Cu")
		(net "DRIVE_B_33_PWR")
	)
	(segment
		(start 310.300116 -181.186074)
		(end 310.300116 -203.44257)
		(width 0.17145)
		(layer "F.Cu")
		(net "DRIVE_B_33_PWR")
	)
	(segment
		(start 249.042936 -229.751636)
		(end 248.420382 -229.129082)
		(width 0.17145)
		(layer "F.Cu")
		(net "DRIVE_B_33_PWR")
	)
	(via
		(at 307.322474 -178.208432)
		(size 0.5588)
		(drill 0.3048)
		(layers "F.Cu" "B.Cu")
		(net "DRIVE_B_33_PWR")
	)
	(via
		(at 434.98135 -48.582072)
		(size 0.5588)
		(drill 0.3048)
		(layers "F.Cu" "B.Cu")
		(net "DRIVE_B_33_PWR")
	)
	(via
		(at 248.420382 -229.129082)
		(size 0.6604)
		(drill 0.3302)
		(layers "F.Cu" "B.Cu")
		(net "DRIVE_B_33_PWR")
	)
	(segment
		(start 378.70892 -54.887114)
		(end 345.063572 -88.532462)
		(width 0.14605)
		(layer "In2.Cu")
		(net "DRIVE_B_33_PWR")
	)
	(segment
		(start 305.844956 -132.474208)
		(end 305.844956 -177.24247)
		(width 0.14605)
		(layer "In2.Cu")
		(net "DRIVE_B_33_PWR")
	)
	(segment
		(start 408.910028 -54.887114)
		(end 378.70892 -54.887114)
		(width 0.14605)
		(layer "In2.Cu")
		(net "DRIVE_B_33_PWR")
	)
	(segment
		(start 434.98135 -48.582072)
		(end 431.850038 -45.45076)
		(width 0.14605)
		(layer "In2.Cu")
		(net "DRIVE_B_33_PWR")
	)
	(segment
		(start 306.810918 -178.208432)
		(end 307.322474 -178.208432)
		(width 0.14605)
		(layer "In2.Cu")
		(net "DRIVE_B_33_PWR")
	)
	(segment
		(start 326.92213 -111.397034)
		(end 305.844956 -132.474208)
		(width 0.14605)
		(layer "In2.Cu")
		(net "DRIVE_B_33_PWR")
	)
	(segment
		(start 431.850038 -45.45076)
		(end 418.346382 -45.45076)
		(width 0.14605)
		(layer "In2.Cu")
		(net "DRIVE_B_33_PWR")
	)
	(segment
		(start 328.488802 -88.532462)
		(end 326.92213 -90.099134)
		(width 0.14605)
		(layer "In2.Cu")
		(net "DRIVE_B_33_PWR")
	)
	(segment
		(start 418.346382 -45.45076)
		(end 408.910028 -54.887114)
		(width 0.14605)
		(layer "In2.Cu")
		(net "DRIVE_B_33_PWR")
	)
	(segment
		(start 305.844956 -177.24247)
		(end 306.810918 -178.208432)
		(width 0.14605)
		(layer "In2.Cu")
		(net "DRIVE_B_33_PWR")
	)
	(segment
		(start 345.063572 -88.532462)
		(end 328.488802 -88.532462)
		(width 0.14605)
		(layer "In2.Cu")
		(net "DRIVE_B_33_PWR")
	)
	(segment
		(start 326.92213 -90.099134)
		(end 326.92213 -111.397034)
		(width 0.14605)
		(layer "In2.Cu")
		(net "DRIVE_B_33_PWR")
	)
	(segment
		(start 316.473586 -110.623858)
		(end 316.458346 -110.623858)
		(width 0.17145)
		(layer "F.Cu")
		(net "DRIVE_B_33_INS")
	)
	(segment
		(start 308.388512 -118.693692)
		(end 308.388766 -118.693692)
		(width 0.17145)
		(layer "F.Cu")
		(net "DRIVE_B_33_INS")
	)
	(segment
		(start 308.388766 -118.693692)
		(end 308.883812 -118.198646)
		(width 0.17145)
		(layer "F.Cu")
		(net "DRIVE_B_33_INS")
	)
	(segment
		(start 297.761914 -154.288998)
		(end 305.008534 -147.042378)
		(width 0.17145)
		(layer "F.Cu")
		(net "DRIVE_B_33_INS")
	)
	(segment
		(start 305.008534 -147.042378)
		(end 305.008534 -145.065496)
		(width 0.17145)
		(layer "F.Cu")
		(net "DRIVE_B_33_INS")
	)
	(segment
		(start 309.49519 -117.587014)
		(end 309.49519 -117.587268)
		(width 0.17145)
		(layer "F.Cu")
		(net "DRIVE_B_33_INS")
	)
	(segment
		(start 305.285394 -144.788636)
		(end 305.285394 -121.79681)
		(width 0.17145)
		(layer "F.Cu")
		(net "DRIVE_B_33_INS")
	)
	(segment
		(start 218.33586 -167.7289)
		(end 223.534732 -167.7289)
		(width 0.17145)
		(layer "F.Cu")
		(net "DRIVE_B_33_INS")
	)
	(segment
		(start 305.285394 -121.79681)
		(end 308.388512 -118.693692)
		(width 0.17145)
		(layer "F.Cu")
		(net "DRIVE_B_33_INS")
	)
	(segment
		(start 412.8262 -34.544)
		(end 412.8262 -33.6296)
		(width 0.17145)
		(layer "F.Cu")
		(net "DRIVE_B_33_INS")
	)
	(segment
		(start 305.008534 -145.065496)
		(end 305.285394 -144.788636)
		(width 0.17145)
		(layer "F.Cu")
		(net "DRIVE_B_33_INS")
	)
	(segment
		(start 316.458346 -110.623858)
		(end 309.49519 -117.587014)
		(width 0.17145)
		(layer "F.Cu")
		(net "DRIVE_B_33_INS")
	)
	(segment
		(start 223.534732 -167.7289)
		(end 236.974634 -154.288998)
		(width 0.17145)
		(layer "F.Cu")
		(net "DRIVE_B_33_INS")
	)
	(segment
		(start 309.49519 -117.587268)
		(end 308.883812 -118.198646)
		(width 0.17145)
		(layer "F.Cu")
		(net "DRIVE_B_33_INS")
	)
	(segment
		(start 236.974634 -154.288998)
		(end 297.761914 -154.288998)
		(width 0.17145)
		(layer "F.Cu")
		(net "DRIVE_B_33_INS")
	)
	(via
		(at 412.8262 -34.544)
		(size 0.5588)
		(drill 0.3048)
		(layers "F.Cu" "B.Cu")
		(net "DRIVE_B_33_INS")
	)
	(via
		(at 308.883812 -118.198646)
		(size 0.6604)
		(drill 0.3302)
		(layers "F.Cu" "B.Cu")
		(net "DRIVE_B_33_INS")
	)
	(via
		(at 316.473586 -110.623858)
		(size 0.5588)
		(drill 0.3048)
		(layers "F.Cu" "B.Cu")
		(net "DRIVE_B_33_INS")
	)
	(segment
		(start 324.531482 -86.569296)
		(end 323.738748 -87.36203)
		(width 0.14605)
		(layer "In2.Cu")
		(net "DRIVE_B_33_INS")
	)
	(segment
		(start 340.715092 -85.602064)
		(end 339.10778 -85.602064)
		(width 0.14605)
		(layer "In2.Cu")
		(net "DRIVE_B_33_INS")
	)
	(segment
		(start 318.3636 -107.953556)
		(end 318.3636 -108.733844)
		(width 0.14605)
		(layer "In2.Cu")
		(net "DRIVE_B_33_INS")
	)
	(segment
		(start 339.10778 -85.602064)
		(end 338.140548 -86.569296)
		(width 0.14605)
		(layer "In2.Cu")
		(net "DRIVE_B_33_INS")
	)
	(segment
		(start 373.431054 -52.886102)
		(end 340.715092 -85.602064)
		(width 0.14605)
		(layer "In2.Cu")
		(net "DRIVE_B_33_INS")
	)
	(segment
		(start 412.8262 -34.544)
		(end 412.8262 -39.0398)
		(width 0.14605)
		(layer "In2.Cu")
		(net "DRIVE_B_33_INS")
	)
	(segment
		(start 338.140548 -86.569296)
		(end 324.531482 -86.569296)
		(width 0.14605)
		(layer "In2.Cu")
		(net "DRIVE_B_33_INS")
	)
	(segment
		(start 323.738748 -87.36203)
		(end 323.738748 -93.645736)
		(width 0.14605)
		(layer "In2.Cu")
		(net "DRIVE_B_33_INS")
	)
	(segment
		(start 324.648576 -101.66858)
		(end 318.3636 -107.953556)
		(width 0.14605)
		(layer "In2.Cu")
		(net "DRIVE_B_33_INS")
	)
	(segment
		(start 412.8262 -39.0398)
		(end 398.979898 -52.886102)
		(width 0.14605)
		(layer "In2.Cu")
		(net "DRIVE_B_33_INS")
	)
	(segment
		(start 324.648576 -94.555564)
		(end 324.648576 -101.66858)
		(width 0.14605)
		(layer "In2.Cu")
		(net "DRIVE_B_33_INS")
	)
	(segment
		(start 323.738748 -93.645736)
		(end 324.648576 -94.555564)
		(width 0.14605)
		(layer "In2.Cu")
		(net "DRIVE_B_33_INS")
	)
	(segment
		(start 398.979898 -52.886102)
		(end 373.431054 -52.886102)
		(width 0.14605)
		(layer "In2.Cu")
		(net "DRIVE_B_33_INS")
	)
	(segment
		(start 318.3636 -108.733844)
		(end 316.473586 -110.623858)
		(width 0.14605)
		(layer "In2.Cu")
		(net "DRIVE_B_33_INS")
	)
	(via
		(at 288.39414 -118.96852)
		(size 0.5588)
		(drill 0.3048)
		(layers "F.Cu" "B.Cu")
		(net "DRIVE_B_33_ACT")
	)
	(via
		(at 272.866866 -103.441246)
		(size 0.6096)
		(drill 0.3048)
		(layers "F.Cu" "B.Cu")
		(net "DRIVE_B_33_ACT")
	)
	(segment
		(start 230.943404 -79.397606)
		(end 230.95585 -79.410052)
		(width 0.17145)
		(layer "B.Cu")
		(net "DRIVE_B_33_ACT")
	)
	(segment
		(start 235.347256 -84.4042)
		(end 254.4572 -84.4042)
		(width 0.17145)
		(layer "B.Cu")
		(net "DRIVE_B_33_ACT")
	)
	(segment
		(start 229.80015 -78.11135)
		(end 230.943404 -79.254604)
		(width 0.17145)
		(layer "B.Cu")
		(net "DRIVE_B_33_ACT")
	)
	(segment
		(start 230.95585 -79.410052)
		(end 230.95585 -80.012794)
		(width 0.17145)
		(layer "B.Cu")
		(net "DRIVE_B_33_ACT")
	)
	(segment
		(start 288.39414 -118.96852)
		(end 272.866866 -103.441246)
		(width 0.17145)
		(layer "B.Cu")
		(net "DRIVE_B_33_ACT")
	)
	(segment
		(start 272.866866 -102.813866)
		(end 272.866866 -103.441246)
		(width 0.17145)
		(layer "B.Cu")
		(net "DRIVE_B_33_ACT")
	)
	(segment
		(start 230.943404 -79.254604)
		(end 230.943404 -79.397606)
		(width 0.17145)
		(layer "B.Cu")
		(net "DRIVE_B_33_ACT")
	)
	(segment
		(start 254.4572 -84.4042)
		(end 272.866866 -102.813866)
		(width 0.17145)
		(layer "B.Cu")
		(net "DRIVE_B_33_ACT")
	)
	(segment
		(start 229.80015 -77.600048)
		(end 229.80015 -78.11135)
		(width 0.17145)
		(layer "B.Cu")
		(net "DRIVE_B_33_ACT")
	)
	(segment
		(start 230.95585 -80.012794)
		(end 235.347256 -84.4042)
		(width 0.17145)
		(layer "B.Cu")
		(net "DRIVE_B_33_ACT")
	)
	(segment
		(start 282.414726 -179.294536)
		(end 283.053536 -178.655726)
		(width 0.14605)
		(layer "In2.Cu")
		(net "DRIVE_B_33_ACT")
	)
	(segment
		(start 291.029644 -134.775956)
		(end 291.029644 -126.046484)
		(width 0.14605)
		(layer "In2.Cu")
		(net "DRIVE_B_33_ACT")
	)
	(segment
		(start 289.519868 -178.655726)
		(end 291.018214 -177.15738)
		(width 0.14605)
		(layer "In2.Cu")
		(net "DRIVE_B_33_ACT")
	)
	(segment
		(start 288.884868 -123.784868)
		(end 288.884868 -119.459248)
		(width 0.14605)
		(layer "In2.Cu")
		(net "DRIVE_B_33_ACT")
	)
	(segment
		(start 290.899088 -125.799088)
		(end 288.884868 -123.784868)
		(width 0.14605)
		(layer "In2.Cu")
		(net "DRIVE_B_33_ACT")
	)
	(segment
		(start 291.049202 -134.795514)
		(end 291.029644 -134.775956)
		(width 0.14605)
		(layer "In2.Cu")
		(net "DRIVE_B_33_ACT")
	)
	(segment
		(start 291.018214 -145.899378)
		(end 291.049202 -145.86839)
		(width 0.14605)
		(layer "In2.Cu")
		(net "DRIVE_B_33_ACT")
	)
	(segment
		(start 291.029644 -126.046484)
		(end 290.899088 -125.915928)
		(width 0.14605)
		(layer "In2.Cu")
		(net "DRIVE_B_33_ACT")
	)
	(segment
		(start 291.018214 -177.15738)
		(end 291.018214 -145.899378)
		(width 0.14605)
		(layer "In2.Cu")
		(net "DRIVE_B_33_ACT")
	)
	(segment
		(start 288.884868 -119.459248)
		(end 288.39414 -118.96852)
		(width 0.14605)
		(layer "In2.Cu")
		(net "DRIVE_B_33_ACT")
	)
	(segment
		(start 291.049202 -145.86839)
		(end 291.049202 -134.795514)
		(width 0.14605)
		(layer "In2.Cu")
		(net "DRIVE_B_33_ACT")
	)
	(segment
		(start 283.053536 -178.655726)
		(end 289.519868 -178.655726)
		(width 0.14605)
		(layer "In2.Cu")
		(net "DRIVE_B_33_ACT")
	)
	(segment
		(start 281.836622 -179.294536)
		(end 282.414726 -179.294536)
		(width 0.14605)
		(layer "In2.Cu")
		(net "DRIVE_B_33_ACT")
	)
	(segment
		(start 290.899088 -125.915928)
		(end 290.899088 -125.799088)
		(width 0.14605)
		(layer "In2.Cu")
		(net "DRIVE_B_33_ACT")
	)
	(segment
		(start 245.787164 -216.5096)
		(end 246.59336 -217.315796)
		(width 0.17145)
		(layer "F.Cu")
		(net "DRIVE_B_32_PWR")
	)
	(segment
		(start 248.131584 -228.03612)
		(end 248.131838 -228.03612)
		(width 0.17145)
		(layer "F.Cu")
		(net "DRIVE_B_32_PWR")
	)
	(segment
		(start 309.517796 -181.970934)
		(end 309.517796 -203.497434)
		(width 0.17145)
		(layer "F.Cu")
		(net "DRIVE_B_32_PWR")
	)
	(segment
		(start 276.101556 -257.34391)
		(end 250.362212 -231.604566)
		(width 0.17145)
		(layer "F.Cu")
		(net "DRIVE_B_32_PWR")
	)
	(segment
		(start 244.6528 -216.5096)
		(end 245.787164 -216.5096)
		(width 0.17145)
		(layer "F.Cu")
		(net "DRIVE_B_32_PWR")
	)
	(segment
		(start 309.517796 -203.497434)
		(end 303.750218 -209.265012)
		(width 0.17145)
		(layer "F.Cu")
		(net "DRIVE_B_32_PWR")
	)
	(segment
		(start 246.04091 -221.19209)
		(end 246.04091 -225.945446)
		(width 0.17145)
		(layer "F.Cu")
		(net "DRIVE_B_32_PWR")
	)
	(segment
		(start 410.4894 -51.761644)
		(end 410.4894 -21.1709)
		(width 0.17145)
		(layer "F.Cu")
		(net "DRIVE_B_32_PWR")
	)
	(segment
		(start 246.59336 -217.315796)
		(end 246.59336 -220.63964)
		(width 0.17145)
		(layer "F.Cu")
		(net "DRIVE_B_32_PWR")
	)
	(segment
		(start 248.131838 -228.03612)
		(end 249.081798 -228.98608)
		(width 0.17145)
		(layer "F.Cu")
		(net "DRIVE_B_32_PWR")
	)
	(segment
		(start 410.4894 -21.1709)
		(end 399.034 -9.7155)
		(width 0.17145)
		(layer "F.Cu")
		(net "DRIVE_B_32_PWR")
	)
	(segment
		(start 250.362212 -231.604566)
		(end 250.362212 -230.266748)
		(width 0.17145)
		(layer "F.Cu")
		(net "DRIVE_B_32_PWR")
	)
	(segment
		(start 244.26418 -218.70162)
		(end 244.26418 -216.89822)
		(width 0.17145)
		(layer "F.Cu")
		(net "DRIVE_B_32_PWR")
	)
	(segment
		(start 309.785766 -252.934978)
		(end 305.376834 -257.34391)
		(width 0.17145)
		(layer "F.Cu")
		(net "DRIVE_B_32_PWR")
	)
	(segment
		(start 399.034 -9.7155)
		(end 398.145 -9.7155)
		(width 0.17145)
		(layer "F.Cu")
		(net "DRIVE_B_32_PWR")
	)
	(segment
		(start 303.750218 -216.624916)
		(end 309.785766 -222.660464)
		(width 0.17145)
		(layer "F.Cu")
		(net "DRIVE_B_32_PWR")
	)
	(segment
		(start 250.362212 -230.266748)
		(end 249.760994 -229.66553)
		(width 0.17145)
		(layer "F.Cu")
		(net "DRIVE_B_32_PWR")
	)
	(segment
		(start 303.750218 -209.265012)
		(end 303.750218 -216.624916)
		(width 0.17145)
		(layer "F.Cu")
		(net "DRIVE_B_32_PWR")
	)
	(segment
		(start 249.081798 -228.986334)
		(end 249.760994 -229.66553)
		(width 0.17145)
		(layer "F.Cu")
		(net "DRIVE_B_32_PWR")
	)
	(segment
		(start 244.26418 -216.89822)
		(end 244.6528 -216.5096)
		(width 0.17145)
		(layer "F.Cu")
		(net "DRIVE_B_32_PWR")
	)
	(segment
		(start 249.081798 -228.98608)
		(end 249.081798 -228.986334)
		(width 0.17145)
		(layer "F.Cu")
		(net "DRIVE_B_32_PWR")
	)
	(segment
		(start 246.59336 -220.63964)
		(end 246.04091 -221.19209)
		(width 0.17145)
		(layer "F.Cu")
		(net "DRIVE_B_32_PWR")
	)
	(segment
		(start 305.376834 -257.34391)
		(end 276.101556 -257.34391)
		(width 0.17145)
		(layer "F.Cu")
		(net "DRIVE_B_32_PWR")
	)
	(segment
		(start 306.429156 -178.882294)
		(end 309.517796 -181.970934)
		(width 0.17145)
		(layer "F.Cu")
		(net "DRIVE_B_32_PWR")
	)
	(segment
		(start 309.785766 -222.660464)
		(end 309.785766 -252.934978)
		(width 0.17145)
		(layer "F.Cu")
		(net "DRIVE_B_32_PWR")
	)
	(segment
		(start 246.04091 -225.945446)
		(end 248.131584 -228.03612)
		(width 0.17145)
		(layer "F.Cu")
		(net "DRIVE_B_32_PWR")
	)
	(via
		(at 306.429156 -178.882294)
		(size 0.5588)
		(drill 0.3048)
		(layers "F.Cu" "B.Cu")
		(net "DRIVE_B_32_PWR")
	)
	(via
		(at 249.760994 -229.66553)
		(size 0.6604)
		(drill 0.3302)
		(layers "F.Cu" "B.Cu")
		(net "DRIVE_B_32_PWR")
	)
	(via
		(at 410.4894 -51.761644)
		(size 0.5588)
		(drill 0.3048)
		(layers "F.Cu" "B.Cu")
		(net "DRIVE_B_32_PWR")
	)
	(segment
		(start 305.162712 -177.61585)
		(end 306.429156 -178.882294)
		(width 0.14605)
		(layer "In2.Cu")
		(net "DRIVE_B_32_PWR")
	)
	(segment
		(start 326.339708 -89.857834)
		(end 326.339708 -111.155734)
		(width 0.14605)
		(layer "In2.Cu")
		(net "DRIVE_B_32_PWR")
	)
	(segment
		(start 410.4894 -51.761644)
		(end 407.946352 -54.304692)
		(width 0.14605)
		(layer "In2.Cu")
		(net "DRIVE_B_32_PWR")
	)
	(segment
		(start 378.46762 -54.304692)
		(end 344.822272 -87.95004)
		(width 0.14605)
		(layer "In2.Cu")
		(net "DRIVE_B_32_PWR")
	)
	(segment
		(start 305.162712 -132.33273)
		(end 305.162712 -177.61585)
		(width 0.14605)
		(layer "In2.Cu")
		(net "DRIVE_B_32_PWR")
	)
	(segment
		(start 407.946352 -54.304692)
		(end 378.46762 -54.304692)
		(width 0.14605)
		(layer "In2.Cu")
		(net "DRIVE_B_32_PWR")
	)
	(segment
		(start 326.339708 -111.155734)
		(end 305.162712 -132.33273)
		(width 0.14605)
		(layer "In2.Cu")
		(net "DRIVE_B_32_PWR")
	)
	(segment
		(start 344.822272 -87.95004)
		(end 328.247502 -87.95004)
		(width 0.14605)
		(layer "In2.Cu")
		(net "DRIVE_B_32_PWR")
	)
	(segment
		(start 328.247502 -87.95004)
		(end 326.339708 -89.857834)
		(width 0.14605)
		(layer "In2.Cu")
		(net "DRIVE_B_32_PWR")
	)
	(segment
		(start 304.771044 -121.017792)
		(end 313.500516 -112.28832)
		(width 0.17145)
		(layer "F.Cu")
		(net "DRIVE_B_32_INS")
	)
	(segment
		(start 295.790366 -153.556208)
		(end 304.771044 -144.57553)
		(width 0.17145)
		(layer "F.Cu")
		(net "DRIVE_B_32_INS")
	)
	(segment
		(start 221.82455 -167.07866)
		(end 221.885002 -167.139112)
		(width 0.17145)
		(layer "F.Cu")
		(net "DRIVE_B_32_INS")
	)
	(segment
		(start 218.33586 -167.07866)
		(end 221.82455 -167.07866)
		(width 0.17145)
		(layer "F.Cu")
		(net "DRIVE_B_32_INS")
	)
	(segment
		(start 221.885002 -167.139112)
		(end 223.397064 -167.139112)
		(width 0.17145)
		(layer "F.Cu")
		(net "DRIVE_B_32_INS")
	)
	(segment
		(start 317.664592 -108.124244)
		(end 313.500516 -112.28832)
		(width 0.17145)
		(layer "F.Cu")
		(net "DRIVE_B_32_INS")
	)
	(segment
		(start 304.771044 -144.57553)
		(end 304.771044 -121.017792)
		(width 0.17145)
		(layer "F.Cu")
		(net "DRIVE_B_32_INS")
	)
	(segment
		(start 236.979968 -153.556208)
		(end 295.790366 -153.556208)
		(width 0.17145)
		(layer "F.Cu")
		(net "DRIVE_B_32_INS")
	)
	(segment
		(start 381.3302 -34.5694)
		(end 381.3302 -33.6296)
		(width 0.17145)
		(layer "F.Cu")
		(net "DRIVE_B_32_INS")
	)
	(segment
		(start 223.397064 -167.139112)
		(end 236.979968 -153.556208)
		(width 0.17145)
		(layer "F.Cu")
		(net "DRIVE_B_32_INS")
	)
	(via
		(at 313.500516 -112.28832)
		(size 0.6604)
		(drill 0.3302)
		(layers "F.Cu" "B.Cu")
		(net "DRIVE_B_32_INS")
	)
	(via
		(at 381.3302 -34.5694)
		(size 0.5588)
		(drill 0.3048)
		(layers "F.Cu" "B.Cu")
		(net "DRIVE_B_32_INS")
	)
	(via
		(at 317.664592 -108.124244)
		(size 0.5588)
		(drill 0.3048)
		(layers "F.Cu" "B.Cu")
		(net "DRIVE_B_32_INS")
	)
	(segment
		(start 317.731394 -107.966002)
		(end 317.731394 -108.057442)
		(width 0.14605)
		(layer "In2.Cu")
		(net "DRIVE_B_32_INS")
	)
	(segment
		(start 324.349872 -86.131146)
		(end 323.300598 -87.18042)
		(width 0.14605)
		(layer "In2.Cu")
		(net "DRIVE_B_32_INS")
	)
	(segment
		(start 337.958938 -86.131146)
		(end 324.349872 -86.131146)
		(width 0.14605)
		(layer "In2.Cu")
		(net "DRIVE_B_32_INS")
	)
	(segment
		(start 323.300344 -92.494608)
		(end 323.300598 -92.494862)
		(width 0.14605)
		(layer "In2.Cu")
		(net "DRIVE_B_32_INS")
	)
	(segment
		(start 381.3302 -34.5694)
		(end 381.3302 -44.367196)
		(width 0.14605)
		(layer "In2.Cu")
		(net "DRIVE_B_32_INS")
	)
	(segment
		(start 323.300598 -93.827346)
		(end 324.210426 -94.737174)
		(width 0.14605)
		(layer "In2.Cu")
		(net "DRIVE_B_32_INS")
	)
	(segment
		(start 341.497412 -84.199984)
		(end 339.8901 -84.199984)
		(width 0.14605)
		(layer "In2.Cu")
		(net "DRIVE_B_32_INS")
	)
	(segment
		(start 323.300344 -92.131896)
		(end 323.300344 -92.494608)
		(width 0.14605)
		(layer "In2.Cu")
		(net "DRIVE_B_32_INS")
	)
	(segment
		(start 323.300598 -92.494862)
		(end 323.300598 -93.827346)
		(width 0.14605)
		(layer "In2.Cu")
		(net "DRIVE_B_32_INS")
	)
	(segment
		(start 381.3302 -44.367196)
		(end 341.497412 -84.199984)
		(width 0.14605)
		(layer "In2.Cu")
		(net "DRIVE_B_32_INS")
	)
	(segment
		(start 323.300598 -87.18042)
		(end 323.300598 -92.131642)
		(width 0.14605)
		(layer "In2.Cu")
		(net "DRIVE_B_32_INS")
	)
	(segment
		(start 339.8901 -84.199984)
		(end 337.958938 -86.131146)
		(width 0.14605)
		(layer "In2.Cu")
		(net "DRIVE_B_32_INS")
	)
	(segment
		(start 324.210426 -101.48697)
		(end 317.731394 -107.966002)
		(width 0.14605)
		(layer "In2.Cu")
		(net "DRIVE_B_32_INS")
	)
	(segment
		(start 323.300598 -92.131642)
		(end 323.300344 -92.131896)
		(width 0.14605)
		(layer "In2.Cu")
		(net "DRIVE_B_32_INS")
	)
	(segment
		(start 324.210426 -94.737174)
		(end 324.210426 -101.48697)
		(width 0.14605)
		(layer "In2.Cu")
		(net "DRIVE_B_32_INS")
	)
	(segment
		(start 317.731394 -108.057442)
		(end 317.664592 -108.124244)
		(width 0.14605)
		(layer "In2.Cu")
		(net "DRIVE_B_32_INS")
	)
	(segment
		(start 257.814572 -108.237274)
		(end 258.445 -108.237274)
		(width 0.17145)
		(layer "F.Cu")
		(net "DRIVE_B_32_ACT")
	)
	(segment
		(start 229.830376 -81.275428)
		(end 230.852726 -81.275428)
		(width 0.17145)
		(layer "F.Cu")
		(net "DRIVE_B_32_ACT")
	)
	(segment
		(start 288.779712 -119.486172)
		(end 289.38982 -120.09628)
		(width 0.17145)
		(layer "F.Cu")
		(net "DRIVE_B_32_ACT")
	)
	(segment
		(start 284.080204 -119.027448)
		(end 287.145476 -119.027448)
		(width 0.17145)
		(layer "F.Cu")
		(net "DRIVE_B_32_ACT")
	)
	(segment
		(start 287.6042 -119.486172)
		(end 288.779712 -119.486172)
		(width 0.17145)
		(layer "F.Cu")
		(net "DRIVE_B_32_ACT")
	)
	(segment
		(start 230.852726 -81.275428)
		(end 257.814572 -108.237274)
		(width 0.17145)
		(layer "F.Cu")
		(net "DRIVE_B_32_ACT")
	)
	(segment
		(start 229.80015 -76.65085)
		(end 229.163372 -77.287628)
		(width 0.17145)
		(layer "F.Cu")
		(net "DRIVE_B_32_ACT")
	)
	(segment
		(start 287.145476 -119.027448)
		(end 287.6042 -119.486172)
		(width 0.17145)
		(layer "F.Cu")
		(net "DRIVE_B_32_ACT")
	)
	(segment
		(start 229.163372 -80.608424)
		(end 229.830376 -81.275428)
		(width 0.17145)
		(layer "F.Cu")
		(net "DRIVE_B_32_ACT")
	)
	(segment
		(start 258.445 -108.237274)
		(end 266.733274 -108.237274)
		(width 0.17145)
		(layer "F.Cu")
		(net "DRIVE_B_32_ACT")
	)
	(segment
		(start 229.80015 -76.499974)
		(end 229.80015 -76.65085)
		(width 0.17145)
		(layer "F.Cu")
		(net "DRIVE_B_32_ACT")
	)
	(segment
		(start 266.733274 -108.237274)
		(end 270.891 -112.395)
		(width 0.17145)
		(layer "F.Cu")
		(net "DRIVE_B_32_ACT")
	)
	(segment
		(start 277.447756 -112.395)
		(end 284.080204 -119.027448)
		(width 0.17145)
		(layer "F.Cu")
		(net "DRIVE_B_32_ACT")
	)
	(segment
		(start 229.163372 -77.287628)
		(end 229.163372 -80.608424)
		(width 0.17145)
		(layer "F.Cu")
		(net "DRIVE_B_32_ACT")
	)
	(segment
		(start 270.891 -112.395)
		(end 277.447756 -112.395)
		(width 0.17145)
		(layer "F.Cu")
		(net "DRIVE_B_32_ACT")
	)
	(via
		(at 289.38982 -120.09628)
		(size 0.5588)
		(drill 0.3048)
		(layers "F.Cu" "B.Cu")
		(net "DRIVE_B_32_ACT")
	)
	(via
		(at 258.445 -108.237274)
		(size 0.6604)
		(drill 0.3302)
		(layers "F.Cu" "B.Cu")
		(net "DRIVE_B_32_ACT")
	)
	(segment
		(start 291.456364 -146.080988)
		(end 291.487352 -146.05)
		(width 0.14605)
		(layer "In2.Cu")
		(net "DRIVE_B_32_ACT")
	)
	(segment
		(start 283.87929 -179.937156)
		(end 288.987484 -179.937156)
		(width 0.14605)
		(layer "In2.Cu")
		(net "DRIVE_B_32_ACT")
	)
	(segment
		(start 291.487352 -134.613904)
		(end 291.467794 -134.594346)
		(width 0.14605)
		(layer "In2.Cu")
		(net "DRIVE_B_32_ACT")
	)
	(segment
		(start 288.987484 -179.937156)
		(end 291.456364 -177.468276)
		(width 0.14605)
		(layer "In2.Cu")
		(net "DRIVE_B_32_ACT")
	)
	(segment
		(start 291.487352 -146.05)
		(end 291.487352 -134.613904)
		(width 0.14605)
		(layer "In2.Cu")
		(net "DRIVE_B_32_ACT")
	)
	(segment
		(start 291.337238 -125.617478)
		(end 289.38982 -123.67006)
		(width 0.14605)
		(layer "In2.Cu")
		(net "DRIVE_B_32_ACT")
	)
	(segment
		(start 291.337238 -125.734318)
		(end 291.337238 -125.617478)
		(width 0.14605)
		(layer "In2.Cu")
		(net "DRIVE_B_32_ACT")
	)
	(segment
		(start 283.23667 -179.294536)
		(end 283.87929 -179.937156)
		(width 0.14605)
		(layer "In2.Cu")
		(net "DRIVE_B_32_ACT")
	)
	(segment
		(start 291.467794 -125.864874)
		(end 291.337238 -125.734318)
		(width 0.14605)
		(layer "In2.Cu")
		(net "DRIVE_B_32_ACT")
	)
	(segment
		(start 291.456364 -177.468276)
		(end 291.456364 -146.080988)
		(width 0.14605)
		(layer "In2.Cu")
		(net "DRIVE_B_32_ACT")
	)
	(segment
		(start 291.467794 -134.594346)
		(end 291.467794 -125.864874)
		(width 0.14605)
		(layer "In2.Cu")
		(net "DRIVE_B_32_ACT")
	)
	(segment
		(start 289.38982 -123.67006)
		(end 289.38982 -120.09628)
		(width 0.14605)
		(layer "In2.Cu")
		(net "DRIVE_B_32_ACT")
	)
	(segment
		(start 329.37831 -102.549706)
		(end 308.557676 -123.37034)
		(width 0.17145)
		(layer "F.Cu")
		(net "DRIVE_B_31_PWR")
	)
	(segment
		(start 247.4214 -189.8904)
		(end 242.7732 -189.8904)
		(width 0.17145)
		(layer "F.Cu")
		(net "DRIVE_B_31_PWR")
	)
	(segment
		(start 365.714026 -54.04739)
		(end 350.179386 -54.04739)
		(width 0.17145)
		(layer "F.Cu")
		(net "DRIVE_B_31_PWR")
	)
	(segment
		(start 261.421372 -167.356028)
		(end 255.5748 -173.2026)
		(width 0.17145)
		(layer "F.Cu")
		(net "DRIVE_B_31_PWR")
	)
	(segment
		(start 338.57565 -88.707722)
		(end 329.37831 -97.905062)
		(width 0.17145)
		(layer "F.Cu")
		(net "DRIVE_B_31_PWR")
	)
	(segment
		(start 368.173 -13.1445)
		(end 371.86235 -16.83385)
		(width 0.17145)
		(layer "F.Cu")
		(net "DRIVE_B_31_PWR")
	)
	(segment
		(start 371.86235 -47.899066)
		(end 369.075208 -50.686208)
		(width 0.17145)
		(layer "F.Cu")
		(net "DRIVE_B_31_PWR")
	)
	(segment
		(start 367.284 -13.1445)
		(end 368.173 -13.1445)
		(width 0.17145)
		(layer "F.Cu")
		(net "DRIVE_B_31_PWR")
	)
	(segment
		(start 371.86235 -16.83385)
		(end 371.86235 -47.899066)
		(width 0.17145)
		(layer "F.Cu")
		(net "DRIVE_B_31_PWR")
	)
	(segment
		(start 338.57565 -65.651126)
		(end 338.57565 -88.707722)
		(width 0.17145)
		(layer "F.Cu")
		(net "DRIVE_B_31_PWR")
	)
	(segment
		(start 283.18587 -167.356028)
		(end 261.421372 -167.356028)
		(width 0.17145)
		(layer "F.Cu")
		(net "DRIVE_B_31_PWR")
	)
	(segment
		(start 369.075208 -50.686208)
		(end 365.714026 -54.04739)
		(width 0.17145)
		(layer "F.Cu")
		(net "DRIVE_B_31_PWR")
	)
	(segment
		(start 255.5748 -173.2026)
		(end 255.5748 -181.737)
		(width 0.17145)
		(layer "F.Cu")
		(net "DRIVE_B_31_PWR")
	)
	(segment
		(start 308.557676 -150.446994)
		(end 301.102268 -157.902402)
		(width 0.17145)
		(layer "F.Cu")
		(net "DRIVE_B_31_PWR")
	)
	(segment
		(start 329.37831 -97.905062)
		(end 329.37831 -102.549706)
		(width 0.17145)
		(layer "F.Cu")
		(net "DRIVE_B_31_PWR")
	)
	(segment
		(start 236.982 -197.697344)
		(end 236.569504 -198.10984)
		(width 0.17145)
		(layer "F.Cu")
		(net "DRIVE_B_31_PWR")
	)
	(segment
		(start 308.557676 -123.37034)
		(end 308.557676 -150.446994)
		(width 0.17145)
		(layer "F.Cu")
		(net "DRIVE_B_31_PWR")
	)
	(segment
		(start 242.7732 -189.8904)
		(end 236.982 -195.6816)
		(width 0.17145)
		(layer "F.Cu")
		(net "DRIVE_B_31_PWR")
	)
	(segment
		(start 236.569504 -198.10984)
		(end 235.0516 -198.10984)
		(width 0.17145)
		(layer "F.Cu")
		(net "DRIVE_B_31_PWR")
	)
	(segment
		(start 301.102268 -157.902402)
		(end 287.518602 -157.902402)
		(width 0.17145)
		(layer "F.Cu")
		(net "DRIVE_B_31_PWR")
	)
	(segment
		(start 350.179386 -54.04739)
		(end 338.57565 -65.651126)
		(width 0.17145)
		(layer "F.Cu")
		(net "DRIVE_B_31_PWR")
	)
	(segment
		(start 255.5748 -181.737)
		(end 247.4214 -189.8904)
		(width 0.17145)
		(layer "F.Cu")
		(net "DRIVE_B_31_PWR")
	)
	(segment
		(start 287.518602 -157.902402)
		(end 286.893 -157.2768)
		(width 0.17145)
		(layer "F.Cu")
		(net "DRIVE_B_31_PWR")
	)
	(segment
		(start 236.982 -195.6816)
		(end 236.982 -197.697344)
		(width 0.17145)
		(layer "F.Cu")
		(net "DRIVE_B_31_PWR")
	)
	(via
		(at 369.075208 -50.686208)
		(size 0.6604)
		(drill 0.3302)
		(layers "F.Cu" "B.Cu")
		(net "DRIVE_B_31_PWR")
	)
	(via
		(at 283.18587 -167.356028)
		(size 0.5588)
		(drill 0.3048)
		(layers "F.Cu" "B.Cu")
		(net "DRIVE_B_31_PWR")
	)
	(via
		(at 286.893 -157.2768)
		(size 0.5588)
		(drill 0.3048)
		(layers "F.Cu" "B.Cu")
		(net "DRIVE_B_31_PWR")
	)
	(segment
		(start 286.893 -157.2768)
		(end 286.893 -163.652708)
		(width 0.14605)
		(layer "In5.Cu")
		(net "DRIVE_B_31_PWR")
	)
	(segment
		(start 286.893 -163.652708)
		(end 283.18968 -167.356028)
		(width 0.14605)
		(layer "In5.Cu")
		(net "DRIVE_B_31_PWR")
	)
	(segment
		(start 283.18968 -167.356028)
		(end 283.18587 -167.356028)
		(width 0.14605)
		(layer "In5.Cu")
		(net "DRIVE_B_31_PWR")
	)
	(segment
		(start 227.6602 -160.9598)
		(end 226.6696 -160.9598)
		(width 0.17145)
		(layer "F.Cu")
		(net "DRIVE_B_31_INS")
	)
	(segment
		(start 210.587844 -208.32064)
		(end 210.028536 -208.879948)
		(width 0.17145)
		(layer "F.Cu")
		(net "DRIVE_B_31_INS")
	)
	(segment
		(start 236.254798 -152.365202)
		(end 295.99001 -152.365202)
		(width 0.17145)
		(layer "F.Cu")
		(net "DRIVE_B_31_INS")
	)
	(segment
		(start 316.979046 -107.521248)
		(end 316.979046 -107.518708)
		(width 0.17145)
		(layer "F.Cu")
		(net "DRIVE_B_31_INS")
	)
	(segment
		(start 204.815948 -208.879948)
		(end 203.4794 -207.5434)
		(width 0.17145)
		(layer "F.Cu")
		(net "DRIVE_B_31_INS")
	)
	(segment
		(start 213.0806 -208.32064)
		(end 210.587844 -208.32064)
		(width 0.17145)
		(layer "F.Cu")
		(net "DRIVE_B_31_INS")
	)
	(segment
		(start 228.263704 -160.356296)
		(end 236.254798 -152.365202)
		(width 0.17145)
		(layer "F.Cu")
		(net "DRIVE_B_31_INS")
	)
	(segment
		(start 203.4794 -207.5434)
		(end 203.4794 -195.7578)
		(width 0.17145)
		(layer "F.Cu")
		(net "DRIVE_B_31_INS")
	)
	(segment
		(start 303.39411 -121.106184)
		(end 316.979046 -107.521248)
		(width 0.17145)
		(layer "F.Cu")
		(net "DRIVE_B_31_INS")
	)
	(segment
		(start 295.99001 -152.365202)
		(end 303.39411 -144.961102)
		(width 0.17145)
		(layer "F.Cu")
		(net "DRIVE_B_31_INS")
	)
	(segment
		(start 203.4794 -195.7578)
		(end 202.0062 -194.2846)
		(width 0.17145)
		(layer "F.Cu")
		(net "DRIVE_B_31_INS")
	)
	(segment
		(start 349.6818 -33.6296)
		(end 349.6818 -34.544)
		(width 0.17145)
		(layer "F.Cu")
		(net "DRIVE_B_31_INS")
	)
	(segment
		(start 303.39411 -144.961102)
		(end 303.39411 -121.106184)
		(width 0.17145)
		(layer "F.Cu")
		(net "DRIVE_B_31_INS")
	)
	(segment
		(start 210.028536 -208.879948)
		(end 204.815948 -208.879948)
		(width 0.17145)
		(layer "F.Cu")
		(net "DRIVE_B_31_INS")
	)
	(segment
		(start 228.263704 -160.356296)
		(end 227.6602 -160.9598)
		(width 0.17145)
		(layer "F.Cu")
		(net "DRIVE_B_31_INS")
	)
	(via
		(at 202.81265 -162.617658)
		(size 0.5588)
		(drill 0.3048)
		(layers "F.Cu" "B.Cu")
		(net "DRIVE_B_31_INS")
	)
	(via
		(at 202.0062 -194.2846)
		(size 0.5588)
		(drill 0.3048)
		(layers "F.Cu" "B.Cu")
		(net "DRIVE_B_31_INS")
	)
	(via
		(at 226.6696 -160.9598)
		(size 0.5588)
		(drill 0.3048)
		(layers "F.Cu" "B.Cu")
		(net "DRIVE_B_31_INS")
	)
	(via
		(at 349.6818 -34.544)
		(size 0.5588)
		(drill 0.3048)
		(layers "F.Cu" "B.Cu")
		(net "DRIVE_B_31_INS")
	)
	(via
		(at 316.979046 -107.518708)
		(size 0.5588)
		(drill 0.3048)
		(layers "F.Cu" "B.Cu")
		(net "DRIVE_B_31_INS")
	)
	(via
		(at 228.263704 -160.356296)
		(size 0.6604)
		(drill 0.3302)
		(layers "F.Cu" "B.Cu")
		(net "DRIVE_B_31_INS")
	)
	(segment
		(start 337.777328 -85.692996)
		(end 351.663 -71.807324)
		(width 0.14605)
		(layer "In2.Cu")
		(net "DRIVE_B_31_INS")
	)
	(segment
		(start 322.862448 -94.008956)
		(end 322.862448 -92.676472)
		(width 0.14605)
		(layer "In2.Cu")
		(net "DRIVE_B_31_INS")
	)
	(segment
		(start 202.746356 -162.683952)
		(end 202.746356 -169.883582)
		(width 0.14605)
		(layer "In2.Cu")
		(net "DRIVE_B_31_INS")
	)
	(segment
		(start 322.862194 -92.676218)
		(end 322.862194 -86.999064)
		(width 0.14605)
		(layer "In2.Cu")
		(net "DRIVE_B_31_INS")
	)
	(segment
		(start 320.955162 -103.542592)
		(end 320.955162 -102.515162)
		(width 0.14605)
		(layer "In2.Cu")
		(net "DRIVE_B_31_INS")
	)
	(segment
		(start 201.918824 -194.197224)
		(end 202.0062 -194.2846)
		(width 0.14605)
		(layer "In2.Cu")
		(net "DRIVE_B_31_INS")
	)
	(segment
		(start 203.177902 -170.315128)
		(end 203.177902 -190.82258)
		(width 0.14605)
		(layer "In2.Cu")
		(net "DRIVE_B_31_INS")
	)
	(segment
		(start 323.772276 -94.918784)
		(end 322.862448 -94.008956)
		(width 0.14605)
		(layer "In2.Cu")
		(net "DRIVE_B_31_INS")
	)
	(segment
		(start 322.862448 -92.676472)
		(end 322.862194 -92.676218)
		(width 0.14605)
		(layer "In2.Cu")
		(net "DRIVE_B_31_INS")
	)
	(segment
		(start 316.979046 -107.518708)
		(end 320.955162 -103.542592)
		(width 0.14605)
		(layer "In2.Cu")
		(net "DRIVE_B_31_INS")
	)
	(segment
		(start 323.772276 -99.698048)
		(end 323.772276 -94.918784)
		(width 0.14605)
		(layer "In2.Cu")
		(net "DRIVE_B_31_INS")
	)
	(segment
		(start 351.663 -36.5252)
		(end 349.6818 -34.544)
		(width 0.14605)
		(layer "In2.Cu")
		(net "DRIVE_B_31_INS")
	)
	(segment
		(start 203.177902 -190.82258)
		(end 201.918824 -192.081658)
		(width 0.14605)
		(layer "In2.Cu")
		(net "DRIVE_B_31_INS")
	)
	(segment
		(start 202.746356 -169.883582)
		(end 203.177902 -170.315128)
		(width 0.14605)
		(layer "In2.Cu")
		(net "DRIVE_B_31_INS")
	)
	(segment
		(start 351.663 -71.807324)
		(end 351.663 -36.5252)
		(width 0.14605)
		(layer "In2.Cu")
		(net "DRIVE_B_31_INS")
	)
	(segment
		(start 322.862194 -86.999064)
		(end 324.168262 -85.692996)
		(width 0.14605)
		(layer "In2.Cu")
		(net "DRIVE_B_31_INS")
	)
	(segment
		(start 201.918824 -192.081658)
		(end 201.918824 -194.197224)
		(width 0.14605)
		(layer "In2.Cu")
		(net "DRIVE_B_31_INS")
	)
	(segment
		(start 202.81265 -162.617658)
		(end 202.746356 -162.683952)
		(width 0.14605)
		(layer "In2.Cu")
		(net "DRIVE_B_31_INS")
	)
	(segment
		(start 320.955162 -102.515162)
		(end 323.772276 -99.698048)
		(width 0.14605)
		(layer "In2.Cu")
		(net "DRIVE_B_31_INS")
	)
	(segment
		(start 324.168262 -85.692996)
		(end 337.777328 -85.692996)
		(width 0.14605)
		(layer "In2.Cu")
		(net "DRIVE_B_31_INS")
	)
	(segment
		(start 202.81265 -162.617658)
		(end 203.199492 -163.0045)
		(width 0.14605)
		(layer "In5.Cu")
		(net "DRIVE_B_31_INS")
	)
	(segment
		(start 207.74406 -160.9598)
		(end 226.6696 -160.9598)
		(width 0.14605)
		(layer "In5.Cu")
		(net "DRIVE_B_31_INS")
	)
	(segment
		(start 205.69936 -163.0045)
		(end 207.74406 -160.9598)
		(width 0.14605)
		(layer "In5.Cu")
		(net "DRIVE_B_31_INS")
	)
	(segment
		(start 203.199492 -163.0045)
		(end 205.69936 -163.0045)
		(width 0.14605)
		(layer "In5.Cu")
		(net "DRIVE_B_31_INS")
	)
	(via
		(at 259.453126 -99.189032)
		(size 0.6096)
		(drill 0.3048)
		(layers "F.Cu" "B.Cu")
		(net "DRIVE_B_31_ACT")
	)
	(via
		(at 289.45586 -118.96852)
		(size 0.5588)
		(drill 0.3048)
		(layers "F.Cu" "B.Cu")
		(net "DRIVE_B_31_ACT")
	)
	(segment
		(start 229.1588 -80.352138)
		(end 234.301284 -85.494622)
		(width 0.17145)
		(layer "B.Cu")
		(net "DRIVE_B_31_ACT")
	)
	(segment
		(start 252.010164 -91.74607)
		(end 259.453126 -99.189032)
		(width 0.17145)
		(layer "B.Cu")
		(net "DRIVE_B_31_ACT")
	)
	(segment
		(start 229.1588 -76.0222)
		(end 229.1588 -80.352138)
		(width 0.17145)
		(layer "B.Cu")
		(net "DRIVE_B_31_ACT")
	)
	(segment
		(start 248.422414 -91.74607)
		(end 252.010164 -91.74607)
		(width 0.17145)
		(layer "B.Cu")
		(net "DRIVE_B_31_ACT")
	)
	(segment
		(start 229.80015 -75.3999)
		(end 229.7811 -75.3999)
		(width 0.17145)
		(layer "B.Cu")
		(net "DRIVE_B_31_ACT")
	)
	(segment
		(start 259.453126 -99.189032)
		(end 279.167336 -118.903242)
		(width 0.17145)
		(layer "B.Cu")
		(net "DRIVE_B_31_ACT")
	)
	(segment
		(start 234.301284 -85.494622)
		(end 242.170966 -85.494622)
		(width 0.17145)
		(layer "B.Cu")
		(net "DRIVE_B_31_ACT")
	)
	(segment
		(start 285.019242 -118.903242)
		(end 287.0454 -120.9294)
		(width 0.17145)
		(layer "B.Cu")
		(net "DRIVE_B_31_ACT")
	)
	(segment
		(start 289.9156 -119.42826)
		(end 289.45586 -118.96852)
		(width 0.17145)
		(layer "B.Cu")
		(net "DRIVE_B_31_ACT")
	)
	(segment
		(start 242.170966 -85.494622)
		(end 248.422414 -91.74607)
		(width 0.17145)
		(layer "B.Cu")
		(net "DRIVE_B_31_ACT")
	)
	(segment
		(start 289.569144 -120.9294)
		(end 289.911028 -120.587516)
		(width 0.17145)
		(layer "B.Cu")
		(net "DRIVE_B_31_ACT")
	)
	(segment
		(start 229.7811 -75.3999)
		(end 229.1588 -76.0222)
		(width 0.17145)
		(layer "B.Cu")
		(net "DRIVE_B_31_ACT")
	)
	(segment
		(start 289.9156 -119.897652)
		(end 289.9156 -119.42826)
		(width 0.17145)
		(layer "B.Cu")
		(net "DRIVE_B_31_ACT")
	)
	(segment
		(start 287.0454 -120.9294)
		(end 289.569144 -120.9294)
		(width 0.17145)
		(layer "B.Cu")
		(net "DRIVE_B_31_ACT")
	)
	(segment
		(start 279.167336 -118.903242)
		(end 285.019242 -118.903242)
		(width 0.17145)
		(layer "B.Cu")
		(net "DRIVE_B_31_ACT")
	)
	(segment
		(start 289.911028 -119.902224)
		(end 289.9156 -119.897652)
		(width 0.17145)
		(layer "B.Cu")
		(net "DRIVE_B_31_ACT")
	)
	(segment
		(start 289.911028 -120.587516)
		(end 289.911028 -119.902224)
		(width 0.17145)
		(layer "B.Cu")
		(net "DRIVE_B_31_ACT")
	)
	(segment
		(start 291.925502 -134.432294)
		(end 291.905944 -134.412736)
		(width 0.14605)
		(layer "In2.Cu")
		(net "DRIVE_B_31_ACT")
	)
	(segment
		(start 291.775388 -125.552708)
		(end 291.775388 -125.435868)
		(width 0.14605)
		(layer "In2.Cu")
		(net "DRIVE_B_31_ACT")
	)
	(segment
		(start 291.894514 -146.262598)
		(end 291.925502 -146.23161)
		(width 0.14605)
		(layer "In2.Cu")
		(net "DRIVE_B_31_ACT")
	)
	(segment
		(start 289.099244 -180.445156)
		(end 291.894514 -177.649886)
		(width 0.14605)
		(layer "In2.Cu")
		(net "DRIVE_B_31_ACT")
	)
	(segment
		(start 291.905944 -134.412736)
		(end 291.905944 -125.683264)
		(width 0.14605)
		(layer "In2.Cu")
		(net "DRIVE_B_31_ACT")
	)
	(segment
		(start 282.83662 -181.09438)
		(end 283.414724 -181.09438)
		(width 0.14605)
		(layer "In2.Cu")
		(net "DRIVE_B_31_ACT")
	)
	(segment
		(start 284.063948 -180.445156)
		(end 289.099244 -180.445156)
		(width 0.14605)
		(layer "In2.Cu")
		(net "DRIVE_B_31_ACT")
	)
	(segment
		(start 291.925502 -146.23161)
		(end 291.925502 -134.432294)
		(width 0.14605)
		(layer "In2.Cu")
		(net "DRIVE_B_31_ACT")
	)
	(segment
		(start 291.894514 -177.649886)
		(end 291.894514 -146.262598)
		(width 0.14605)
		(layer "In2.Cu")
		(net "DRIVE_B_31_ACT")
	)
	(segment
		(start 283.414724 -181.09438)
		(end 284.063948 -180.445156)
		(width 0.14605)
		(layer "In2.Cu")
		(net "DRIVE_B_31_ACT")
	)
	(segment
		(start 291.775388 -125.435868)
		(end 289.923728 -123.584208)
		(width 0.14605)
		(layer "In2.Cu")
		(net "DRIVE_B_31_ACT")
	)
	(segment
		(start 289.923728 -123.584208)
		(end 289.923728 -119.436388)
		(width 0.14605)
		(layer "In2.Cu")
		(net "DRIVE_B_31_ACT")
	)
	(segment
		(start 289.923728 -119.436388)
		(end 289.45586 -118.96852)
		(width 0.14605)
		(layer "In2.Cu")
		(net "DRIVE_B_31_ACT")
	)
	(segment
		(start 291.905944 -125.683264)
		(end 291.775388 -125.552708)
		(width 0.14605)
		(layer "In2.Cu")
		(net "DRIVE_B_31_ACT")
	)
	(segment
		(start 236.64672 -198.76008)
		(end 237.49635 -197.91045)
		(width 0.17145)
		(layer "F.Cu")
		(net "DRIVE_B_30_PWR")
	)
	(segment
		(start 300.941486 -157.161738)
		(end 288.1884 -157.161738)
		(width 0.17145)
		(layer "F.Cu")
		(net "DRIVE_B_30_PWR")
	)
	(segment
		(start 283.55163 -167.899842)
		(end 284.10027 -167.351202)
		(width 0.17145)
		(layer "F.Cu")
		(net "DRIVE_B_30_PWR")
	)
	(segment
		(start 346.6084 -11.557)
		(end 346.6084 -48.1584)
		(width 0.17145)
		(layer "F.Cu")
		(net "DRIVE_B_30_PWR")
	)
	(segment
		(start 256.08915 -173.75505)
		(end 261.944358 -167.899842)
		(width 0.17145)
		(layer "F.Cu")
		(net "DRIVE_B_30_PWR")
	)
	(segment
		(start 346.6084 -56.6928)
		(end 338.0613 -65.2399)
		(width 0.17145)
		(layer "F.Cu")
		(net "DRIVE_B_30_PWR")
	)
	(segment
		(start 328.86396 -97.691956)
		(end 328.86396 -102.3366)
		(width 0.17145)
		(layer "F.Cu")
		(net "DRIVE_B_30_PWR")
	)
	(segment
		(start 256.08915 -181.950106)
		(end 256.08915 -173.75505)
		(width 0.17145)
		(layer "F.Cu")
		(net "DRIVE_B_30_PWR")
	)
	(segment
		(start 328.86396 -102.3366)
		(end 307.817266 -123.383294)
		(width 0.17145)
		(layer "F.Cu")
		(net "DRIVE_B_30_PWR")
	)
	(segment
		(start 237.49635 -197.91045)
		(end 237.49635 -195.894706)
		(width 0.17145)
		(layer "F.Cu")
		(net "DRIVE_B_30_PWR")
	)
	(segment
		(start 343.6366 -8.5852)
		(end 346.6084 -11.557)
		(width 0.17145)
		(layer "F.Cu")
		(net "DRIVE_B_30_PWR")
	)
	(segment
		(start 338.0613 -65.2399)
		(end 338.0613 -88.494616)
		(width 0.17145)
		(layer "F.Cu")
		(net "DRIVE_B_30_PWR")
	)
	(segment
		(start 261.944358 -167.899842)
		(end 283.55163 -167.899842)
		(width 0.17145)
		(layer "F.Cu")
		(net "DRIVE_B_30_PWR")
	)
	(segment
		(start 338.0613 -88.494616)
		(end 328.86396 -97.691956)
		(width 0.17145)
		(layer "F.Cu")
		(net "DRIVE_B_30_PWR")
	)
	(segment
		(start 247.634506 -190.40475)
		(end 256.08915 -181.950106)
		(width 0.17145)
		(layer "F.Cu")
		(net "DRIVE_B_30_PWR")
	)
	(segment
		(start 334.772 -9.7155)
		(end 335.9023 -8.5852)
		(width 0.17145)
		(layer "F.Cu")
		(net "DRIVE_B_30_PWR")
	)
	(segment
		(start 307.817266 -150.285958)
		(end 300.941486 -157.161738)
		(width 0.17145)
		(layer "F.Cu")
		(net "DRIVE_B_30_PWR")
	)
	(segment
		(start 237.49635 -195.894706)
		(end 242.986306 -190.40475)
		(width 0.17145)
		(layer "F.Cu")
		(net "DRIVE_B_30_PWR")
	)
	(segment
		(start 335.9023 -8.5852)
		(end 343.6366 -8.5852)
		(width 0.17145)
		(layer "F.Cu")
		(net "DRIVE_B_30_PWR")
	)
	(segment
		(start 235.0516 -198.76008)
		(end 236.64672 -198.76008)
		(width 0.17145)
		(layer "F.Cu")
		(net "DRIVE_B_30_PWR")
	)
	(segment
		(start 346.6084 -48.1584)
		(end 346.6084 -56.6928)
		(width 0.17145)
		(layer "F.Cu")
		(net "DRIVE_B_30_PWR")
	)
	(segment
		(start 307.817266 -123.383294)
		(end 307.817266 -150.285958)
		(width 0.17145)
		(layer "F.Cu")
		(net "DRIVE_B_30_PWR")
	)
	(segment
		(start 242.986306 -190.40475)
		(end 247.634506 -190.40475)
		(width 0.17145)
		(layer "F.Cu")
		(net "DRIVE_B_30_PWR")
	)
	(via
		(at 288.1884 -157.161738)
		(size 0.5588)
		(drill 0.3048)
		(layers "F.Cu" "B.Cu")
		(net "DRIVE_B_30_PWR")
	)
	(via
		(at 284.10027 -167.351202)
		(size 0.5588)
		(drill 0.3048)
		(layers "F.Cu" "B.Cu")
		(net "DRIVE_B_30_PWR")
	)
	(via
		(at 346.6084 -48.1584)
		(size 0.6604)
		(drill 0.3302)
		(layers "F.Cu" "B.Cu")
		(net "DRIVE_B_30_PWR")
	)
	(segment
		(start 284.10027 -167.351202)
		(end 288.1884 -163.263072)
		(width 0.14605)
		(layer "In5.Cu")
		(net "DRIVE_B_30_PWR")
	)
	(segment
		(start 288.1884 -163.263072)
		(end 288.1884 -157.161738)
		(width 0.14605)
		(layer "In5.Cu")
		(net "DRIVE_B_30_PWR")
	)
	(segment
		(start 233.393234 -151.42337)
		(end 226.667314 -158.14929)
		(width 0.17145)
		(layer "F.Cu")
		(net "DRIVE_B_30_INS")
	)
	(segment
		(start 202.96505 -207.756506)
		(end 202.96505 -196.10705)
		(width 0.17145)
		(layer "F.Cu")
		(net "DRIVE_B_30_INS")
	)
	(segment
		(start 202.96505 -196.10705)
		(end 201.041 -194.183)
		(width 0.17145)
		(layer "F.Cu")
		(net "DRIVE_B_30_INS")
	)
	(segment
		(start 210.66506 -208.97088)
		(end 210.241642 -209.394298)
		(width 0.17145)
		(layer "F.Cu")
		(net "DRIVE_B_30_INS")
	)
	(segment
		(start 302.87976 -144.51584)
		(end 295.97223 -151.42337)
		(width 0.17145)
		(layer "F.Cu")
		(net "DRIVE_B_30_INS")
	)
	(segment
		(start 295.97223 -151.42337)
		(end 233.393234 -151.42337)
		(width 0.17145)
		(layer "F.Cu")
		(net "DRIVE_B_30_INS")
	)
	(segment
		(start 210.241642 -209.394298)
		(end 204.602842 -209.394298)
		(width 0.17145)
		(layer "F.Cu")
		(net "DRIVE_B_30_INS")
	)
	(segment
		(start 316.374018 -106.832908)
		(end 302.87976 -120.327166)
		(width 0.17145)
		(layer "F.Cu")
		(net "DRIVE_B_30_INS")
	)
	(segment
		(start 226.667314 -158.14929)
		(end 224.739454 -160.07715)
		(width 0.17145)
		(layer "F.Cu")
		(net "DRIVE_B_30_INS")
	)
	(segment
		(start 204.602842 -209.394298)
		(end 202.96505 -207.756506)
		(width 0.17145)
		(layer "F.Cu")
		(net "DRIVE_B_30_INS")
	)
	(segment
		(start 318.262 -33.6296)
		(end 319.2272 -33.6296)
		(width 0.17145)
		(layer "F.Cu")
		(net "DRIVE_B_30_INS")
	)
	(segment
		(start 213.0806 -208.97088)
		(end 210.66506 -208.97088)
		(width 0.17145)
		(layer "F.Cu")
		(net "DRIVE_B_30_INS")
	)
	(segment
		(start 302.87976 -120.327166)
		(end 302.87976 -144.51584)
		(width 0.17145)
		(layer "F.Cu")
		(net "DRIVE_B_30_INS")
	)
	(via
		(at 319.2272 -33.6296)
		(size 0.5588)
		(drill 0.3048)
		(layers "F.Cu" "B.Cu")
		(net "DRIVE_B_30_INS")
	)
	(via
		(at 226.667314 -158.14929)
		(size 0.6604)
		(drill 0.3302)
		(layers "F.Cu" "B.Cu")
		(net "DRIVE_B_30_INS")
	)
	(via
		(at 201.900282 -162.555936)
		(size 0.5588)
		(drill 0.3048)
		(layers "F.Cu" "B.Cu")
		(net "DRIVE_B_30_INS")
	)
	(via
		(at 201.041 -194.183)
		(size 0.5588)
		(drill 0.3048)
		(layers "F.Cu" "B.Cu")
		(net "DRIVE_B_30_INS")
	)
	(via
		(at 316.374018 -106.832908)
		(size 0.5588)
		(drill 0.3048)
		(layers "F.Cu" "B.Cu")
		(net "DRIVE_B_30_INS")
	)
	(via
		(at 224.739454 -160.07715)
		(size 0.5588)
		(drill 0.3048)
		(layers "F.Cu" "B.Cu")
		(net "DRIVE_B_30_INS")
	)
	(segment
		(start 319.757298 -101.654102)
		(end 322.802758 -98.608642)
		(width 0.14605)
		(layer "In2.Cu")
		(net "DRIVE_B_30_INS")
	)
	(segment
		(start 322.424298 -94.190566)
		(end 322.424298 -92.858082)
		(width 0.14605)
		(layer "In2.Cu")
		(net "DRIVE_B_30_INS")
	)
	(segment
		(start 322.802758 -94.569026)
		(end 322.424298 -94.190566)
		(width 0.14605)
		(layer "In2.Cu")
		(net "DRIVE_B_30_INS")
	)
	(segment
		(start 319.757298 -103.449628)
		(end 319.757298 -101.654102)
		(width 0.14605)
		(layer "In2.Cu")
		(net "DRIVE_B_30_INS")
	)
	(segment
		(start 201.900282 -162.555936)
		(end 202.308206 -162.96386)
		(width 0.14605)
		(layer "In2.Cu")
		(net "DRIVE_B_30_INS")
	)
	(segment
		(start 322.802758 -86.43874)
		(end 322.802758 -57.380886)
		(width 0.14605)
		(layer "In2.Cu")
		(net "DRIVE_B_30_INS")
	)
	(segment
		(start 322.42379 -92.857574)
		(end 322.42379 -92.494862)
		(width 0.14605)
		(layer "In2.Cu")
		(net "DRIVE_B_30_INS")
	)
	(segment
		(start 202.308206 -170.065192)
		(end 202.739752 -170.496738)
		(width 0.14605)
		(layer "In2.Cu")
		(net "DRIVE_B_30_INS")
	)
	(segment
		(start 322.424298 -92.858082)
		(end 322.42379 -92.857574)
		(width 0.14605)
		(layer "In2.Cu")
		(net "DRIVE_B_30_INS")
	)
	(segment
		(start 322.802758 -98.608642)
		(end 322.802758 -94.569026)
		(width 0.14605)
		(layer "In2.Cu")
		(net "DRIVE_B_30_INS")
	)
	(segment
		(start 202.739752 -190.64097)
		(end 201.480674 -191.900048)
		(width 0.14605)
		(layer "In2.Cu")
		(net "DRIVE_B_30_INS")
	)
	(segment
		(start 202.739752 -170.496738)
		(end 202.739752 -190.64097)
		(width 0.14605)
		(layer "In2.Cu")
		(net "DRIVE_B_30_INS")
	)
	(segment
		(start 322.802758 -57.380886)
		(end 319.2272 -53.805328)
		(width 0.14605)
		(layer "In2.Cu")
		(net "DRIVE_B_30_INS")
	)
	(segment
		(start 201.480674 -191.900048)
		(end 201.480674 -193.743326)
		(width 0.14605)
		(layer "In2.Cu")
		(net "DRIVE_B_30_INS")
	)
	(segment
		(start 322.42379 -92.494862)
		(end 322.424044 -92.494608)
		(width 0.14605)
		(layer "In2.Cu")
		(net "DRIVE_B_30_INS")
	)
	(segment
		(start 316.374018 -106.832908)
		(end 319.757298 -103.449628)
		(width 0.14605)
		(layer "In2.Cu")
		(net "DRIVE_B_30_INS")
	)
	(segment
		(start 322.424044 -86.817454)
		(end 322.802758 -86.43874)
		(width 0.14605)
		(layer "In2.Cu")
		(net "DRIVE_B_30_INS")
	)
	(segment
		(start 322.424044 -92.494608)
		(end 322.424044 -86.817454)
		(width 0.14605)
		(layer "In2.Cu")
		(net "DRIVE_B_30_INS")
	)
	(segment
		(start 202.308206 -162.96386)
		(end 202.308206 -170.065192)
		(width 0.14605)
		(layer "In2.Cu")
		(net "DRIVE_B_30_INS")
	)
	(segment
		(start 319.2272 -53.805328)
		(end 319.2272 -33.6296)
		(width 0.14605)
		(layer "In2.Cu")
		(net "DRIVE_B_30_INS")
	)
	(segment
		(start 201.480674 -193.743326)
		(end 201.041 -194.183)
		(width 0.14605)
		(layer "In2.Cu")
		(net "DRIVE_B_30_INS")
	)
	(segment
		(start 208.12252 -159.8676)
		(end 221.59722 -159.8676)
		(width 0.14605)
		(layer "In5.Cu")
		(net "DRIVE_B_30_INS")
	)
	(segment
		(start 221.80677 -160.07715)
		(end 224.739454 -160.07715)
		(width 0.14605)
		(layer "In5.Cu")
		(net "DRIVE_B_30_INS")
	)
	(segment
		(start 201.900282 -162.555936)
		(end 201.901044 -162.555936)
		(width 0.14605)
		(layer "In5.Cu")
		(net "DRIVE_B_30_INS")
	)
	(segment
		(start 201.901044 -162.555936)
		(end 202.344274 -162.112706)
		(width 0.14605)
		(layer "In5.Cu")
		(net "DRIVE_B_30_INS")
	)
	(segment
		(start 203.087986 -162.179)
		(end 205.81112 -162.179)
		(width 0.14605)
		(layer "In5.Cu")
		(net "DRIVE_B_30_INS")
	)
	(segment
		(start 205.81112 -162.179)
		(end 208.12252 -159.8676)
		(width 0.14605)
		(layer "In5.Cu")
		(net "DRIVE_B_30_INS")
	)
	(segment
		(start 221.59722 -159.8676)
		(end 221.80677 -160.07715)
		(width 0.14605)
		(layer "In5.Cu")
		(net "DRIVE_B_30_INS")
	)
	(segment
		(start 202.344274 -162.112706)
		(end 203.021692 -162.112706)
		(width 0.14605)
		(layer "In5.Cu")
		(net "DRIVE_B_30_INS")
	)
	(segment
		(start 203.021692 -162.112706)
		(end 203.087986 -162.179)
		(width 0.14605)
		(layer "In5.Cu")
		(net "DRIVE_B_30_INS")
	)
	(via
		(at 290.42868 -120.1166)
		(size 0.5588)
		(drill 0.3048)
		(layers "F.Cu" "B.Cu")
		(net "DRIVE_B_30_ACT")
	)
	(via
		(at 272.140934 -112.758728)
		(size 0.6096)
		(drill 0.3048)
		(layers "F.Cu" "B.Cu")
		(net "DRIVE_B_30_ACT")
	)
	(segment
		(start 228.63175 -80.552544)
		(end 234.088178 -86.008972)
		(width 0.17145)
		(layer "B.Cu")
		(net "DRIVE_B_30_ACT")
	)
	(segment
		(start 229.80015 -73.999852)
		(end 229.80015 -74.560176)
		(width 0.17145)
		(layer "B.Cu")
		(net "DRIVE_B_30_ACT")
	)
	(segment
		(start 228.63175 -75.728576)
		(end 228.63175 -80.552544)
		(width 0.17145)
		(layer "B.Cu")
		(net "DRIVE_B_30_ACT")
	)
	(segment
		(start 229.80015 -74.560176)
		(end 228.63175 -75.728576)
		(width 0.17145)
		(layer "B.Cu")
		(net "DRIVE_B_30_ACT")
	)
	(segment
		(start 248.209308 -92.26042)
		(end 251.642626 -92.26042)
		(width 0.17145)
		(layer "B.Cu")
		(net "DRIVE_B_30_ACT")
	)
	(segment
		(start 289.88385 -121.44375)
		(end 290.42868 -120.89892)
		(width 0.17145)
		(layer "B.Cu")
		(net "DRIVE_B_30_ACT")
	)
	(segment
		(start 278.844248 -119.462042)
		(end 284.562042 -119.462042)
		(width 0.17145)
		(layer "B.Cu")
		(net "DRIVE_B_30_ACT")
	)
	(segment
		(start 290.42868 -120.89892)
		(end 290.42868 -120.1166)
		(width 0.17145)
		(layer "B.Cu")
		(net "DRIVE_B_30_ACT")
	)
	(segment
		(start 241.95786 -86.008972)
		(end 248.209308 -92.26042)
		(width 0.17145)
		(layer "B.Cu")
		(net "DRIVE_B_30_ACT")
	)
	(segment
		(start 286.54375 -121.44375)
		(end 289.88385 -121.44375)
		(width 0.17145)
		(layer "B.Cu")
		(net "DRIVE_B_30_ACT")
	)
	(segment
		(start 234.088178 -86.008972)
		(end 241.95786 -86.008972)
		(width 0.17145)
		(layer "B.Cu")
		(net "DRIVE_B_30_ACT")
	)
	(segment
		(start 284.562042 -119.462042)
		(end 286.54375 -121.44375)
		(width 0.17145)
		(layer "B.Cu")
		(net "DRIVE_B_30_ACT")
	)
	(segment
		(start 251.642626 -92.26042)
		(end 272.140934 -112.758728)
		(width 0.17145)
		(layer "B.Cu")
		(net "DRIVE_B_30_ACT")
	)
	(segment
		(start 272.140934 -112.758728)
		(end 278.844248 -119.462042)
		(width 0.17145)
		(layer "B.Cu")
		(net "DRIVE_B_30_ACT")
	)
	(segment
		(start 292.363652 -146.41322)
		(end 292.363652 -134.250684)
		(width 0.14605)
		(layer "In2.Cu")
		(net "DRIVE_B_30_ACT")
	)
	(segment
		(start 284.885384 -181.743096)
		(end 289.174174 -181.743096)
		(width 0.14605)
		(layer "In2.Cu")
		(net "DRIVE_B_30_ACT")
	)
	(segment
		(start 292.332664 -146.444208)
		(end 292.363652 -146.41322)
		(width 0.14605)
		(layer "In2.Cu")
		(net "DRIVE_B_30_ACT")
	)
	(segment
		(start 292.344094 -134.231126)
		(end 292.344094 -125.501654)
		(width 0.14605)
		(layer "In2.Cu")
		(net "DRIVE_B_30_ACT")
	)
	(segment
		(start 284.236668 -181.09438)
		(end 284.885384 -181.743096)
		(width 0.14605)
		(layer "In2.Cu")
		(net "DRIVE_B_30_ACT")
	)
	(segment
		(start 292.339268 -125.496828)
		(end 292.339268 -125.379988)
		(width 0.14605)
		(layer "In2.Cu")
		(net "DRIVE_B_30_ACT")
	)
	(segment
		(start 292.339268 -125.379988)
		(end 290.42868 -123.4694)
		(width 0.14605)
		(layer "In2.Cu")
		(net "DRIVE_B_30_ACT")
	)
	(segment
		(start 292.332664 -178.584606)
		(end 292.332664 -146.444208)
		(width 0.14605)
		(layer "In2.Cu")
		(net "DRIVE_B_30_ACT")
	)
	(segment
		(start 290.42868 -123.4694)
		(end 290.42868 -120.1166)
		(width 0.14605)
		(layer "In2.Cu")
		(net "DRIVE_B_30_ACT")
	)
	(segment
		(start 292.363652 -134.250684)
		(end 292.344094 -134.231126)
		(width 0.14605)
		(layer "In2.Cu")
		(net "DRIVE_B_30_ACT")
	)
	(segment
		(start 289.174174 -181.743096)
		(end 292.332664 -178.584606)
		(width 0.14605)
		(layer "In2.Cu")
		(net "DRIVE_B_30_ACT")
	)
	(segment
		(start 292.344094 -125.501654)
		(end 292.339268 -125.496828)
		(width 0.14605)
		(layer "In2.Cu")
		(net "DRIVE_B_30_ACT")
	)
	(segment
		(start 218.495626 -231.722676)
		(end 216.69883 -229.92588)
		(width 0.17145)
		(layer "F.Cu")
		(net "DRIVE_B_3_PWR")
	)
	(segment
		(start 153.084276 -230.0605)
		(end 151.867616 -228.84384)
		(width 0.17145)
		(layer "F.Cu")
		(net "DRIVE_B_3_PWR")
	)
	(segment
		(start 229.17404 -229.251256)
		(end 229.17404 -230.500428)
		(width 0.17145)
		(layer "F.Cu")
		(net "DRIVE_B_3_PWR")
	)
	(segment
		(start 117.5131 -246.1768)
		(end 118.3894 -246.1768)
		(width 0.17145)
		(layer "F.Cu")
		(net "DRIVE_B_3_PWR")
	)
	(segment
		(start 203.480416 -229.92588)
		(end 203.345796 -230.0605)
		(width 0.17145)
		(layer "F.Cu")
		(net "DRIVE_B_3_PWR")
	)
	(segment
		(start 229.17404 -230.500428)
		(end 226.825556 -232.848912)
		(width 0.17145)
		(layer "F.Cu")
		(net "DRIVE_B_3_PWR")
	)
	(segment
		(start 216.69883 -229.92588)
		(end 203.480416 -229.92588)
		(width 0.17145)
		(layer "F.Cu")
		(net "DRIVE_B_3_PWR")
	)
	(segment
		(start 219.621862 -232.848912)
		(end 218.495626 -231.722676)
		(width 0.17145)
		(layer "F.Cu")
		(net "DRIVE_B_3_PWR")
	)
	(segment
		(start 203.345796 -230.0605)
		(end 153.084276 -230.0605)
		(width 0.17145)
		(layer "F.Cu")
		(net "DRIVE_B_3_PWR")
	)
	(segment
		(start 226.825556 -232.848912)
		(end 219.621862 -232.848912)
		(width 0.17145)
		(layer "F.Cu")
		(net "DRIVE_B_3_PWR")
	)
	(via
		(at 151.867616 -228.84384)
		(size 0.5588)
		(drill 0.3048)
		(layers "F.Cu" "B.Cu")
		(net "DRIVE_B_3_PWR")
	)
	(via
		(at 218.495626 -231.722676)
		(size 0.6604)
		(drill 0.3302)
		(layers "F.Cu" "B.Cu")
		(net "DRIVE_B_3_PWR")
	)
	(via
		(at 118.3894 -246.1768)
		(size 0.5588)
		(drill 0.3048)
		(layers "F.Cu" "B.Cu")
		(net "DRIVE_B_3_PWR")
	)
	(segment
		(start 118.3894 -246.1768)
		(end 127.597916 -236.968284)
		(width 0.14605)
		(layer "In2.Cu")
		(net "DRIVE_B_3_PWR")
	)
	(segment
		(start 127.597916 -236.968284)
		(end 143.743172 -236.968284)
		(width 0.14605)
		(layer "In2.Cu")
		(net "DRIVE_B_3_PWR")
	)
	(segment
		(start 143.743172 -236.968284)
		(end 151.867616 -228.84384)
		(width 0.14605)
		(layer "In2.Cu")
		(net "DRIVE_B_3_PWR")
	)
	(segment
		(start 205.359 -247.689624)
		(end 205.359 -271.448276)
		(width 0.17145)
		(layer "F.Cu")
		(net "DRIVE_B_3_INS")
	)
	(segment
		(start 206.29626 -244.48262)
		(end 206.29626 -246.752364)
		(width 0.17145)
		(layer "F.Cu")
		(net "DRIVE_B_3_INS")
	)
	(segment
		(start 131.064 -284.24124)
		(end 131.69011 -284.86735)
		(width 0.17145)
		(layer "F.Cu")
		(net "DRIVE_B_3_INS")
	)
	(segment
		(start 205.359 -271.448276)
		(end 203.749148 -273.058128)
		(width 0.17145)
		(layer "F.Cu")
		(net "DRIVE_B_3_INS")
	)
	(segment
		(start 131.69011 -284.86735)
		(end 191.939926 -284.86735)
		(width 0.17145)
		(layer "F.Cu")
		(net "DRIVE_B_3_INS")
	)
	(segment
		(start 191.939926 -284.86735)
		(end 203.749148 -273.058128)
		(width 0.17145)
		(layer "F.Cu")
		(net "DRIVE_B_3_INS")
	)
	(segment
		(start 131.064 -266.065)
		(end 131.064 -284.24124)
		(width 0.17145)
		(layer "F.Cu")
		(net "DRIVE_B_3_INS")
	)
	(segment
		(start 206.29626 -246.752364)
		(end 205.359 -247.689624)
		(width 0.17145)
		(layer "F.Cu")
		(net "DRIVE_B_3_INS")
	)
	(via
		(at 203.749148 -273.058128)
		(size 0.6604)
		(drill 0.3302)
		(layers "F.Cu" "B.Cu")
		(net "DRIVE_B_3_INS")
	)
	(segment
		(start 110.10265 -218.43492)
		(end 110.10265 -217.337386)
		(width 0.17145)
		(layer "F.Cu")
		(net "DRIVE_B_3_FLT_LED")
	)
	(segment
		(start 212.9536 -220.90888)
		(end 198.68007 -220.90888)
		(width 0.17145)
		(layer "F.Cu")
		(net "DRIVE_B_3_FLT_LED")
	)
	(segment
		(start 197.253098 -222.335852)
		(end 114.003582 -222.335852)
		(width 0.17145)
		(layer "F.Cu")
		(net "DRIVE_B_3_FLT_LED")
	)
	(segment
		(start 110.46206 -218.79433)
		(end 110.10265 -218.43492)
		(width 0.17145)
		(layer "F.Cu")
		(net "DRIVE_B_3_FLT_LED")
	)
	(segment
		(start 114.003582 -222.335852)
		(end 110.46206 -218.79433)
		(width 0.17145)
		(layer "F.Cu")
		(net "DRIVE_B_3_FLT_LED")
	)
	(segment
		(start 198.68007 -220.90888)
		(end 197.253098 -222.335852)
		(width 0.17145)
		(layer "F.Cu")
		(net "DRIVE_B_3_FLT_LED")
	)
	(segment
		(start 110.10265 -217.337386)
		(end 110.10265 -215.6587)
		(width 0.17145)
		(layer "F.Cu")
		(net "DRIVE_B_3_FLT_LED")
	)
	(via
		(at 110.46206 -218.79433)
		(size 0.6604)
		(drill 0.3302)
		(layers "F.Cu" "B.Cu")
		(net "DRIVE_B_3_FLT_LED")
	)
	(segment
		(start 233.426 -206.3496)
		(end 233.426 -205.857602)
		(width 0.17145)
		(layer "F.Cu")
		(net "DRIVE_B_3_ACT")
	)
	(segment
		(start 231.916986 -205.833218)
		(end 232.712768 -206.629)
		(width 0.17145)
		(layer "F.Cu")
		(net "DRIVE_B_3_ACT")
	)
	(segment
		(start 256.147062 -204.949044)
		(end 274.606512 -204.949044)
		(width 0.17145)
		(layer "F.Cu")
		(net "DRIVE_B_3_ACT")
	)
	(segment
		(start 235.51007 -204.888846)
		(end 242.167918 -204.888846)
		(width 0.17145)
		(layer "F.Cu")
		(net "DRIVE_B_3_ACT")
	)
	(segment
		(start 106.360468 -212.312504)
		(end 106.360468 -213.799928)
		(width 0.17145)
		(layer "F.Cu")
		(net "DRIVE_B_3_ACT")
	)
	(segment
		(start 106.360468 -210.513676)
		(end 106.360468 -212.312504)
		(width 0.17145)
		(layer "F.Cu")
		(net "DRIVE_B_3_ACT")
	)
	(segment
		(start 233.714544 -205.569058)
		(end 234.829858 -205.569058)
		(width 0.17145)
		(layer "F.Cu")
		(net "DRIVE_B_3_ACT")
	)
	(segment
		(start 106.360468 -210.513676)
		(end 106.360468 -209.408776)
		(width 0.17145)
		(layer "F.Cu")
		(net "DRIVE_B_3_ACT")
	)
	(segment
		(start 233.426 -205.857602)
		(end 233.714544 -205.569058)
		(width 0.17145)
		(layer "F.Cu")
		(net "DRIVE_B_3_ACT")
	)
	(segment
		(start 282.201112 -205.658974)
		(end 282.83662 -206.294482)
		(width 0.17145)
		(layer "F.Cu")
		(net "DRIVE_B_3_ACT")
	)
	(segment
		(start 234.829858 -205.569058)
		(end 235.51007 -204.888846)
		(width 0.17145)
		(layer "F.Cu")
		(net "DRIVE_B_3_ACT")
	)
	(segment
		(start 243.104162 -203.952602)
		(end 255.15062 -203.952602)
		(width 0.17145)
		(layer "F.Cu")
		(net "DRIVE_B_3_ACT")
	)
	(segment
		(start 232.712768 -206.629)
		(end 233.1466 -206.629)
		(width 0.17145)
		(layer "F.Cu")
		(net "DRIVE_B_3_ACT")
	)
	(segment
		(start 275.316442 -205.658974)
		(end 282.201112 -205.658974)
		(width 0.17145)
		(layer "F.Cu")
		(net "DRIVE_B_3_ACT")
	)
	(segment
		(start 274.606512 -204.949044)
		(end 275.316442 -205.658974)
		(width 0.17145)
		(layer "F.Cu")
		(net "DRIVE_B_3_ACT")
	)
	(segment
		(start 233.1466 -206.629)
		(end 233.426 -206.3496)
		(width 0.17145)
		(layer "F.Cu")
		(net "DRIVE_B_3_ACT")
	)
	(segment
		(start 255.15062 -203.952602)
		(end 256.147062 -204.949044)
		(width 0.17145)
		(layer "F.Cu")
		(net "DRIVE_B_3_ACT")
	)
	(segment
		(start 242.167918 -204.888846)
		(end 243.104162 -203.952602)
		(width 0.17145)
		(layer "F.Cu")
		(net "DRIVE_B_3_ACT")
	)
	(via
		(at 106.360468 -209.408776)
		(size 0.5588)
		(drill 0.3048)
		(layers "F.Cu" "B.Cu")
		(net "DRIVE_B_3_ACT")
	)
	(via
		(at 231.916986 -205.833218)
		(size 0.5588)
		(drill 0.3048)
		(layers "F.Cu" "B.Cu")
		(net "DRIVE_B_3_ACT")
	)
	(via
		(at 106.360468 -210.513676)
		(size 0.6604)
		(drill 0.3302)
		(layers "F.Cu" "B.Cu")
		(net "DRIVE_B_3_ACT")
	)
	(segment
		(start 108.570776 -209.408776)
		(end 106.360468 -209.408776)
		(width 0.14605)
		(layer "In5.Cu")
		(net "DRIVE_B_3_ACT")
	)
	(segment
		(start 199.836278 -218.253056)
		(end 117.415056 -218.253056)
		(width 0.14605)
		(layer "In5.Cu")
		(net "DRIVE_B_3_ACT")
	)
	(segment
		(start 227.194872 -210.555332)
		(end 207.534002 -210.555332)
		(width 0.14605)
		(layer "In5.Cu")
		(net "DRIVE_B_3_ACT")
	)
	(segment
		(start 231.916986 -205.833218)
		(end 227.194872 -210.555332)
		(width 0.14605)
		(layer "In5.Cu")
		(net "DRIVE_B_3_ACT")
	)
	(segment
		(start 117.415056 -218.253056)
		(end 108.570776 -209.408776)
		(width 0.14605)
		(layer "In5.Cu")
		(net "DRIVE_B_3_ACT")
	)
	(segment
		(start 207.534002 -210.555332)
		(end 199.836278 -218.253056)
		(width 0.14605)
		(layer "In5.Cu")
		(net "DRIVE_B_3_ACT")
	)
	(segment
		(start 235.0516 -199.41032)
		(end 233.777028 -199.41032)
		(width 0.17145)
		(layer "F.Cu")
		(net "DRIVE_B_29_PWR")
	)
	(segment
		(start 182.118 -19.6215)
		(end 182.118 -20.142962)
		(width 0.17145)
		(layer "F.Cu")
		(net "DRIVE_B_29_PWR")
	)
	(segment
		(start 230.5812 -200.3298)
		(end 231.365552 -199.545448)
		(width 0.17145)
		(layer "F.Cu")
		(net "DRIVE_B_29_PWR")
	)
	(segment
		(start 181.305962 -20.955)
		(end 180.902356 -20.955)
		(width 0.17145)
		(layer "F.Cu")
		(net "DRIVE_B_29_PWR")
	)
	(segment
		(start 231.365552 -199.545448)
		(end 232.35412 -199.545448)
		(width 0.17145)
		(layer "F.Cu")
		(net "DRIVE_B_29_PWR")
	)
	(segment
		(start 233.375708 -199.009)
		(end 233.0704 -199.009)
		(width 0.17145)
		(layer "F.Cu")
		(net "DRIVE_B_29_PWR")
	)
	(segment
		(start 232.35412 -199.545448)
		(end 232.890568 -199.009)
		(width 0.17145)
		(layer "F.Cu")
		(net "DRIVE_B_29_PWR")
	)
	(segment
		(start 233.777028 -199.41032)
		(end 233.375708 -199.009)
		(width 0.17145)
		(layer "F.Cu")
		(net "DRIVE_B_29_PWR")
	)
	(segment
		(start 182.118 -20.142962)
		(end 181.305962 -20.955)
		(width 0.17145)
		(layer "F.Cu")
		(net "DRIVE_B_29_PWR")
	)
	(segment
		(start 232.890568 -199.009)
		(end 233.0704 -199.009)
		(width 0.17145)
		(layer "F.Cu")
		(net "DRIVE_B_29_PWR")
	)
	(via
		(at 233.0704 -199.009)
		(size 0.6604)
		(drill 0.3302)
		(layers "F.Cu" "B.Cu")
		(net "DRIVE_B_29_PWR")
	)
	(via
		(at 184.9374 -189.357)
		(size 0.5588)
		(drill 0.3048)
		(layers "F.Cu" "B.Cu")
		(net "DRIVE_B_29_PWR")
	)
	(via
		(at 230.5812 -200.3298)
		(size 0.5588)
		(drill 0.3048)
		(layers "F.Cu" "B.Cu")
		(net "DRIVE_B_29_PWR")
	)
	(via
		(at 180.902356 -20.955)
		(size 0.5588)
		(drill 0.3048)
		(layers "F.Cu" "B.Cu")
		(net "DRIVE_B_29_PWR")
	)
	(segment
		(start 180.902356 -24.17445)
		(end 182.118 -25.390094)
		(width 0.14605)
		(layer "In2.Cu")
		(net "DRIVE_B_29_PWR")
	)
	(segment
		(start 200.355454 -82.45983)
		(end 200.355454 -111.35233)
		(width 0.14605)
		(layer "In2.Cu")
		(net "DRIVE_B_29_PWR")
	)
	(segment
		(start 195.072 -140.6652)
		(end 195.072 -179.2224)
		(width 0.14605)
		(layer "In2.Cu")
		(net "DRIVE_B_29_PWR")
	)
	(segment
		(start 204.19314 -131.54406)
		(end 195.072 -140.6652)
		(width 0.14605)
		(layer "In2.Cu")
		(net "DRIVE_B_29_PWR")
	)
	(segment
		(start 180.902356 -20.955)
		(end 180.902356 -24.17445)
		(width 0.14605)
		(layer "In2.Cu")
		(net "DRIVE_B_29_PWR")
	)
	(segment
		(start 183.44007 -34.055558)
		(end 183.44007 -65.544446)
		(width 0.14605)
		(layer "In2.Cu")
		(net "DRIVE_B_29_PWR")
	)
	(segment
		(start 182.118 -32.733488)
		(end 183.44007 -34.055558)
		(width 0.14605)
		(layer "In2.Cu")
		(net "DRIVE_B_29_PWR")
	)
	(segment
		(start 204.19314 -115.190016)
		(end 204.19314 -131.54406)
		(width 0.14605)
		(layer "In2.Cu")
		(net "DRIVE_B_29_PWR")
	)
	(segment
		(start 183.44007 -65.544446)
		(end 200.355454 -82.45983)
		(width 0.14605)
		(layer "In2.Cu")
		(net "DRIVE_B_29_PWR")
	)
	(segment
		(start 182.118 -25.390094)
		(end 182.118 -32.733488)
		(width 0.14605)
		(layer "In2.Cu")
		(net "DRIVE_B_29_PWR")
	)
	(segment
		(start 195.072 -179.2224)
		(end 184.9374 -189.357)
		(width 0.14605)
		(layer "In2.Cu")
		(net "DRIVE_B_29_PWR")
	)
	(segment
		(start 200.355454 -111.35233)
		(end 204.19314 -115.190016)
		(width 0.14605)
		(layer "In2.Cu")
		(net "DRIVE_B_29_PWR")
	)
	(segment
		(start 230.4288 -200.4822)
		(end 229.1334 -200.4822)
		(width 0.14605)
		(layer "In5.Cu")
		(net "DRIVE_B_29_PWR")
	)
	(segment
		(start 229.1334 -200.4822)
		(end 228.294946 -199.643746)
		(width 0.14605)
		(layer "In5.Cu")
		(net "DRIVE_B_29_PWR")
	)
	(segment
		(start 230.5812 -200.3298)
		(end 230.4288 -200.4822)
		(width 0.14605)
		(layer "In5.Cu")
		(net "DRIVE_B_29_PWR")
	)
	(segment
		(start 228.294946 -199.643746)
		(end 201.070464 -199.643746)
		(width 0.14605)
		(layer "In5.Cu")
		(net "DRIVE_B_29_PWR")
	)
	(segment
		(start 201.070464 -199.643746)
		(end 191.449452 -190.022734)
		(width 0.14605)
		(layer "In5.Cu")
		(net "DRIVE_B_29_PWR")
	)
	(segment
		(start 185.603134 -190.022734)
		(end 184.9374 -189.357)
		(width 0.14605)
		(layer "In5.Cu")
		(net "DRIVE_B_29_PWR")
	)
	(segment
		(start 191.449452 -190.022734)
		(end 185.603134 -190.022734)
		(width 0.14605)
		(layer "In5.Cu")
		(net "DRIVE_B_29_PWR")
	)
	(segment
		(start 195.8721 -189.859412)
		(end 195.8721 -164.233606)
		(width 0.17145)
		(layer "F.Cu")
		(net "DRIVE_B_29_INS")
	)
	(segment
		(start 210.060286 -210.30311)
		(end 202.488546 -210.30311)
		(width 0.17145)
		(layer "F.Cu")
		(net "DRIVE_B_29_INS")
	)
	(segment
		(start 190.0936 -54.8386)
		(end 188.5442 -56.388)
		(width 0.17145)
		(layer "F.Cu")
		(net "DRIVE_B_29_INS")
	)
	(segment
		(start 135.124698 -102.117144)
		(end 135.124698 -74.7903)
		(width 0.17145)
		(layer "F.Cu")
		(net "DRIVE_B_29_INS")
	)
	(segment
		(start 144.26438 -56.388)
		(end 135.124698 -65.527682)
		(width 0.17145)
		(layer "F.Cu")
		(net "DRIVE_B_29_INS")
	)
	(segment
		(start 186.955176 -110.33125)
		(end 143.338804 -110.33125)
		(width 0.17145)
		(layer "F.Cu")
		(net "DRIVE_B_29_INS")
	)
	(segment
		(start 210.541362 -149.564344)
		(end 210.541362 -133.917436)
		(width 0.17145)
		(layer "F.Cu")
		(net "DRIVE_B_29_INS")
	)
	(segment
		(start 202.226672 -196.213984)
		(end 195.8721 -189.859412)
		(width 0.17145)
		(layer "F.Cu")
		(net "DRIVE_B_29_INS")
	)
	(segment
		(start 210.541362 -133.917436)
		(end 186.955176 -110.33125)
		(width 0.17145)
		(layer "F.Cu")
		(net "DRIVE_B_29_INS")
	)
	(segment
		(start 135.124698 -65.527682)
		(end 135.124698 -74.7903)
		(width 0.17145)
		(layer "F.Cu")
		(net "DRIVE_B_29_INS")
	)
	(segment
		(start 202.488546 -210.30311)
		(end 202.226672 -210.041236)
		(width 0.17145)
		(layer "F.Cu")
		(net "DRIVE_B_29_INS")
	)
	(segment
		(start 213.0806 -209.62112)
		(end 210.742276 -209.62112)
		(width 0.17145)
		(layer "F.Cu")
		(net "DRIVE_B_29_INS")
	)
	(segment
		(start 202.226672 -210.041236)
		(end 202.226672 -196.213984)
		(width 0.17145)
		(layer "F.Cu")
		(net "DRIVE_B_29_INS")
	)
	(segment
		(start 195.8721 -164.233606)
		(end 210.541362 -149.564344)
		(width 0.17145)
		(layer "F.Cu")
		(net "DRIVE_B_29_INS")
	)
	(segment
		(start 190.0936 -36.3474)
		(end 190.0936 -54.8386)
		(width 0.17145)
		(layer "F.Cu")
		(net "DRIVE_B_29_INS")
	)
	(segment
		(start 143.338804 -110.33125)
		(end 135.124698 -102.117144)
		(width 0.17145)
		(layer "F.Cu")
		(net "DRIVE_B_29_INS")
	)
	(segment
		(start 188.5442 -56.388)
		(end 144.26438 -56.388)
		(width 0.17145)
		(layer "F.Cu")
		(net "DRIVE_B_29_INS")
	)
	(segment
		(start 210.742276 -209.62112)
		(end 210.060286 -210.30311)
		(width 0.17145)
		(layer "F.Cu")
		(net "DRIVE_B_29_INS")
	)
	(via
		(at 135.124698 -74.7903)
		(size 0.6604)
		(drill 0.3302)
		(layers "F.Cu" "B.Cu")
		(net "DRIVE_B_29_INS")
	)
	(segment
		(start 271.0688 -111.6584)
		(end 277.438612 -111.6584)
		(width 0.17145)
		(layer "F.Cu")
		(net "DRIVE_B_29_ACT")
	)
	(segment
		(start 229.80015 -72.900032)
		(end 229.948232 -72.900032)
		(width 0.17145)
		(layer "F.Cu")
		(net "DRIVE_B_29_ACT")
	)
	(segment
		(start 257.804666 -107.499912)
		(end 262.4328 -107.499912)
		(width 0.17145)
		(layer "F.Cu")
		(net "DRIVE_B_29_ACT")
	)
	(segment
		(start 230.43896 -80.134206)
		(end 257.804666 -107.499912)
		(width 0.17145)
		(layer "F.Cu")
		(net "DRIVE_B_29_ACT")
	)
	(segment
		(start 277.438612 -111.6584)
		(end 283.947362 -118.16715)
		(width 0.17145)
		(layer "F.Cu")
		(net "DRIVE_B_29_ACT")
	)
	(segment
		(start 283.947362 -118.16715)
		(end 289.66795 -118.16715)
		(width 0.17145)
		(layer "F.Cu")
		(net "DRIVE_B_29_ACT")
	)
	(segment
		(start 289.66795 -118.16715)
		(end 290.50488 -119.00408)
		(width 0.17145)
		(layer "F.Cu")
		(net "DRIVE_B_29_ACT")
	)
	(segment
		(start 262.4328 -107.499912)
		(end 266.910312 -107.499912)
		(width 0.17145)
		(layer "F.Cu")
		(net "DRIVE_B_29_ACT")
	)
	(segment
		(start 230.43896 -73.39076)
		(end 230.43896 -80.134206)
		(width 0.17145)
		(layer "F.Cu")
		(net "DRIVE_B_29_ACT")
	)
	(segment
		(start 229.948232 -72.900032)
		(end 230.43896 -73.39076)
		(width 0.17145)
		(layer "F.Cu")
		(net "DRIVE_B_29_ACT")
	)
	(segment
		(start 266.910312 -107.499912)
		(end 271.0688 -111.6584)
		(width 0.17145)
		(layer "F.Cu")
		(net "DRIVE_B_29_ACT")
	)
	(via
		(at 262.4328 -107.499912)
		(size 0.6604)
		(drill 0.3302)
		(layers "F.Cu" "B.Cu")
		(net "DRIVE_B_29_ACT")
	)
	(via
		(at 290.50488 -119.00408)
		(size 0.5588)
		(drill 0.3048)
		(layers "F.Cu" "B.Cu")
		(net "DRIVE_B_29_ACT")
	)
	(segment
		(start 292.953694 -146.442938)
		(end 292.953694 -125.374654)
		(width 0.14605)
		(layer "In2.Cu")
		(net "DRIVE_B_29_ACT")
	)
	(segment
		(start 292.953694 -125.374654)
		(end 290.944808 -123.365768)
		(width 0.14605)
		(layer "In2.Cu")
		(net "DRIVE_B_29_ACT")
	)
	(segment
		(start 292.770814 -146.625818)
		(end 292.953694 -146.442938)
		(width 0.14605)
		(layer "In2.Cu")
		(net "DRIVE_B_29_ACT")
	)
	(segment
		(start 290.944808 -119.444008)
		(end 290.50488 -119.00408)
		(width 0.14605)
		(layer "In2.Cu")
		(net "DRIVE_B_29_ACT")
	)
	(segment
		(start 281.836622 -182.894478)
		(end 282.486354 -182.244746)
		(width 0.14605)
		(layer "In2.Cu")
		(net "DRIVE_B_29_ACT")
	)
	(segment
		(start 289.302444 -182.244746)
		(end 292.770814 -178.776376)
		(width 0.14605)
		(layer "In2.Cu")
		(net "DRIVE_B_29_ACT")
	)
	(segment
		(start 282.486354 -182.244746)
		(end 289.302444 -182.244746)
		(width 0.14605)
		(layer "In2.Cu")
		(net "DRIVE_B_29_ACT")
	)
	(segment
		(start 292.770814 -178.776376)
		(end 292.770814 -146.625818)
		(width 0.14605)
		(layer "In2.Cu")
		(net "DRIVE_B_29_ACT")
	)
	(segment
		(start 290.944808 -123.365768)
		(end 290.944808 -119.444008)
		(width 0.14605)
		(layer "In2.Cu")
		(net "DRIVE_B_29_ACT")
	)
	(segment
		(start 233.765344 -200.06056)
		(end 233.625644 -200.20026)
		(width 0.17145)
		(layer "F.Cu")
		(net "DRIVE_B_28_PWR")
	)
	(segment
		(start 235.0516 -200.06056)
		(end 233.765344 -200.06056)
		(width 0.17145)
		(layer "F.Cu")
		(net "DRIVE_B_28_PWR")
	)
	(segment
		(start 233.625644 -200.20026)
		(end 232.97261 -200.20026)
		(width 0.17145)
		(layer "F.Cu")
		(net "DRIVE_B_28_PWR")
	)
	(segment
		(start 231.793796 -200.201276)
		(end 232.971594 -200.201276)
		(width 0.17145)
		(layer "F.Cu")
		(net "DRIVE_B_28_PWR")
	)
	(segment
		(start 232.97261 -200.20026)
		(end 232.971594 -200.201276)
		(width 0.17145)
		(layer "F.Cu")
		(net "DRIVE_B_28_PWR")
	)
	(segment
		(start 231.65562 -200.0631)
		(end 231.793796 -200.201276)
		(width 0.17145)
		(layer "F.Cu")
		(net "DRIVE_B_28_PWR")
	)
	(segment
		(start 149.1615 -16.3322)
		(end 150.0124 -16.3322)
		(width 0.17145)
		(layer "F.Cu")
		(net "DRIVE_B_28_PWR")
	)
	(via
		(at 150.0124 -16.3322)
		(size 0.5588)
		(drill 0.3048)
		(layers "F.Cu" "B.Cu")
		(net "DRIVE_B_28_PWR")
	)
	(via
		(at 232.971594 -200.201276)
		(size 0.6604)
		(drill 0.3302)
		(layers "F.Cu" "B.Cu")
		(net "DRIVE_B_28_PWR")
	)
	(via
		(at 231.65562 -200.0631)
		(size 0.5588)
		(drill 0.3048)
		(layers "F.Cu" "B.Cu")
		(net "DRIVE_B_28_PWR")
	)
	(via
		(at 184.95645 -188.2902)
		(size 0.5588)
		(drill 0.3048)
		(layers "F.Cu" "B.Cu")
		(net "DRIVE_B_28_PWR")
	)
	(segment
		(start 203.75499 -115.371626)
		(end 199.6694 -111.286036)
		(width 0.14605)
		(layer "In2.Cu")
		(net "DRIVE_B_28_PWR")
	)
	(segment
		(start 184.95645 -188.2902)
		(end 184.8612 -188.19495)
		(width 0.14605)
		(layer "In2.Cu")
		(net "DRIVE_B_28_PWR")
	)
	(segment
		(start 194.29095 -167.42029)
		(end 194.29095 -140.82649)
		(width 0.14605)
		(layer "In2.Cu")
		(net "DRIVE_B_28_PWR")
	)
	(segment
		(start 199.6694 -82.953098)
		(end 168.072562 -51.35626)
		(width 0.14605)
		(layer "In2.Cu")
		(net "DRIVE_B_28_PWR")
	)
	(segment
		(start 194.29095 -140.82649)
		(end 203.75499 -131.36245)
		(width 0.14605)
		(layer "In2.Cu")
		(net "DRIVE_B_28_PWR")
	)
	(segment
		(start 184.8612 -176.85004)
		(end 194.29095 -167.42029)
		(width 0.14605)
		(layer "In2.Cu")
		(net "DRIVE_B_28_PWR")
	)
	(segment
		(start 151.511508 -17.831308)
		(end 150.0124 -16.3322)
		(width 0.14605)
		(layer "In2.Cu")
		(net "DRIVE_B_28_PWR")
	)
	(segment
		(start 151.511508 -18.573242)
		(end 151.511508 -17.831308)
		(width 0.14605)
		(layer "In2.Cu")
		(net "DRIVE_B_28_PWR")
	)
	(segment
		(start 168.072562 -35.134296)
		(end 151.511508 -18.573242)
		(width 0.14605)
		(layer "In2.Cu")
		(net "DRIVE_B_28_PWR")
	)
	(segment
		(start 199.6694 -111.286036)
		(end 199.6694 -82.953098)
		(width 0.14605)
		(layer "In2.Cu")
		(net "DRIVE_B_28_PWR")
	)
	(segment
		(start 168.072562 -51.35626)
		(end 168.072562 -35.134296)
		(width 0.14605)
		(layer "In2.Cu")
		(net "DRIVE_B_28_PWR")
	)
	(segment
		(start 184.8612 -188.19495)
		(end 184.8612 -176.85004)
		(width 0.14605)
		(layer "In2.Cu")
		(net "DRIVE_B_28_PWR")
	)
	(segment
		(start 203.75499 -131.36245)
		(end 203.75499 -115.371626)
		(width 0.14605)
		(layer "In2.Cu")
		(net "DRIVE_B_28_PWR")
	)
	(segment
		(start 230.94315 -199.01535)
		(end 201.061828 -199.01535)
		(width 0.14605)
		(layer "In5.Cu")
		(net "DRIVE_B_28_PWR")
	)
	(segment
		(start 201.061828 -199.01535)
		(end 191.631062 -189.584584)
		(width 0.14605)
		(layer "In5.Cu")
		(net "DRIVE_B_28_PWR")
	)
	(segment
		(start 191.631062 -189.584584)
		(end 186.250834 -189.584584)
		(width 0.14605)
		(layer "In5.Cu")
		(net "DRIVE_B_28_PWR")
	)
	(segment
		(start 231.65562 -199.72782)
		(end 230.94315 -199.01535)
		(width 0.14605)
		(layer "In5.Cu")
		(net "DRIVE_B_28_PWR")
	)
	(segment
		(start 231.65562 -200.0631)
		(end 231.65562 -199.72782)
		(width 0.14605)
		(layer "In5.Cu")
		(net "DRIVE_B_28_PWR")
	)
	(segment
		(start 186.250834 -189.584584)
		(end 184.95645 -188.2902)
		(width 0.14605)
		(layer "In5.Cu")
		(net "DRIVE_B_28_PWR")
	)
	(segment
		(start 210.273392 -210.81746)
		(end 210.819492 -210.27136)
		(width 0.17145)
		(layer "F.Cu")
		(net "DRIVE_B_28_INS")
	)
	(segment
		(start 195.35775 -190.072518)
		(end 201.712322 -196.42709)
		(width 0.17145)
		(layer "F.Cu")
		(net "DRIVE_B_28_INS")
	)
	(segment
		(start 133.04774 -79.38262)
		(end 133.04774 -102.385368)
		(width 0.17145)
		(layer "F.Cu")
		(net "DRIVE_B_28_INS")
	)
	(segment
		(start 186.61126 -111.25581)
		(end 209.931 -134.57555)
		(width 0.17145)
		(layer "F.Cu")
		(net "DRIVE_B_28_INS")
	)
	(segment
		(start 161.8742 -33.6042)
		(end 161.8742 -50.56124)
		(width 0.17145)
		(layer "F.Cu")
		(net "DRIVE_B_28_INS")
	)
	(segment
		(start 201.712322 -196.42709)
		(end 201.712322 -210.254342)
		(width 0.17145)
		(layer "F.Cu")
		(net "DRIVE_B_28_INS")
	)
	(segment
		(start 209.931 -149.44725)
		(end 195.35775 -164.0205)
		(width 0.17145)
		(layer "F.Cu")
		(net "DRIVE_B_28_INS")
	)
	(segment
		(start 157.905958 -54.529482)
		(end 143.67637 -54.529482)
		(width 0.17145)
		(layer "F.Cu")
		(net "DRIVE_B_28_INS")
	)
	(segment
		(start 133.04774 -102.385368)
		(end 141.918182 -111.25581)
		(width 0.17145)
		(layer "F.Cu")
		(net "DRIVE_B_28_INS")
	)
	(segment
		(start 161.8742 -50.56124)
		(end 157.905958 -54.529482)
		(width 0.17145)
		(layer "F.Cu")
		(net "DRIVE_B_28_INS")
	)
	(segment
		(start 201.712322 -210.254342)
		(end 202.27544 -210.81746)
		(width 0.17145)
		(layer "F.Cu")
		(net "DRIVE_B_28_INS")
	)
	(segment
		(start 210.819492 -210.27136)
		(end 213.0806 -210.27136)
		(width 0.17145)
		(layer "F.Cu")
		(net "DRIVE_B_28_INS")
	)
	(segment
		(start 133.04774 -65.158112)
		(end 133.04774 -79.38262)
		(width 0.17145)
		(layer "F.Cu")
		(net "DRIVE_B_28_INS")
	)
	(segment
		(start 202.27544 -210.81746)
		(end 210.273392 -210.81746)
		(width 0.17145)
		(layer "F.Cu")
		(net "DRIVE_B_28_INS")
	)
	(segment
		(start 195.35775 -164.0205)
		(end 195.35775 -190.072518)
		(width 0.17145)
		(layer "F.Cu")
		(net "DRIVE_B_28_INS")
	)
	(segment
		(start 141.918182 -111.25581)
		(end 186.61126 -111.25581)
		(width 0.17145)
		(layer "F.Cu")
		(net "DRIVE_B_28_INS")
	)
	(segment
		(start 209.931 -134.57555)
		(end 209.931 -149.44725)
		(width 0.17145)
		(layer "F.Cu")
		(net "DRIVE_B_28_INS")
	)
	(segment
		(start 143.67637 -54.529482)
		(end 133.04774 -65.158112)
		(width 0.17145)
		(layer "F.Cu")
		(net "DRIVE_B_28_INS")
	)
	(via
		(at 133.04774 -79.38262)
		(size 0.6604)
		(drill 0.3302)
		(layers "F.Cu" "B.Cu")
		(net "DRIVE_B_28_INS")
	)
	(segment
		(start 229.80015 -71.799958)
		(end 229.838758 -71.799958)
		(width 0.17145)
		(layer "F.Cu")
		(net "DRIVE_B_28_ACT")
	)
	(segment
		(start 271.526 -110.9472)
		(end 267.3604 -106.7816)
		(width 0.17145)
		(layer "F.Cu")
		(net "DRIVE_B_28_ACT")
	)
	(segment
		(start 257.875278 -106.7816)
		(end 265.5062 -106.7816)
		(width 0.17145)
		(layer "F.Cu")
		(net "DRIVE_B_28_ACT")
	)
	(segment
		(start 229.838758 -71.799958)
		(end 230.96601 -72.92721)
		(width 0.17145)
		(layer "F.Cu")
		(net "DRIVE_B_28_ACT")
	)
	(segment
		(start 230.96601 -79.872332)
		(end 257.875278 -106.7816)
		(width 0.17145)
		(layer "F.Cu")
		(net "DRIVE_B_28_ACT")
	)
	(segment
		(start 291.44976 -118.95836)
		(end 290.1442 -117.6528)
		(width 0.17145)
		(layer "F.Cu")
		(net "DRIVE_B_28_ACT")
	)
	(segment
		(start 230.96601 -72.92721)
		(end 230.96601 -79.872332)
		(width 0.17145)
		(layer "F.Cu")
		(net "DRIVE_B_28_ACT")
	)
	(segment
		(start 291.44976 -120.15216)
		(end 291.44976 -118.95836)
		(width 0.17145)
		(layer "F.Cu")
		(net "DRIVE_B_28_ACT")
	)
	(segment
		(start 284.160468 -117.6528)
		(end 277.454868 -110.9472)
		(width 0.17145)
		(layer "F.Cu")
		(net "DRIVE_B_28_ACT")
	)
	(segment
		(start 277.454868 -110.9472)
		(end 271.526 -110.9472)
		(width 0.17145)
		(layer "F.Cu")
		(net "DRIVE_B_28_ACT")
	)
	(segment
		(start 290.1442 -117.6528)
		(end 284.160468 -117.6528)
		(width 0.17145)
		(layer "F.Cu")
		(net "DRIVE_B_28_ACT")
	)
	(segment
		(start 267.3604 -106.7816)
		(end 265.5062 -106.7816)
		(width 0.17145)
		(layer "F.Cu")
		(net "DRIVE_B_28_ACT")
	)
	(via
		(at 265.5062 -106.7816)
		(size 0.6604)
		(drill 0.3302)
		(layers "F.Cu" "B.Cu")
		(net "DRIVE_B_28_ACT")
	)
	(via
		(at 291.44976 -120.15216)
		(size 0.5588)
		(drill 0.3048)
		(layers "F.Cu" "B.Cu")
		(net "DRIVE_B_28_ACT")
	)
	(segment
		(start 293.391844 -146.624548)
		(end 293.391844 -125.193044)
		(width 0.14605)
		(layer "In2.Cu")
		(net "DRIVE_B_28_ACT")
	)
	(segment
		(start 283.873448 -183.531256)
		(end 288.635694 -183.531256)
		(width 0.14605)
		(layer "In2.Cu")
		(net "DRIVE_B_28_ACT")
	)
	(segment
		(start 293.208964 -146.807428)
		(end 293.391844 -146.624548)
		(width 0.14605)
		(layer "In2.Cu")
		(net "DRIVE_B_28_ACT")
	)
	(segment
		(start 283.23667 -182.894478)
		(end 283.873448 -183.531256)
		(width 0.14605)
		(layer "In2.Cu")
		(net "DRIVE_B_28_ACT")
	)
	(segment
		(start 288.635694 -183.531256)
		(end 293.208964 -178.957986)
		(width 0.14605)
		(layer "In2.Cu")
		(net "DRIVE_B_28_ACT")
	)
	(segment
		(start 291.44976 -123.25096)
		(end 291.44976 -120.15216)
		(width 0.14605)
		(layer "In2.Cu")
		(net "DRIVE_B_28_ACT")
	)
	(segment
		(start 293.391844 -125.193044)
		(end 291.44976 -123.25096)
		(width 0.14605)
		(layer "In2.Cu")
		(net "DRIVE_B_28_ACT")
	)
	(segment
		(start 293.208964 -178.957986)
		(end 293.208964 -146.807428)
		(width 0.14605)
		(layer "In2.Cu")
		(net "DRIVE_B_28_ACT")
	)
	(segment
		(start 229.418134 -201.660252)
		(end 230.438198 -201.660252)
		(width 0.17145)
		(layer "F.Cu")
		(net "DRIVE_B_27_PWR")
	)
	(segment
		(start 230.438198 -201.660252)
		(end 230.769922 -201.328528)
		(width 0.17145)
		(layer "F.Cu")
		(net "DRIVE_B_27_PWR")
	)
	(segment
		(start 230.769922 -201.328528)
		(end 231.24795 -200.8505)
		(width 0.17145)
		(layer "F.Cu")
		(net "DRIVE_B_27_PWR")
	)
	(segment
		(start 233.579924 -200.8505)
		(end 233.719624 -200.7108)
		(width 0.17145)
		(layer "F.Cu")
		(net "DRIVE_B_27_PWR")
	)
	(segment
		(start 233.719624 -200.7108)
		(end 235.0516 -200.7108)
		(width 0.17145)
		(layer "F.Cu")
		(net "DRIVE_B_27_PWR")
	)
	(segment
		(start 231.24795 -200.8505)
		(end 233.579924 -200.8505)
		(width 0.17145)
		(layer "F.Cu")
		(net "DRIVE_B_27_PWR")
	)
	(segment
		(start 118.999 -19.6215)
		(end 118.999 -20.447)
		(width 0.17145)
		(layer "F.Cu")
		(net "DRIVE_B_27_PWR")
	)
	(via
		(at 118.999 -20.447)
		(size 0.5588)
		(drill 0.3048)
		(layers "F.Cu" "B.Cu")
		(net "DRIVE_B_27_PWR")
	)
	(via
		(at 229.418134 -201.660252)
		(size 0.5588)
		(drill 0.3048)
		(layers "F.Cu" "B.Cu")
		(net "DRIVE_B_27_PWR")
	)
	(via
		(at 230.769922 -201.328528)
		(size 0.6604)
		(drill 0.3302)
		(layers "F.Cu" "B.Cu")
		(net "DRIVE_B_27_PWR")
	)
	(via
		(at 183.7182 -188.8998)
		(size 0.5588)
		(drill 0.3048)
		(layers "F.Cu" "B.Cu")
		(net "DRIVE_B_27_PWR")
	)
	(segment
		(start 143.146272 -44.149772)
		(end 119.4435 -20.447)
		(width 0.14605)
		(layer "In2.Cu")
		(net "DRIVE_B_27_PWR")
	)
	(segment
		(start 119.4435 -20.447)
		(end 118.999 -20.447)
		(width 0.14605)
		(layer "In2.Cu")
		(net "DRIVE_B_27_PWR")
	)
	(segment
		(start 183.7182 -188.8998)
		(end 184.146952 -188.471048)
		(width 0.14605)
		(layer "In2.Cu")
		(net "DRIVE_B_27_PWR")
	)
	(segment
		(start 203.261976 -115.525296)
		(end 198.613014 -110.876334)
		(width 0.14605)
		(layer "In2.Cu")
		(net "DRIVE_B_27_PWR")
	)
	(segment
		(start 184.146952 -176.944528)
		(end 193.8528 -167.23868)
		(width 0.14605)
		(layer "In2.Cu")
		(net "DRIVE_B_27_PWR")
	)
	(segment
		(start 159.242506 -44.149772)
		(end 143.146272 -44.149772)
		(width 0.14605)
		(layer "In2.Cu")
		(net "DRIVE_B_27_PWR")
	)
	(segment
		(start 198.613014 -110.876334)
		(end 198.613014 -83.52028)
		(width 0.14605)
		(layer "In2.Cu")
		(net "DRIVE_B_27_PWR")
	)
	(segment
		(start 198.613014 -83.52028)
		(end 159.242506 -44.149772)
		(width 0.14605)
		(layer "In2.Cu")
		(net "DRIVE_B_27_PWR")
	)
	(segment
		(start 203.261976 -131.158234)
		(end 203.261976 -115.525296)
		(width 0.14605)
		(layer "In2.Cu")
		(net "DRIVE_B_27_PWR")
	)
	(segment
		(start 193.8528 -140.56741)
		(end 203.261976 -131.158234)
		(width 0.14605)
		(layer "In2.Cu")
		(net "DRIVE_B_27_PWR")
	)
	(segment
		(start 193.8528 -167.23868)
		(end 193.8528 -140.56741)
		(width 0.14605)
		(layer "In2.Cu")
		(net "DRIVE_B_27_PWR")
	)
	(segment
		(start 184.146952 -188.471048)
		(end 184.146952 -176.944528)
		(width 0.14605)
		(layer "In2.Cu")
		(net "DRIVE_B_27_PWR")
	)
	(segment
		(start 227.772976 -200.520046)
		(end 200.707244 -200.520046)
		(width 0.14605)
		(layer "In5.Cu")
		(net "DRIVE_B_27_PWR")
	)
	(segment
		(start 229.418134 -201.660252)
		(end 228.913182 -201.660252)
		(width 0.14605)
		(layer "In5.Cu")
		(net "DRIVE_B_27_PWR")
	)
	(segment
		(start 228.913182 -201.660252)
		(end 227.772976 -200.520046)
		(width 0.14605)
		(layer "In5.Cu")
		(net "DRIVE_B_27_PWR")
	)
	(segment
		(start 191.086232 -190.899034)
		(end 185.14568 -190.899034)
		(width 0.14605)
		(layer "In5.Cu")
		(net "DRIVE_B_27_PWR")
	)
	(segment
		(start 185.14568 -190.899034)
		(end 183.889396 -189.64275)
		(width 0.14605)
		(layer "In5.Cu")
		(net "DRIVE_B_27_PWR")
	)
	(segment
		(start 183.889396 -189.64275)
		(end 183.889396 -189.070996)
		(width 0.14605)
		(layer "In5.Cu")
		(net "DRIVE_B_27_PWR")
	)
	(segment
		(start 200.707244 -200.520046)
		(end 191.086232 -190.899034)
		(width 0.14605)
		(layer "In5.Cu")
		(net "DRIVE_B_27_PWR")
	)
	(segment
		(start 183.889396 -189.070996)
		(end 183.7182 -188.8998)
		(width 0.14605)
		(layer "In5.Cu")
		(net "DRIVE_B_27_PWR")
	)
	(segment
		(start 210.486498 -211.33181)
		(end 210.896708 -210.9216)
		(width 0.17145)
		(layer "F.Cu")
		(net "DRIVE_B_27_INS")
	)
	(segment
		(start 197.324218 -158.580836)
		(end 194.8434 -161.061654)
		(width 0.17145)
		(layer "F.Cu")
		(net "DRIVE_B_27_INS")
	)
	(segment
		(start 130.4544 -33.6042)
		(end 130.4544 -36.363402)
		(width 0.17145)
		(layer "F.Cu")
		(net "DRIVE_B_27_INS")
	)
	(segment
		(start 197.324218 -122.696224)
		(end 197.324218 -158.580836)
		(width 0.17145)
		(layer "F.Cu")
		(net "DRIVE_B_27_INS")
	)
	(segment
		(start 130.4544 -36.363402)
		(end 131.438142 -37.347144)
		(width 0.17145)
		(layer "F.Cu")
		(net "DRIVE_B_27_INS")
	)
	(segment
		(start 131.438142 -84.469224)
		(end 131.438142 -102.56266)
		(width 0.17145)
		(layer "F.Cu")
		(net "DRIVE_B_27_INS")
	)
	(segment
		(start 140.999718 -112.124236)
		(end 186.75223 -112.124236)
		(width 0.17145)
		(layer "F.Cu")
		(net "DRIVE_B_27_INS")
	)
	(segment
		(start 194.8434 -161.061654)
		(end 194.8434 -190.285624)
		(width 0.17145)
		(layer "F.Cu")
		(net "DRIVE_B_27_INS")
	)
	(segment
		(start 131.438142 -37.347144)
		(end 131.438142 -84.469224)
		(width 0.17145)
		(layer "F.Cu")
		(net "DRIVE_B_27_INS")
	)
	(segment
		(start 201.197972 -196.640196)
		(end 201.197972 -210.467448)
		(width 0.17145)
		(layer "F.Cu")
		(net "DRIVE_B_27_INS")
	)
	(segment
		(start 201.197972 -210.467448)
		(end 202.062334 -211.33181)
		(width 0.17145)
		(layer "F.Cu")
		(net "DRIVE_B_27_INS")
	)
	(segment
		(start 210.896708 -210.9216)
		(end 213.0806 -210.9216)
		(width 0.17145)
		(layer "F.Cu")
		(net "DRIVE_B_27_INS")
	)
	(segment
		(start 194.8434 -190.285624)
		(end 201.197972 -196.640196)
		(width 0.17145)
		(layer "F.Cu")
		(net "DRIVE_B_27_INS")
	)
	(segment
		(start 131.438142 -102.56266)
		(end 140.999718 -112.124236)
		(width 0.17145)
		(layer "F.Cu")
		(net "DRIVE_B_27_INS")
	)
	(segment
		(start 202.062334 -211.33181)
		(end 210.486498 -211.33181)
		(width 0.17145)
		(layer "F.Cu")
		(net "DRIVE_B_27_INS")
	)
	(segment
		(start 186.75223 -112.124236)
		(end 197.324218 -122.696224)
		(width 0.17145)
		(layer "F.Cu")
		(net "DRIVE_B_27_INS")
	)
	(via
		(at 131.438142 -84.469224)
		(size 0.6604)
		(drill 0.3302)
		(layers "F.Cu" "B.Cu")
		(net "DRIVE_B_27_INS")
	)
	(via
		(at 230.247444 -83.953096)
		(size 0.5588)
		(drill 0.3048)
		(layers "F.Cu" "B.Cu")
		(net "DRIVE_B_27_ACT")
	)
	(via
		(at 259.752084 -101.905308)
		(size 0.6096)
		(drill 0.3048)
		(layers "F.Cu" "B.Cu")
		(net "DRIVE_B_27_ACT")
	)
	(via
		(at 292.3286 -123.2154)
		(size 0.5588)
		(drill 0.3048)
		(layers "F.Cu" "B.Cu")
		(net "DRIVE_B_27_ACT")
	)
	(segment
		(start 263.472676 -105.664254)
		(end 263.51103 -105.664254)
		(width 0.17145)
		(layer "B.Cu")
		(net "DRIVE_B_27_ACT")
	)
	(segment
		(start 241.531648 -87.037672)
		(end 232.592118 -87.037672)
		(width 0.17145)
		(layer "B.Cu")
		(net "DRIVE_B_27_ACT")
	)
	(segment
		(start 230.247444 -84.692998)
		(end 230.247444 -83.953096)
		(width 0.17145)
		(layer "B.Cu")
		(net "DRIVE_B_27_ACT")
	)
	(segment
		(start 247.783096 -93.28912)
		(end 241.531648 -87.037672)
		(width 0.17145)
		(layer "B.Cu")
		(net "DRIVE_B_27_ACT")
	)
	(segment
		(start 266.273026 -108.42498)
		(end 266.591288 -108.743242)
		(width 0.17145)
		(layer "B.Cu")
		(net "DRIVE_B_27_ACT")
	)
	(segment
		(start 232.592118 -87.037672)
		(end 230.247444 -84.692998)
		(width 0.17145)
		(layer "B.Cu")
		(net "DRIVE_B_27_ACT")
	)
	(segment
		(start 259.752084 -101.905308)
		(end 251.135896 -93.28912)
		(width 0.17145)
		(layer "B.Cu")
		(net "DRIVE_B_27_ACT")
	)
	(segment
		(start 259.752084 -101.905308)
		(end 263.154414 -105.307638)
		(width 0.17145)
		(layer "B.Cu")
		(net "DRIVE_B_27_ACT")
	)
	(segment
		(start 266.271756 -108.42498)
		(end 266.273026 -108.42498)
		(width 0.17145)
		(layer "B.Cu")
		(net "DRIVE_B_27_ACT")
	)
	(segment
		(start 263.51103 -105.664254)
		(end 266.271756 -108.42498)
		(width 0.17145)
		(layer "B.Cu")
		(net "DRIVE_B_27_ACT")
	)
	(segment
		(start 263.154414 -105.345992)
		(end 263.472676 -105.664254)
		(width 0.17145)
		(layer "B.Cu")
		(net "DRIVE_B_27_ACT")
	)
	(segment
		(start 292.06825 -123.47575)
		(end 292.3286 -123.2154)
		(width 0.17145)
		(layer "B.Cu")
		(net "DRIVE_B_27_ACT")
	)
	(segment
		(start 263.154414 -105.307638)
		(end 263.154414 -105.345992)
		(width 0.17145)
		(layer "B.Cu")
		(net "DRIVE_B_27_ACT")
	)
	(segment
		(start 266.591288 -108.743242)
		(end 266.591288 -108.744512)
		(width 0.17145)
		(layer "B.Cu")
		(net "DRIVE_B_27_ACT")
	)
	(segment
		(start 281.322526 -123.47575)
		(end 292.06825 -123.47575)
		(width 0.17145)
		(layer "B.Cu")
		(net "DRIVE_B_27_ACT")
	)
	(segment
		(start 266.591288 -108.744512)
		(end 281.322526 -123.47575)
		(width 0.17145)
		(layer "B.Cu")
		(net "DRIVE_B_27_ACT")
	)
	(segment
		(start 251.135896 -93.28912)
		(end 247.783096 -93.28912)
		(width 0.17145)
		(layer "B.Cu")
		(net "DRIVE_B_27_ACT")
	)
	(segment
		(start 229.80015 -70.61835)
		(end 230.45801 -71.27621)
		(width 0.14605)
		(layer "In2.Cu")
		(net "DRIVE_B_27_ACT")
	)
	(segment
		(start 293.17696 -179.610258)
		(end 293.177214 -179.610258)
		(width 0.14605)
		(layer "In2.Cu")
		(net "DRIVE_B_27_ACT")
	)
	(segment
		(start 283.550614 -184.063386)
		(end 288.723324 -184.063386)
		(width 0.14605)
		(layer "In2.Cu")
		(net "DRIVE_B_27_ACT")
	)
	(segment
		(start 293.647114 -146.989038)
		(end 293.829994 -146.806158)
		(width 0.14605)
		(layer "In2.Cu")
		(net "DRIVE_B_27_ACT")
	)
	(segment
		(start 293.177214 -179.610258)
		(end 293.647114 -179.140358)
		(width 0.14605)
		(layer "In2.Cu")
		(net "DRIVE_B_27_ACT")
	)
	(segment
		(start 292.874192 -179.912518)
		(end 292.874446 -179.912518)
		(width 0.14605)
		(layer "In2.Cu")
		(net "DRIVE_B_27_ACT")
	)
	(segment
		(start 293.130732 -179.656232)
		(end 293.130986 -179.656232)
		(width 0.14605)
		(layer "In2.Cu")
		(net "DRIVE_B_27_ACT")
	)
	(segment
		(start 230.45801 -83.74253)
		(end 230.247444 -83.953096)
		(width 0.14605)
		(layer "In2.Cu")
		(net "DRIVE_B_27_ACT")
	)
	(segment
		(start 230.45801 -71.27621)
		(end 230.45801 -83.74253)
		(width 0.14605)
		(layer "In2.Cu")
		(net "DRIVE_B_27_ACT")
	)
	(segment
		(start 282.919424 -184.694576)
		(end 283.550614 -184.063386)
		(width 0.14605)
		(layer "In2.Cu")
		(net "DRIVE_B_27_ACT")
	)
	(segment
		(start 229.80015 -70.39991)
		(end 229.80015 -70.61835)
		(width 0.14605)
		(layer "In2.Cu")
		(net "DRIVE_B_27_ACT")
	)
	(segment
		(start 288.723324 -184.063386)
		(end 292.874192 -179.912518)
		(width 0.14605)
		(layer "In2.Cu")
		(net "DRIVE_B_27_ACT")
	)
	(segment
		(start 293.829994 -146.806158)
		(end 293.829994 -124.742194)
		(width 0.14605)
		(layer "In2.Cu")
		(net "DRIVE_B_27_ACT")
	)
	(segment
		(start 293.829994 -124.742194)
		(end 292.3286 -123.2408)
		(width 0.14605)
		(layer "In2.Cu")
		(net "DRIVE_B_27_ACT")
	)
	(segment
		(start 282.83662 -184.694576)
		(end 282.919424 -184.694576)
		(width 0.14605)
		(layer "In2.Cu")
		(net "DRIVE_B_27_ACT")
	)
	(segment
		(start 292.874446 -179.912518)
		(end 293.130732 -179.656232)
		(width 0.14605)
		(layer "In2.Cu")
		(net "DRIVE_B_27_ACT")
	)
	(segment
		(start 292.3286 -123.2408)
		(end 292.3286 -123.2154)
		(width 0.14605)
		(layer "In2.Cu")
		(net "DRIVE_B_27_ACT")
	)
	(segment
		(start 293.130986 -179.656232)
		(end 293.17696 -179.610258)
		(width 0.14605)
		(layer "In2.Cu")
		(net "DRIVE_B_27_ACT")
	)
	(segment
		(start 293.647114 -179.140358)
		(end 293.647114 -146.989038)
		(width 0.14605)
		(layer "In2.Cu")
		(net "DRIVE_B_27_ACT")
	)
	(segment
		(start 232.971594 -201.501756)
		(end 233.69143 -201.501756)
		(width 0.17145)
		(layer "F.Cu")
		(net "DRIVE_B_26_PWR")
	)
	(segment
		(start 231.981502 -201.501756)
		(end 231.8512 -201.371454)
		(width 0.17145)
		(layer "F.Cu")
		(net "DRIVE_B_26_PWR")
	)
	(segment
		(start 232.971594 -201.501756)
		(end 231.981502 -201.501756)
		(width 0.17145)
		(layer "F.Cu")
		(net "DRIVE_B_26_PWR")
	)
	(segment
		(start 233.69143 -201.501756)
		(end 233.832146 -201.36104)
		(width 0.17145)
		(layer "F.Cu")
		(net "DRIVE_B_26_PWR")
	)
	(segment
		(start 85.9663 -16.1798)
		(end 86.8172 -16.1798)
		(width 0.17145)
		(layer "F.Cu")
		(net "DRIVE_B_26_PWR")
	)
	(segment
		(start 233.832146 -201.36104)
		(end 235.0516 -201.36104)
		(width 0.17145)
		(layer "F.Cu")
		(net "DRIVE_B_26_PWR")
	)
	(segment
		(start 231.8512 -201.371454)
		(end 231.841548 -201.371454)
		(width 0.17145)
		(layer "F.Cu")
		(net "DRIVE_B_26_PWR")
	)
	(via
		(at 231.841548 -201.371454)
		(size 0.5588)
		(drill 0.3048)
		(layers "F.Cu" "B.Cu")
		(net "DRIVE_B_26_PWR")
	)
	(via
		(at 183.642 -187.7568)
		(size 0.5588)
		(drill 0.3048)
		(layers "F.Cu" "B.Cu")
		(net "DRIVE_B_26_PWR")
	)
	(via
		(at 232.971594 -201.501756)
		(size 0.6604)
		(drill 0.3302)
		(layers "F.Cu" "B.Cu")
		(net "DRIVE_B_26_PWR")
	)
	(via
		(at 86.8172 -16.1798)
		(size 0.5588)
		(drill 0.3048)
		(layers "F.Cu" "B.Cu")
		(net "DRIVE_B_26_PWR")
	)
	(segment
		(start 89.73312 -19.875246)
		(end 114.475514 -44.61764)
		(width 0.14605)
		(layer "In2.Cu")
		(net "DRIVE_B_26_PWR")
	)
	(segment
		(start 86.8172 -16.1798)
		(end 87.6808 -16.1798)
		(width 0.14605)
		(layer "In2.Cu")
		(net "DRIVE_B_26_PWR")
	)
	(segment
		(start 183.642 -176.82972)
		(end 183.642 -187.7568)
		(width 0.14605)
		(layer "In2.Cu")
		(net "DRIVE_B_26_PWR")
	)
	(segment
		(start 198.174864 -83.70189)
		(end 198.174864 -111.06404)
		(width 0.14605)
		(layer "In2.Cu")
		(net "DRIVE_B_26_PWR")
	)
	(segment
		(start 114.475514 -44.61764)
		(end 159.090614 -44.61764)
		(width 0.14605)
		(layer "In2.Cu")
		(net "DRIVE_B_26_PWR")
	)
	(segment
		(start 89.73312 -18.23212)
		(end 89.73312 -19.875246)
		(width 0.14605)
		(layer "In2.Cu")
		(net "DRIVE_B_26_PWR")
	)
	(segment
		(start 87.6808 -16.1798)
		(end 89.73312 -18.23212)
		(width 0.14605)
		(layer "In2.Cu")
		(net "DRIVE_B_26_PWR")
	)
	(segment
		(start 193.0908 -140.70965)
		(end 193.0908 -167.38092)
		(width 0.14605)
		(layer "In2.Cu")
		(net "DRIVE_B_26_PWR")
	)
	(segment
		(start 198.174864 -111.06404)
		(end 202.61326 -115.502436)
		(width 0.14605)
		(layer "In2.Cu")
		(net "DRIVE_B_26_PWR")
	)
	(segment
		(start 193.0908 -167.38092)
		(end 183.642 -176.82972)
		(width 0.14605)
		(layer "In2.Cu")
		(net "DRIVE_B_26_PWR")
	)
	(segment
		(start 159.090614 -44.61764)
		(end 198.174864 -83.70189)
		(width 0.14605)
		(layer "In2.Cu")
		(net "DRIVE_B_26_PWR")
	)
	(segment
		(start 202.61326 -115.502436)
		(end 202.61326 -131.18719)
		(width 0.14605)
		(layer "In2.Cu")
		(net "DRIVE_B_26_PWR")
	)
	(segment
		(start 202.61326 -131.18719)
		(end 193.0908 -140.70965)
		(width 0.14605)
		(layer "In2.Cu")
		(net "DRIVE_B_26_PWR")
	)
	(segment
		(start 191.267842 -190.460884)
		(end 185.32729 -190.460884)
		(width 0.14605)
		(layer "In5.Cu")
		(net "DRIVE_B_26_PWR")
	)
	(segment
		(start 231.841548 -201.371454)
		(end 231.484424 -201.01433)
		(width 0.14605)
		(layer "In5.Cu")
		(net "DRIVE_B_26_PWR")
	)
	(segment
		(start 185.32729 -190.460884)
		(end 184.3278 -189.461394)
		(width 0.14605)
		(layer "In5.Cu")
		(net "DRIVE_B_26_PWR")
	)
	(segment
		(start 231.484424 -201.01433)
		(end 228.95433 -201.01433)
		(width 0.14605)
		(layer "In5.Cu")
		(net "DRIVE_B_26_PWR")
	)
	(segment
		(start 200.888854 -200.081896)
		(end 191.267842 -190.460884)
		(width 0.14605)
		(layer "In5.Cu")
		(net "DRIVE_B_26_PWR")
	)
	(segment
		(start 228.021896 -200.081896)
		(end 200.888854 -200.081896)
		(width 0.14605)
		(layer "In5.Cu")
		(net "DRIVE_B_26_PWR")
	)
	(segment
		(start 184.3278 -188.4426)
		(end 183.642 -187.7568)
		(width 0.14605)
		(layer "In5.Cu")
		(net "DRIVE_B_26_PWR")
	)
	(segment
		(start 184.3278 -189.461394)
		(end 184.3278 -188.4426)
		(width 0.14605)
		(layer "In5.Cu")
		(net "DRIVE_B_26_PWR")
	)
	(segment
		(start 228.95433 -201.01433)
		(end 228.021896 -200.081896)
		(width 0.14605)
		(layer "In5.Cu")
		(net "DRIVE_B_26_PWR")
	)
	(segment
		(start 196.809868 -122.90933)
		(end 196.809868 -157.974284)
		(width 0.17145)
		(layer "F.Cu")
		(net "DRIVE_B_26_INS")
	)
	(segment
		(start 200.683622 -196.853556)
		(end 200.683622 -210.680554)
		(width 0.17145)
		(layer "F.Cu")
		(net "DRIVE_B_26_INS")
	)
	(segment
		(start 196.809868 -157.974284)
		(end 194.32905 -160.455102)
		(width 0.17145)
		(layer "F.Cu")
		(net "DRIVE_B_26_INS")
	)
	(segment
		(start 140.266166 -113.12144)
		(end 187.021978 -113.12144)
		(width 0.17145)
		(layer "F.Cu")
		(net "DRIVE_B_26_INS")
	)
	(segment
		(start 98.806 -33.6296)
		(end 98.806 -36.669218)
		(width 0.17145)
		(layer "F.Cu")
		(net "DRIVE_B_26_INS")
	)
	(segment
		(start 210.699604 -211.84616)
		(end 210.973924 -211.57184)
		(width 0.17145)
		(layer "F.Cu")
		(net "DRIVE_B_26_INS")
	)
	(segment
		(start 194.32905 -160.455102)
		(end 194.32905 -190.498984)
		(width 0.17145)
		(layer "F.Cu")
		(net "DRIVE_B_26_INS")
	)
	(segment
		(start 129.828544 -102.683818)
		(end 140.266166 -113.12144)
		(width 0.17145)
		(layer "F.Cu")
		(net "DRIVE_B_26_INS")
	)
	(segment
		(start 201.849228 -211.84616)
		(end 210.699604 -211.84616)
		(width 0.17145)
		(layer "F.Cu")
		(net "DRIVE_B_26_INS")
	)
	(segment
		(start 129.828544 -89.491312)
		(end 129.828544 -102.683818)
		(width 0.17145)
		(layer "F.Cu")
		(net "DRIVE_B_26_INS")
	)
	(segment
		(start 98.806 -36.669218)
		(end 129.828544 -67.691762)
		(width 0.17145)
		(layer "F.Cu")
		(net "DRIVE_B_26_INS")
	)
	(segment
		(start 129.828544 -67.691762)
		(end 129.828544 -89.491312)
		(width 0.17145)
		(layer "F.Cu")
		(net "DRIVE_B_26_INS")
	)
	(segment
		(start 194.32905 -190.498984)
		(end 200.683622 -196.853556)
		(width 0.17145)
		(layer "F.Cu")
		(net "DRIVE_B_26_INS")
	)
	(segment
		(start 200.683622 -210.680554)
		(end 201.849228 -211.84616)
		(width 0.17145)
		(layer "F.Cu")
		(net "DRIVE_B_26_INS")
	)
	(segment
		(start 210.973924 -211.57184)
		(end 213.0806 -211.57184)
		(width 0.17145)
		(layer "F.Cu")
		(net "DRIVE_B_26_INS")
	)
	(segment
		(start 187.021978 -113.12144)
		(end 196.809868 -122.90933)
		(width 0.17145)
		(layer "F.Cu")
		(net "DRIVE_B_26_INS")
	)
	(via
		(at 129.828544 -89.491312)
		(size 0.6604)
		(drill 0.3302)
		(layers "F.Cu" "B.Cu")
		(net "DRIVE_B_26_INS")
	)
	(via
		(at 292.090856 -122.332242)
		(size 0.5588)
		(drill 0.3048)
		(layers "F.Cu" "B.Cu")
		(net "DRIVE_B_26_ACT")
	)
	(via
		(at 263.697466 -105.121202)
		(size 0.6096)
		(drill 0.3048)
		(layers "F.Cu" "B.Cu")
		(net "DRIVE_B_26_ACT")
	)
	(via
		(at 230.945944 -84.643468)
		(size 0.5588)
		(drill 0.3048)
		(layers "F.Cu" "B.Cu")
		(net "DRIVE_B_26_ACT")
	)
	(segment
		(start 281.537664 -122.9614)
		(end 291.461698 -122.9614)
		(width 0.17145)
		(layer "B.Cu")
		(net "DRIVE_B_26_ACT")
	)
	(segment
		(start 263.697466 -105.121202)
		(end 281.537664 -122.9614)
		(width 0.17145)
		(layer "B.Cu")
		(net "DRIVE_B_26_ACT")
	)
	(segment
		(start 263.697466 -105.121202)
		(end 260.295136 -101.718872)
		(width 0.17145)
		(layer "B.Cu")
		(net "DRIVE_B_26_ACT")
	)
	(segment
		(start 251.351034 -92.77477)
		(end 247.996202 -92.77477)
		(width 0.17145)
		(layer "B.Cu")
		(net "DRIVE_B_26_ACT")
	)
	(segment
		(start 232.825798 -86.523322)
		(end 230.945944 -84.643468)
		(width 0.17145)
		(layer "B.Cu")
		(net "DRIVE_B_26_ACT")
	)
	(segment
		(start 259.93852 -101.362256)
		(end 251.351034 -92.77477)
		(width 0.17145)
		(layer "B.Cu")
		(net "DRIVE_B_26_ACT")
	)
	(segment
		(start 241.744754 -86.523322)
		(end 232.825798 -86.523322)
		(width 0.17145)
		(layer "B.Cu")
		(net "DRIVE_B_26_ACT")
	)
	(segment
		(start 260.295136 -101.718872)
		(end 260.295136 -101.680518)
		(width 0.17145)
		(layer "B.Cu")
		(net "DRIVE_B_26_ACT")
	)
	(segment
		(start 260.295136 -101.680518)
		(end 259.976874 -101.362256)
		(width 0.17145)
		(layer "B.Cu")
		(net "DRIVE_B_26_ACT")
	)
	(segment
		(start 291.461698 -122.9614)
		(end 292.090856 -122.332242)
		(width 0.17145)
		(layer "B.Cu")
		(net "DRIVE_B_26_ACT")
	)
	(segment
		(start 247.996202 -92.77477)
		(end 241.744754 -86.523322)
		(width 0.17145)
		(layer "B.Cu")
		(net "DRIVE_B_26_ACT")
	)
	(segment
		(start 259.976874 -101.362256)
		(end 259.93852 -101.362256)
		(width 0.17145)
		(layer "B.Cu")
		(net "DRIVE_B_26_ACT")
	)
	(segment
		(start 294.085264 -180.491638)
		(end 294.085264 -147.170648)
		(width 0.14605)
		(layer "In2.Cu")
		(net "DRIVE_B_26_ACT")
	)
	(segment
		(start 294.085264 -147.170648)
		(end 294.268144 -146.987768)
		(width 0.14605)
		(layer "In2.Cu")
		(net "DRIVE_B_26_ACT")
	)
	(segment
		(start 284.236668 -184.694576)
		(end 284.860492 -185.3184)
		(width 0.14605)
		(layer "In2.Cu")
		(net "DRIVE_B_26_ACT")
	)
	(segment
		(start 292.159436 -122.332242)
		(end 292.090856 -122.332242)
		(width 0.14605)
		(layer "In2.Cu")
		(net "DRIVE_B_26_ACT")
	)
	(segment
		(start 294.268144 -124.44095)
		(end 292.159436 -122.332242)
		(width 0.14605)
		(layer "In2.Cu")
		(net "DRIVE_B_26_ACT")
	)
	(segment
		(start 229.80015 -69.44995)
		(end 230.95966 -70.60946)
		(width 0.14605)
		(layer "In2.Cu")
		(net "DRIVE_B_26_ACT")
	)
	(segment
		(start 230.95966 -70.60946)
		(end 230.95966 -84.629752)
		(width 0.14605)
		(layer "In2.Cu")
		(net "DRIVE_B_26_ACT")
	)
	(segment
		(start 230.95966 -84.629752)
		(end 230.945944 -84.643468)
		(width 0.14605)
		(layer "In2.Cu")
		(net "DRIVE_B_26_ACT")
	)
	(segment
		(start 284.860492 -185.3184)
		(end 289.258502 -185.3184)
		(width 0.14605)
		(layer "In2.Cu")
		(net "DRIVE_B_26_ACT")
	)
	(segment
		(start 289.258502 -185.3184)
		(end 294.085264 -180.491638)
		(width 0.14605)
		(layer "In2.Cu")
		(net "DRIVE_B_26_ACT")
	)
	(segment
		(start 229.80015 -69.30009)
		(end 229.80015 -69.44995)
		(width 0.14605)
		(layer "In2.Cu")
		(net "DRIVE_B_26_ACT")
	)
	(segment
		(start 294.268144 -146.987768)
		(end 294.268144 -124.44095)
		(width 0.14605)
		(layer "In2.Cu")
		(net "DRIVE_B_26_ACT")
	)
	(segment
		(start 230.126032 -203.040488)
		(end 229.5398 -203.62672)
		(width 0.17145)
		(layer "F.Cu")
		(net "DRIVE_B_25_PWR")
	)
	(segment
		(start 230.597202 -202.569318)
		(end 230.126032 -203.040488)
		(width 0.17145)
		(layer "F.Cu")
		(net "DRIVE_B_25_PWR")
	)
	(segment
		(start 235.0516 -202.01128)
		(end 233.785664 -202.01128)
		(width 0.17145)
		(layer "F.Cu")
		(net "DRIVE_B_25_PWR")
	)
	(segment
		(start 233.785664 -202.01128)
		(end 233.227626 -202.569318)
		(width 0.17145)
		(layer "F.Cu")
		(net "DRIVE_B_25_PWR")
	)
	(segment
		(start 55.88 -19.6215)
		(end 55.88 -20.447)
		(width 0.17145)
		(layer "F.Cu")
		(net "DRIVE_B_25_PWR")
	)
	(segment
		(start 229.5398 -203.62672)
		(end 229.5398 -204.0128)
		(width 0.17145)
		(layer "F.Cu")
		(net "DRIVE_B_25_PWR")
	)
	(segment
		(start 233.227626 -202.569318)
		(end 230.597202 -202.569318)
		(width 0.17145)
		(layer "F.Cu")
		(net "DRIVE_B_25_PWR")
	)
	(via
		(at 182.4228 -188.976)
		(size 0.5588)
		(drill 0.3048)
		(layers "F.Cu" "B.Cu")
		(net "DRIVE_B_25_PWR")
	)
	(via
		(at 229.5398 -204.0128)
		(size 0.5588)
		(drill 0.3048)
		(layers "F.Cu" "B.Cu")
		(net "DRIVE_B_25_PWR")
	)
	(via
		(at 230.126032 -203.040488)
		(size 0.6604)
		(drill 0.3302)
		(layers "F.Cu" "B.Cu")
		(net "DRIVE_B_25_PWR")
	)
	(via
		(at 55.88 -20.447)
		(size 0.5588)
		(drill 0.3048)
		(layers "F.Cu" "B.Cu")
		(net "DRIVE_B_25_PWR")
	)
	(segment
		(start 202.109324 -130.978402)
		(end 192.28435 -140.803376)
		(width 0.14605)
		(layer "In2.Cu")
		(net "DRIVE_B_25_PWR")
	)
	(segment
		(start 192.28435 -140.803376)
		(end 192.28435 -167.56761)
		(width 0.14605)
		(layer "In2.Cu")
		(net "DRIVE_B_25_PWR")
	)
	(segment
		(start 197.670674 -111.206026)
		(end 202.109324 -115.644676)
		(width 0.14605)
		(layer "In2.Cu")
		(net "DRIVE_B_25_PWR")
	)
	(segment
		(start 183.0324 -188.3664)
		(end 182.4228 -188.976)
		(width 0.14605)
		(layer "In2.Cu")
		(net "DRIVE_B_25_PWR")
	)
	(segment
		(start 183.0324 -176.81956)
		(end 183.0324 -188.3664)
		(width 0.14605)
		(layer "In2.Cu")
		(net "DRIVE_B_25_PWR")
	)
	(segment
		(start 202.109324 -115.644676)
		(end 202.109324 -130.978402)
		(width 0.14605)
		(layer "In2.Cu")
		(net "DRIVE_B_25_PWR")
	)
	(segment
		(start 192.28435 -167.56761)
		(end 183.0324 -176.81956)
		(width 0.14605)
		(layer "In2.Cu")
		(net "DRIVE_B_25_PWR")
	)
	(segment
		(start 197.670674 -83.81746)
		(end 197.670674 -111.206026)
		(width 0.14605)
		(layer "In2.Cu")
		(net "DRIVE_B_25_PWR")
	)
	(segment
		(start 56.042814 -20.447)
		(end 80.717644 -45.12183)
		(width 0.14605)
		(layer "In2.Cu")
		(net "DRIVE_B_25_PWR")
	)
	(segment
		(start 55.88 -20.447)
		(end 56.042814 -20.447)
		(width 0.14605)
		(layer "In2.Cu")
		(net "DRIVE_B_25_PWR")
	)
	(segment
		(start 80.717644 -45.12183)
		(end 158.975044 -45.12183)
		(width 0.14605)
		(layer "In2.Cu")
		(net "DRIVE_B_25_PWR")
	)
	(segment
		(start 158.975044 -45.12183)
		(end 197.670674 -83.81746)
		(width 0.14605)
		(layer "In2.Cu")
		(net "DRIVE_B_25_PWR")
	)
	(segment
		(start 226.9236 -201.3966)
		(end 200.344278 -201.3966)
		(width 0.14605)
		(layer "In5.Cu")
		(net "DRIVE_B_25_PWR")
	)
	(segment
		(start 229.5398 -204.0128)
		(end 226.9236 -201.3966)
		(width 0.14605)
		(layer "In5.Cu")
		(net "DRIVE_B_25_PWR")
	)
	(segment
		(start 200.344278 -201.3966)
		(end 190.790322 -191.842644)
		(width 0.14605)
		(layer "In5.Cu")
		(net "DRIVE_B_25_PWR")
	)
	(segment
		(start 184.573164 -191.842644)
		(end 182.4228 -189.69228)
		(width 0.14605)
		(layer "In5.Cu")
		(net "DRIVE_B_25_PWR")
	)
	(segment
		(start 182.4228 -189.69228)
		(end 182.4228 -188.976)
		(width 0.14605)
		(layer "In5.Cu")
		(net "DRIVE_B_25_PWR")
	)
	(segment
		(start 190.790322 -191.842644)
		(end 184.573164 -191.842644)
		(width 0.14605)
		(layer "In5.Cu")
		(net "DRIVE_B_25_PWR")
	)
	(segment
		(start 114.568732 -54.427882)
		(end 128.283208 -68.142358)
		(width 0.17145)
		(layer "F.Cu")
		(net "DRIVE_B_25_INS")
	)
	(segment
		(start 128.283208 -102.869746)
		(end 139.306808 -113.893346)
		(width 0.17145)
		(layer "F.Cu")
		(net "DRIVE_B_25_INS")
	)
	(segment
		(start 196.295518 -157.761178)
		(end 193.8147 -160.241996)
		(width 0.17145)
		(layer "F.Cu")
		(net "DRIVE_B_25_INS")
	)
	(segment
		(start 210.91271 -212.36051)
		(end 211.05114 -212.22208)
		(width 0.17145)
		(layer "F.Cu")
		(net "DRIVE_B_25_INS")
	)
	(segment
		(start 67.31 -33.5788)
		(end 67.31 -36.462462)
		(width 0.17145)
		(layer "F.Cu")
		(net "DRIVE_B_25_INS")
	)
	(segment
		(start 200.169272 -197.21195)
		(end 200.169272 -210.89366)
		(width 0.17145)
		(layer "F.Cu")
		(net "DRIVE_B_25_INS")
	)
	(segment
		(start 196.295518 -123.122436)
		(end 196.295518 -157.761178)
		(width 0.17145)
		(layer "F.Cu")
		(net "DRIVE_B_25_INS")
	)
	(segment
		(start 68.435728 -54.427882)
		(end 114.568732 -54.427882)
		(width 0.17145)
		(layer "F.Cu")
		(net "DRIVE_B_25_INS")
	)
	(segment
		(start 128.283208 -68.142358)
		(end 128.283208 -93.612208)
		(width 0.17145)
		(layer "F.Cu")
		(net "DRIVE_B_25_INS")
	)
	(segment
		(start 67.31 -36.462462)
		(end 67.888866 -37.041328)
		(width 0.17145)
		(layer "F.Cu")
		(net "DRIVE_B_25_INS")
	)
	(segment
		(start 193.8147 -190.857378)
		(end 200.169272 -197.21195)
		(width 0.17145)
		(layer "F.Cu")
		(net "DRIVE_B_25_INS")
	)
	(segment
		(start 193.8147 -160.241996)
		(end 193.8147 -190.857378)
		(width 0.17145)
		(layer "F.Cu")
		(net "DRIVE_B_25_INS")
	)
	(segment
		(start 187.066428 -113.893346)
		(end 196.295518 -123.122436)
		(width 0.17145)
		(layer "F.Cu")
		(net "DRIVE_B_25_INS")
	)
	(segment
		(start 67.888866 -37.041328)
		(end 67.888866 -53.88102)
		(width 0.17145)
		(layer "F.Cu")
		(net "DRIVE_B_25_INS")
	)
	(segment
		(start 200.169272 -210.89366)
		(end 201.636122 -212.36051)
		(width 0.17145)
		(layer "F.Cu")
		(net "DRIVE_B_25_INS")
	)
	(segment
		(start 201.636122 -212.36051)
		(end 210.91271 -212.36051)
		(width 0.17145)
		(layer "F.Cu")
		(net "DRIVE_B_25_INS")
	)
	(segment
		(start 211.05114 -212.22208)
		(end 213.0806 -212.22208)
		(width 0.17145)
		(layer "F.Cu")
		(net "DRIVE_B_25_INS")
	)
	(segment
		(start 67.888866 -53.88102)
		(end 68.435728 -54.427882)
		(width 0.17145)
		(layer "F.Cu")
		(net "DRIVE_B_25_INS")
	)
	(segment
		(start 128.283208 -93.612208)
		(end 128.283208 -102.869746)
		(width 0.17145)
		(layer "F.Cu")
		(net "DRIVE_B_25_INS")
	)
	(segment
		(start 139.306808 -113.893346)
		(end 187.066428 -113.893346)
		(width 0.17145)
		(layer "F.Cu")
		(net "DRIVE_B_25_INS")
	)
	(via
		(at 128.283208 -93.612208)
		(size 0.6604)
		(drill 0.3302)
		(layers "F.Cu" "B.Cu")
		(net "DRIVE_B_25_INS")
	)
	(via
		(at 292.7604 -118.99138)
		(size 0.5588)
		(drill 0.3048)
		(layers "F.Cu" "B.Cu")
		(net "DRIVE_B_25_ACT")
	)
	(segment
		(start 294.706294 -122.951494)
		(end 293.146988 -121.392188)
		(width 0.14605)
		(layer "In2.Cu")
		(net "DRIVE_B_25_ACT")
	)
	(segment
		(start 293.146988 -119.377968)
		(end 292.7604 -118.99138)
		(width 0.14605)
		(layer "In2.Cu")
		(net "DRIVE_B_25_ACT")
	)
	(segment
		(start 289.370516 -185.8264)
		(end 294.523414 -180.673502)
		(width 0.14605)
		(layer "In2.Cu")
		(net "DRIVE_B_25_ACT")
	)
	(segment
		(start 281.836622 -186.49442)
		(end 282.504642 -185.8264)
		(width 0.14605)
		(layer "In2.Cu")
		(net "DRIVE_B_25_ACT")
	)
	(segment
		(start 282.504642 -185.8264)
		(end 289.370516 -185.8264)
		(width 0.14605)
		(layer "In2.Cu")
		(net "DRIVE_B_25_ACT")
	)
	(segment
		(start 294.523414 -147.352258)
		(end 294.706294 -147.169378)
		(width 0.14605)
		(layer "In2.Cu")
		(net "DRIVE_B_25_ACT")
	)
	(segment
		(start 294.706294 -147.169378)
		(end 294.706294 -122.951494)
		(width 0.14605)
		(layer "In2.Cu")
		(net "DRIVE_B_25_ACT")
	)
	(segment
		(start 294.523414 -180.673502)
		(end 294.523414 -147.352258)
		(width 0.14605)
		(layer "In2.Cu")
		(net "DRIVE_B_25_ACT")
	)
	(segment
		(start 293.146988 -121.392188)
		(end 293.146988 -119.377968)
		(width 0.14605)
		(layer "In2.Cu")
		(net "DRIVE_B_25_ACT")
	)
	(segment
		(start 277.85949 -118.25605)
		(end 292.02507 -118.25605)
		(width 0.14605)
		(layer "In5.Cu")
		(net "DRIVE_B_25_ACT")
	)
	(segment
		(start 230.455724 -80.883506)
		(end 251.99467 -102.422452)
		(width 0.14605)
		(layer "In5.Cu")
		(net "DRIVE_B_25_ACT")
	)
	(segment
		(start 262.025892 -102.422452)
		(end 277.85949 -118.25605)
		(width 0.14605)
		(layer "In5.Cu")
		(net "DRIVE_B_25_ACT")
	)
	(segment
		(start 230.455724 -68.85559)
		(end 230.455724 -80.883506)
		(width 0.14605)
		(layer "In5.Cu")
		(net "DRIVE_B_25_ACT")
	)
	(segment
		(start 292.02507 -118.25605)
		(end 292.7604 -118.99138)
		(width 0.14605)
		(layer "In5.Cu")
		(net "DRIVE_B_25_ACT")
	)
	(segment
		(start 229.80015 -68.200016)
		(end 230.455724 -68.85559)
		(width 0.14605)
		(layer "In5.Cu")
		(net "DRIVE_B_25_ACT")
	)
	(segment
		(start 251.99467 -102.422452)
		(end 262.025892 -102.422452)
		(width 0.14605)
		(layer "In5.Cu")
		(net "DRIVE_B_25_ACT")
	)
	(segment
		(start 230.922576 -204.049884)
		(end 231.544114 -203.428346)
		(width 0.17145)
		(layer "F.Cu")
		(net "DRIVE_B_24_PWR")
	)
	(segment
		(start 231.544114 -203.428346)
		(end 232.053638 -203.428346)
		(width 0.17145)
		(layer "F.Cu")
		(net "DRIVE_B_24_PWR")
	)
	(segment
		(start 234.101894 -202.66152)
		(end 235.0516 -202.66152)
		(width 0.17145)
		(layer "F.Cu")
		(net "DRIVE_B_24_PWR")
	)
	(segment
		(start 22.6187 -15.9512)
		(end 23.495 -15.9512)
		(width 0.17145)
		(layer "F.Cu")
		(net "DRIVE_B_24_PWR")
	)
	(segment
		(start 233.335068 -203.428346)
		(end 234.101894 -202.66152)
		(width 0.17145)
		(layer "F.Cu")
		(net "DRIVE_B_24_PWR")
	)
	(segment
		(start 232.053638 -203.428346)
		(end 233.335068 -203.428346)
		(width 0.17145)
		(layer "F.Cu")
		(net "DRIVE_B_24_PWR")
	)
	(via
		(at 230.922576 -204.049884)
		(size 0.5588)
		(drill 0.3048)
		(layers "F.Cu" "B.Cu")
		(net "DRIVE_B_24_PWR")
	)
	(via
		(at 232.053638 -203.428346)
		(size 0.6604)
		(drill 0.3302)
		(layers "F.Cu" "B.Cu")
		(net "DRIVE_B_24_PWR")
	)
	(via
		(at 23.495 -15.9512)
		(size 0.5588)
		(drill 0.3048)
		(layers "F.Cu" "B.Cu")
		(net "DRIVE_B_24_PWR")
	)
	(via
		(at 182.3974 -187.579)
		(size 0.5588)
		(drill 0.3048)
		(layers "F.Cu" "B.Cu")
		(net "DRIVE_B_24_PWR")
	)
	(segment
		(start 43.564048 -35.896042)
		(end 53.227986 -45.55998)
		(width 0.14605)
		(layer "In2.Cu")
		(net "DRIVE_B_24_PWR")
	)
	(segment
		(start 182.3974 -176.8348)
		(end 182.3974 -187.579)
		(width 0.14605)
		(layer "In2.Cu")
		(net "DRIVE_B_24_PWR")
	)
	(segment
		(start 24.3332 -15.9512)
		(end 43.564048 -35.182048)
		(width 0.14605)
		(layer "In2.Cu")
		(net "DRIVE_B_24_PWR")
	)
	(segment
		(start 197.232524 -83.99907)
		(end 197.232524 -111.473996)
		(width 0.14605)
		(layer "In2.Cu")
		(net "DRIVE_B_24_PWR")
	)
	(segment
		(start 53.227986 -45.55998)
		(end 158.793434 -45.55998)
		(width 0.14605)
		(layer "In2.Cu")
		(net "DRIVE_B_24_PWR")
	)
	(segment
		(start 201.671174 -130.796792)
		(end 191.8462 -140.621766)
		(width 0.14605)
		(layer "In2.Cu")
		(net "DRIVE_B_24_PWR")
	)
	(segment
		(start 197.232524 -111.473996)
		(end 201.671174 -115.912646)
		(width 0.14605)
		(layer "In2.Cu")
		(net "DRIVE_B_24_PWR")
	)
	(segment
		(start 43.564048 -35.182048)
		(end 43.564048 -35.896042)
		(width 0.14605)
		(layer "In2.Cu")
		(net "DRIVE_B_24_PWR")
	)
	(segment
		(start 158.793434 -45.55998)
		(end 197.232524 -83.99907)
		(width 0.14605)
		(layer "In2.Cu")
		(net "DRIVE_B_24_PWR")
	)
	(segment
		(start 191.8462 -167.386)
		(end 182.3974 -176.8348)
		(width 0.14605)
		(layer "In2.Cu")
		(net "DRIVE_B_24_PWR")
	)
	(segment
		(start 23.495 -15.9512)
		(end 24.3332 -15.9512)
		(width 0.14605)
		(layer "In2.Cu")
		(net "DRIVE_B_24_PWR")
	)
	(segment
		(start 191.8462 -140.621766)
		(end 191.8462 -167.386)
		(width 0.14605)
		(layer "In2.Cu")
		(net "DRIVE_B_24_PWR")
	)
	(segment
		(start 201.671174 -115.912646)
		(end 201.671174 -130.796792)
		(width 0.14605)
		(layer "In2.Cu")
		(net "DRIVE_B_24_PWR")
	)
	(segment
		(start 230.922576 -203.185776)
		(end 230.909876 -203.173076)
		(width 0.14605)
		(layer "In5.Cu")
		(net "DRIVE_B_24_PWR")
	)
	(segment
		(start 230.922576 -204.049884)
		(end 230.922576 -203.185776)
		(width 0.14605)
		(layer "In5.Cu")
		(net "DRIVE_B_24_PWR")
	)
	(segment
		(start 183.0324 -189.68212)
		(end 183.0324 -188.214)
		(width 0.14605)
		(layer "In5.Cu")
		(net "DRIVE_B_24_PWR")
	)
	(segment
		(start 230.909876 -203.173076)
		(end 230.909876 -203.171552)
		(width 0.14605)
		(layer "In5.Cu")
		(net "DRIVE_B_24_PWR")
	)
	(segment
		(start 230.909876 -203.171552)
		(end 230.089456 -202.351132)
		(width 0.14605)
		(layer "In5.Cu")
		(net "DRIVE_B_24_PWR")
	)
	(segment
		(start 183.0324 -188.214)
		(end 182.3974 -187.579)
		(width 0.14605)
		(layer "In5.Cu")
		(net "DRIVE_B_24_PWR")
	)
	(segment
		(start 227.374196 -200.958196)
		(end 200.525634 -200.958196)
		(width 0.14605)
		(layer "In5.Cu")
		(net "DRIVE_B_24_PWR")
	)
	(segment
		(start 200.525634 -200.958196)
		(end 190.904622 -191.337184)
		(width 0.14605)
		(layer "In5.Cu")
		(net "DRIVE_B_24_PWR")
	)
	(segment
		(start 190.904622 -191.337184)
		(end 184.687464 -191.337184)
		(width 0.14605)
		(layer "In5.Cu")
		(net "DRIVE_B_24_PWR")
	)
	(segment
		(start 228.767132 -202.351132)
		(end 227.374196 -200.958196)
		(width 0.14605)
		(layer "In5.Cu")
		(net "DRIVE_B_24_PWR")
	)
	(segment
		(start 184.687464 -191.337184)
		(end 183.0324 -189.68212)
		(width 0.14605)
		(layer "In5.Cu")
		(net "DRIVE_B_24_PWR")
	)
	(segment
		(start 230.089456 -202.351132)
		(end 228.767132 -202.351132)
		(width 0.14605)
		(layer "In5.Cu")
		(net "DRIVE_B_24_PWR")
	)
	(segment
		(start 211.128356 -212.87232)
		(end 213.0806 -212.87232)
		(width 0.17145)
		(layer "F.Cu")
		(net "DRIVE_B_24_INS")
	)
	(segment
		(start 126.737872 -68.303394)
		(end 126.737872 -75.390756)
		(width 0.17145)
		(layer "F.Cu")
		(net "DRIVE_B_24_INS")
	)
	(segment
		(start 113.376964 -54.942486)
		(end 126.737872 -68.303394)
		(width 0.17145)
		(layer "F.Cu")
		(net "DRIVE_B_24_INS")
	)
	(segment
		(start 193.30035 -191.070484)
		(end 199.654922 -197.425056)
		(width 0.17145)
		(layer "F.Cu")
		(net "DRIVE_B_24_INS")
	)
	(segment
		(start 199.654922 -197.425056)
		(end 199.654922 -211.106766)
		(width 0.17145)
		(layer "F.Cu")
		(net "DRIVE_B_24_INS")
	)
	(segment
		(start 35.687 -33.5534)
		(end 35.687 -49.430178)
		(width 0.17145)
		(layer "F.Cu")
		(net "DRIVE_B_24_INS")
	)
	(segment
		(start 195.781168 -157.275276)
		(end 193.30035 -159.756094)
		(width 0.17145)
		(layer "F.Cu")
		(net "DRIVE_B_24_INS")
	)
	(segment
		(start 41.199308 -54.942486)
		(end 113.376964 -54.942486)
		(width 0.17145)
		(layer "F.Cu")
		(net "DRIVE_B_24_INS")
	)
	(segment
		(start 193.30035 -159.756094)
		(end 193.30035 -191.070484)
		(width 0.17145)
		(layer "F.Cu")
		(net "DRIVE_B_24_INS")
	)
	(segment
		(start 201.423016 -212.87486)
		(end 211.125816 -212.87486)
		(width 0.17145)
		(layer "F.Cu")
		(net "DRIVE_B_24_INS")
	)
	(segment
		(start 126.737872 -103.446326)
		(end 138.119104 -114.827558)
		(width 0.17145)
		(layer "F.Cu")
		(net "DRIVE_B_24_INS")
	)
	(segment
		(start 187.273184 -114.827558)
		(end 195.781168 -123.335542)
		(width 0.17145)
		(layer "F.Cu")
		(net "DRIVE_B_24_INS")
	)
	(segment
		(start 35.687 -49.430178)
		(end 41.199308 -54.942486)
		(width 0.17145)
		(layer "F.Cu")
		(net "DRIVE_B_24_INS")
	)
	(segment
		(start 199.654922 -211.106766)
		(end 201.423016 -212.87486)
		(width 0.17145)
		(layer "F.Cu")
		(net "DRIVE_B_24_INS")
	)
	(segment
		(start 195.781168 -123.335542)
		(end 195.781168 -157.275276)
		(width 0.17145)
		(layer "F.Cu")
		(net "DRIVE_B_24_INS")
	)
	(segment
		(start 138.119104 -114.827558)
		(end 187.273184 -114.827558)
		(width 0.17145)
		(layer "F.Cu")
		(net "DRIVE_B_24_INS")
	)
	(segment
		(start 211.125816 -212.87486)
		(end 211.128356 -212.87232)
		(width 0.17145)
		(layer "F.Cu")
		(net "DRIVE_B_24_INS")
	)
	(segment
		(start 126.737872 -75.390756)
		(end 126.737872 -103.446326)
		(width 0.17145)
		(layer "F.Cu")
		(net "DRIVE_B_24_INS")
	)
	(via
		(at 126.737872 -75.390756)
		(size 0.6604)
		(drill 0.3302)
		(layers "F.Cu" "B.Cu")
		(net "DRIVE_B_24_INS")
	)
	(via
		(at 293.65194 -120.22582)
		(size 0.5588)
		(drill 0.3048)
		(layers "F.Cu" "B.Cu")
		(net "DRIVE_B_24_ACT")
	)
	(segment
		(start 294.961564 -181.106318)
		(end 294.961564 -147.533868)
		(width 0.14605)
		(layer "In2.Cu")
		(net "DRIVE_B_24_ACT")
	)
	(segment
		(start 294.961564 -147.533868)
		(end 295.144444 -147.350988)
		(width 0.14605)
		(layer "In2.Cu")
		(net "DRIVE_B_24_ACT")
	)
	(segment
		(start 293.65194 -120.83034)
		(end 293.65194 -120.22582)
		(width 0.14605)
		(layer "In2.Cu")
		(net "DRIVE_B_24_ACT")
	)
	(segment
		(start 288.869882 -187.198)
		(end 294.961564 -181.106318)
		(width 0.14605)
		(layer "In2.Cu")
		(net "DRIVE_B_24_ACT")
	)
	(segment
		(start 283.94025 -187.198)
		(end 288.869882 -187.198)
		(width 0.14605)
		(layer "In2.Cu")
		(net "DRIVE_B_24_ACT")
	)
	(segment
		(start 295.144444 -147.350988)
		(end 295.144444 -122.322844)
		(width 0.14605)
		(layer "In2.Cu")
		(net "DRIVE_B_24_ACT")
	)
	(segment
		(start 295.144444 -122.322844)
		(end 293.65194 -120.83034)
		(width 0.14605)
		(layer "In2.Cu")
		(net "DRIVE_B_24_ACT")
	)
	(segment
		(start 283.23667 -186.49442)
		(end 283.94025 -187.198)
		(width 0.14605)
		(layer "In2.Cu")
		(net "DRIVE_B_24_ACT")
	)
	(segment
		(start 292.649148 -117.704616)
		(end 293.65194 -118.707408)
		(width 0.14605)
		(layer "In5.Cu")
		(net "DRIVE_B_24_ACT")
	)
	(segment
		(start 277.927816 -117.704616)
		(end 292.649148 -117.704616)
		(width 0.14605)
		(layer "In5.Cu")
		(net "DRIVE_B_24_ACT")
	)
	(segment
		(start 229.80015 -66.799968)
		(end 230.957374 -67.957192)
		(width 0.14605)
		(layer "In5.Cu")
		(net "DRIVE_B_24_ACT")
	)
	(segment
		(start 252.17628 -101.984302)
		(end 262.207502 -101.984302)
		(width 0.14605)
		(layer "In5.Cu")
		(net "DRIVE_B_24_ACT")
	)
	(segment
		(start 293.65194 -118.707408)
		(end 293.65194 -120.22582)
		(width 0.14605)
		(layer "In5.Cu")
		(net "DRIVE_B_24_ACT")
	)
	(segment
		(start 230.957374 -67.957192)
		(end 230.957374 -80.765396)
		(width 0.14605)
		(layer "In5.Cu")
		(net "DRIVE_B_24_ACT")
	)
	(segment
		(start 262.207502 -101.984302)
		(end 277.927816 -117.704616)
		(width 0.14605)
		(layer "In5.Cu")
		(net "DRIVE_B_24_ACT")
	)
	(segment
		(start 230.957374 -80.765396)
		(end 252.17628 -101.984302)
		(width 0.14605)
		(layer "In5.Cu")
		(net "DRIVE_B_24_ACT")
	)
	(segment
		(start 469.519 -128.8415)
		(end 469.519 -128.016)
		(width 0.17145)
		(layer "F.Cu")
		(net "DRIVE_B_23_PWR")
	)
	(segment
		(start 288.7091 -171.003468)
		(end 266.653772 -171.003468)
		(width 0.17145)
		(layer "F.Cu")
		(net "DRIVE_B_23_PWR")
	)
	(segment
		(start 242.27155 -201.87539)
		(end 242.13566 -202.01128)
		(width 0.17145)
		(layer "F.Cu")
		(net "DRIVE_B_23_PWR")
	)
	(segment
		(start 266.653772 -171.003468)
		(end 262.294116 -175.363124)
		(width 0.17145)
		(layer "F.Cu")
		(net "DRIVE_B_23_PWR")
	)
	(segment
		(start 242.13566 -202.01128)
		(end 240.6904 -202.01128)
		(width 0.17145)
		(layer "F.Cu")
		(net "DRIVE_B_23_PWR")
	)
	(segment
		(start 262.294116 -175.363124)
		(end 262.294116 -177.148744)
		(width 0.17145)
		(layer "F.Cu")
		(net "DRIVE_B_23_PWR")
	)
	(segment
		(start 309.80888 -170.014646)
		(end 289.697922 -170.014646)
		(width 0.17145)
		(layer "F.Cu")
		(net "DRIVE_B_23_PWR")
	)
	(segment
		(start 262.294116 -177.148744)
		(end 262.294116 -187.898786)
		(width 0.17145)
		(layer "F.Cu")
		(net "DRIVE_B_23_PWR")
	)
	(segment
		(start 313.601608 -171.380912)
		(end 311.175146 -171.380912)
		(width 0.17145)
		(layer "F.Cu")
		(net "DRIVE_B_23_PWR")
	)
	(segment
		(start 289.697922 -170.014646)
		(end 288.7091 -171.003468)
		(width 0.17145)
		(layer "F.Cu")
		(net "DRIVE_B_23_PWR")
	)
	(segment
		(start 311.175146 -171.380912)
		(end 309.80888 -170.014646)
		(width 0.17145)
		(layer "F.Cu")
		(net "DRIVE_B_23_PWR")
	)
	(segment
		(start 314.11926 -170.86326)
		(end 313.601608 -171.380912)
		(width 0.17145)
		(layer "F.Cu")
		(net "DRIVE_B_23_PWR")
	)
	(segment
		(start 262.294116 -187.898786)
		(end 248.317512 -201.87539)
		(width 0.17145)
		(layer "F.Cu")
		(net "DRIVE_B_23_PWR")
	)
	(segment
		(start 248.317512 -201.87539)
		(end 242.27155 -201.87539)
		(width 0.17145)
		(layer "F.Cu")
		(net "DRIVE_B_23_PWR")
	)
	(via
		(at 314.11926 -170.86326)
		(size 0.5588)
		(drill 0.3048)
		(layers "F.Cu" "B.Cu")
		(net "DRIVE_B_23_PWR")
	)
	(via
		(at 469.519 -128.016)
		(size 0.5588)
		(drill 0.3048)
		(layers "F.Cu" "B.Cu")
		(net "DRIVE_B_23_PWR")
	)
	(via
		(at 262.294116 -177.148744)
		(size 0.6604)
		(drill 0.3302)
		(layers "F.Cu" "B.Cu")
		(net "DRIVE_B_23_PWR")
	)
	(segment
		(start 443.357 -160.147)
		(end 463.169 -140.335)
		(width 0.14605)
		(layer "In2.Cu")
		(net "DRIVE_B_23_PWR")
	)
	(segment
		(start 317.75781 -168.386506)
		(end 317.75781 -164.03066)
		(width 0.14605)
		(layer "In2.Cu")
		(net "DRIVE_B_23_PWR")
	)
	(segment
		(start 463.169 -140.335)
		(end 463.169 -134.366)
		(width 0.14605)
		(layer "In2.Cu")
		(net "DRIVE_B_23_PWR")
	)
	(segment
		(start 317.75781 -164.03066)
		(end 321.64147 -160.147)
		(width 0.14605)
		(layer "In2.Cu")
		(net "DRIVE_B_23_PWR")
	)
	(segment
		(start 314.11926 -170.86326)
		(end 315.281056 -170.86326)
		(width 0.14605)
		(layer "In2.Cu")
		(net "DRIVE_B_23_PWR")
	)
	(segment
		(start 321.64147 -160.147)
		(end 443.357 -160.147)
		(width 0.14605)
		(layer "In2.Cu")
		(net "DRIVE_B_23_PWR")
	)
	(segment
		(start 463.169 -134.366)
		(end 469.519 -128.016)
		(width 0.14605)
		(layer "In2.Cu")
		(net "DRIVE_B_23_PWR")
	)
	(segment
		(start 315.281056 -170.86326)
		(end 317.75781 -168.386506)
		(width 0.14605)
		(layer "In2.Cu")
		(net "DRIVE_B_23_PWR")
	)
	(segment
		(start 422.840404 -115.7732)
		(end 323.429376 -115.7732)
		(width 0.17145)
		(layer "F.Cu")
		(net "DRIVE_B_23_INS")
	)
	(segment
		(start 239.590834 -161.144204)
		(end 222.90405 -177.830988)
		(width 0.17145)
		(layer "F.Cu")
		(net "DRIVE_B_23_INS")
	)
	(segment
		(start 446.575942 -124.043948)
		(end 431.111152 -124.043948)
		(width 0.17145)
		(layer "F.Cu")
		(net "DRIVE_B_23_INS")
	)
	(segment
		(start 468.183214 -122.201686)
		(end 461.150716 -122.201686)
		(width 0.17145)
		(layer "F.Cu")
		(net "DRIVE_B_23_INS")
	)
	(segment
		(start 472.467686 -126.486158)
		(end 468.183214 -122.201686)
		(width 0.17145)
		(layer "F.Cu")
		(net "DRIVE_B_23_INS")
	)
	(segment
		(start 461.150716 -122.201686)
		(end 458.532992 -119.583962)
		(width 0.17145)
		(layer "F.Cu")
		(net "DRIVE_B_23_INS")
	)
	(segment
		(start 215.172798 -202.718924)
		(end 215.172798 -210.881468)
		(width 0.17145)
		(layer "F.Cu")
		(net "DRIVE_B_23_INS")
	)
	(segment
		(start 242.147852 -161.144458)
		(end 242.147598 -161.144204)
		(width 0.17145)
		(layer "F.Cu")
		(net "DRIVE_B_23_INS")
	)
	(segment
		(start 476.5294 -130.8608)
		(end 476.5294 -130.547872)
		(width 0.17145)
		(layer "F.Cu")
		(net "DRIVE_B_23_INS")
	)
	(segment
		(start 431.111152 -124.043948)
		(end 422.840404 -115.7732)
		(width 0.17145)
		(layer "F.Cu")
		(net "DRIVE_B_23_INS")
	)
	(segment
		(start 222.904304 -193.009266)
		(end 222.904304 -197.842124)
		(width 0.17145)
		(layer "F.Cu")
		(net "DRIVE_B_23_INS")
	)
	(segment
		(start 319.892426 -121.174002)
		(end 313.990482 -127.075946)
		(width 0.17145)
		(layer "F.Cu")
		(net "DRIVE_B_23_INS")
	)
	(segment
		(start 222.934784 -191.97955)
		(end 222.934784 -192.978786)
		(width 0.17145)
		(layer "F.Cu")
		(net "DRIVE_B_23_INS")
	)
	(segment
		(start 313.990482 -149.805644)
		(end 302.651668 -161.144458)
		(width 0.17145)
		(layer "F.Cu")
		(net "DRIVE_B_23_INS")
	)
	(segment
		(start 458.532992 -119.583962)
		(end 448.828414 -119.583962)
		(width 0.17145)
		(layer "F.Cu")
		(net "DRIVE_B_23_INS")
	)
	(segment
		(start 242.147598 -161.144204)
		(end 239.590834 -161.144204)
		(width 0.17145)
		(layer "F.Cu")
		(net "DRIVE_B_23_INS")
	)
	(segment
		(start 221.986348 -198.76008)
		(end 219.131642 -198.76008)
		(width 0.17145)
		(layer "F.Cu")
		(net "DRIVE_B_23_INS")
	)
	(segment
		(start 222.90405 -177.830988)
		(end 222.90405 -178.256692)
		(width 0.17145)
		(layer "F.Cu")
		(net "DRIVE_B_23_INS")
	)
	(segment
		(start 222.904304 -178.256946)
		(end 222.904304 -191.94907)
		(width 0.17145)
		(layer "F.Cu")
		(net "DRIVE_B_23_INS")
	)
	(segment
		(start 323.429376 -115.7732)
		(end 319.892426 -119.31015)
		(width 0.17145)
		(layer "F.Cu")
		(net "DRIVE_B_23_INS")
	)
	(segment
		(start 319.892426 -119.31015)
		(end 319.892426 -121.174002)
		(width 0.17145)
		(layer "F.Cu")
		(net "DRIVE_B_23_INS")
	)
	(segment
		(start 448.828414 -119.583962)
		(end 448.208146 -120.20423)
		(width 0.17145)
		(layer "F.Cu")
		(net "DRIVE_B_23_INS")
	)
	(segment
		(start 448.208146 -120.20423)
		(end 448.208146 -122.411744)
		(width 0.17145)
		(layer "F.Cu")
		(net "DRIVE_B_23_INS")
	)
	(segment
		(start 448.208146 -122.411744)
		(end 446.575942 -124.043948)
		(width 0.17145)
		(layer "F.Cu")
		(net "DRIVE_B_23_INS")
	)
	(segment
		(start 476.5294 -130.547872)
		(end 472.467686 -126.486158)
		(width 0.17145)
		(layer "F.Cu")
		(net "DRIVE_B_23_INS")
	)
	(segment
		(start 222.904304 -197.842124)
		(end 221.986348 -198.76008)
		(width 0.17145)
		(layer "F.Cu")
		(net "DRIVE_B_23_INS")
	)
	(segment
		(start 222.90405 -178.256692)
		(end 222.904304 -178.256946)
		(width 0.17145)
		(layer "F.Cu")
		(net "DRIVE_B_23_INS")
	)
	(segment
		(start 219.131642 -198.76008)
		(end 215.172798 -202.718924)
		(width 0.17145)
		(layer "F.Cu")
		(net "DRIVE_B_23_INS")
	)
	(segment
		(start 215.172798 -210.881468)
		(end 216.51341 -212.22208)
		(width 0.17145)
		(layer "F.Cu")
		(net "DRIVE_B_23_INS")
	)
	(segment
		(start 216.51341 -212.22208)
		(end 218.7194 -212.22208)
		(width 0.17145)
		(layer "F.Cu")
		(net "DRIVE_B_23_INS")
	)
	(segment
		(start 222.934784 -192.978786)
		(end 222.904304 -193.009266)
		(width 0.17145)
		(layer "F.Cu")
		(net "DRIVE_B_23_INS")
	)
	(segment
		(start 313.990482 -127.075946)
		(end 313.990482 -149.805644)
		(width 0.17145)
		(layer "F.Cu")
		(net "DRIVE_B_23_INS")
	)
	(segment
		(start 222.904304 -191.94907)
		(end 222.934784 -191.97955)
		(width 0.17145)
		(layer "F.Cu")
		(net "DRIVE_B_23_INS")
	)
	(segment
		(start 302.651668 -161.144458)
		(end 242.147852 -161.144458)
		(width 0.17145)
		(layer "F.Cu")
		(net "DRIVE_B_23_INS")
	)
	(via
		(at 472.467686 -126.486158)
		(size 0.6604)
		(drill 0.3302)
		(layers "F.Cu" "B.Cu")
		(net "DRIVE_B_23_INS")
	)
	(segment
		(start 211.6328 -189.85992)
		(end 210.73872 -189.85992)
		(width 0.17145)
		(layer "F.Cu")
		(net "DRIVE_B_23_FLT_LED")
	)
	(segment
		(start 238.971582 -160.630108)
		(end 239.377474 -160.630108)
		(width 0.17145)
		(layer "F.Cu")
		(net "DRIVE_B_23_FLT_LED")
	)
	(segment
		(start 242.360958 -160.630108)
		(end 302.438562 -160.630108)
		(width 0.17145)
		(layer "F.Cu")
		(net "DRIVE_B_23_FLT_LED")
	)
	(segment
		(start 319.377822 -120.96115)
		(end 319.377822 -119.097298)
		(width 0.17145)
		(layer "F.Cu")
		(net "DRIVE_B_23_FLT_LED")
	)
	(segment
		(start 461.605122 -103.77043)
		(end 462.24825 -103.127302)
		(width 0.17145)
		(layer "F.Cu")
		(net "DRIVE_B_23_FLT_LED")
	)
	(segment
		(start 242.360704 -160.629854)
		(end 242.360958 -160.630108)
		(width 0.17145)
		(layer "F.Cu")
		(net "DRIVE_B_23_FLT_LED")
	)
	(segment
		(start 313.057032 -127.28194)
		(end 319.377822 -120.96115)
		(width 0.17145)
		(layer "F.Cu")
		(net "DRIVE_B_23_FLT_LED")
	)
	(segment
		(start 210.73872 -189.85992)
		(end 210.657948 -189.779148)
		(width 0.17145)
		(layer "F.Cu")
		(net "DRIVE_B_23_FLT_LED")
	)
	(segment
		(start 453.762364 -103.77043)
		(end 461.605122 -103.77043)
		(width 0.17145)
		(layer "F.Cu")
		(net "DRIVE_B_23_FLT_LED")
	)
	(segment
		(start 313.057032 -150.011638)
		(end 313.057032 -127.28194)
		(width 0.17145)
		(layer "F.Cu")
		(net "DRIVE_B_23_FLT_LED")
	)
	(segment
		(start 462.24825 -102.503986)
		(end 462.24825 -100.7999)
		(width 0.17145)
		(layer "F.Cu")
		(net "DRIVE_B_23_FLT_LED")
	)
	(segment
		(start 451.89394 -105.631234)
		(end 453.758554 -103.76662)
		(width 0.17145)
		(layer "F.Cu")
		(net "DRIVE_B_23_FLT_LED")
	)
	(segment
		(start 239.377474 -160.630108)
		(end 239.377728 -160.629854)
		(width 0.17145)
		(layer "F.Cu")
		(net "DRIVE_B_23_FLT_LED")
	)
	(segment
		(start 423.630598 -105.631234)
		(end 451.89394 -105.631234)
		(width 0.17145)
		(layer "F.Cu")
		(net "DRIVE_B_23_FLT_LED")
	)
	(segment
		(start 239.377728 -160.629854)
		(end 242.360704 -160.629854)
		(width 0.17145)
		(layer "F.Cu")
		(net "DRIVE_B_23_FLT_LED")
	)
	(segment
		(start 414.199832 -115.062)
		(end 423.630598 -105.631234)
		(width 0.17145)
		(layer "F.Cu")
		(net "DRIVE_B_23_FLT_LED")
	)
	(segment
		(start 323.41312 -115.062)
		(end 414.199832 -115.062)
		(width 0.17145)
		(layer "F.Cu")
		(net "DRIVE_B_23_FLT_LED")
	)
	(segment
		(start 462.24825 -103.127302)
		(end 462.24825 -102.503986)
		(width 0.17145)
		(layer "F.Cu")
		(net "DRIVE_B_23_FLT_LED")
	)
	(segment
		(start 210.657948 -188.943742)
		(end 238.971582 -160.630108)
		(width 0.17145)
		(layer "F.Cu")
		(net "DRIVE_B_23_FLT_LED")
	)
	(segment
		(start 319.377822 -119.097298)
		(end 323.41312 -115.062)
		(width 0.17145)
		(layer "F.Cu")
		(net "DRIVE_B_23_FLT_LED")
	)
	(segment
		(start 302.438562 -160.630108)
		(end 313.057032 -150.011638)
		(width 0.17145)
		(layer "F.Cu")
		(net "DRIVE_B_23_FLT_LED")
	)
	(segment
		(start 453.758554 -103.76662)
		(end 453.762364 -103.77043)
		(width 0.17145)
		(layer "F.Cu")
		(net "DRIVE_B_23_FLT_LED")
	)
	(segment
		(start 210.657948 -189.779148)
		(end 210.657948 -188.943742)
		(width 0.17145)
		(layer "F.Cu")
		(net "DRIVE_B_23_FLT_LED")
	)
	(via
		(at 453.758554 -103.76662)
		(size 0.6604)
		(drill 0.3302)
		(layers "F.Cu" "B.Cu")
		(net "DRIVE_B_23_FLT_LED")
	)
	(segment
		(start 458.506068 -98.966528)
		(end 458.506068 -97.480628)
		(width 0.17145)
		(layer "F.Cu")
		(net "DRIVE_B_23_ACT")
	)
	(segment
		(start 458.506068 -97.480628)
		(end 458.506068 -94.6404)
		(width 0.17145)
		(layer "F.Cu")
		(net "DRIVE_B_23_ACT")
	)
	(via
		(at 458.506068 -94.6404)
		(size 0.5588)
		(drill 0.3048)
		(layers "F.Cu" "B.Cu")
		(net "DRIVE_B_23_ACT")
	)
	(via
		(at 302.912272 -182.85333)
		(size 0.6096)
		(drill 0.3048)
		(layers "F.Cu" "B.Cu")
		(net "DRIVE_B_23_ACT")
	)
	(via
		(at 307.997098 -182.85333)
		(size 0.5588)
		(drill 0.3048)
		(layers "F.Cu" "B.Cu")
		(net "DRIVE_B_23_ACT")
	)
	(segment
		(start 293.112952 -187.4647)
		(end 297.724322 -182.85333)
		(width 0.17145)
		(layer "B.Cu")
		(net "DRIVE_B_23_ACT")
	)
	(segment
		(start 302.912272 -182.85333)
		(end 307.997098 -182.85333)
		(width 0.17145)
		(layer "B.Cu")
		(net "DRIVE_B_23_ACT")
	)
	(segment
		(start 282.83662 -188.294518)
		(end 283.081222 -188.294518)
		(width 0.17145)
		(layer "B.Cu")
		(net "DRIVE_B_23_ACT")
	)
	(segment
		(start 283.081222 -188.294518)
		(end 283.91104 -187.4647)
		(width 0.17145)
		(layer "B.Cu")
		(net "DRIVE_B_23_ACT")
	)
	(segment
		(start 283.91104 -187.4647)
		(end 293.112952 -187.4647)
		(width 0.17145)
		(layer "B.Cu")
		(net "DRIVE_B_23_ACT")
	)
	(segment
		(start 297.724322 -182.85333)
		(end 302.912272 -182.85333)
		(width 0.17145)
		(layer "B.Cu")
		(net "DRIVE_B_23_ACT")
	)
	(segment
		(start 379.095254 -118.0846)
		(end 390.976358 -106.203496)
		(width 0.14605)
		(layer "In2.Cu")
		(net "DRIVE_B_23_ACT")
	)
	(segment
		(start 325.932038 -118.0846)
		(end 379.095254 -118.0846)
		(width 0.14605)
		(layer "In2.Cu")
		(net "DRIVE_B_23_ACT")
	)
	(segment
		(start 307.997098 -182.85333)
		(end 311.959752 -178.890676)
		(width 0.14605)
		(layer "In2.Cu")
		(net "DRIVE_B_23_ACT")
	)
	(segment
		(start 311.959752 -132.056886)
		(end 325.932038 -118.0846)
		(width 0.14605)
		(layer "In2.Cu")
		(net "DRIVE_B_23_ACT")
	)
	(segment
		(start 432.745642 -104.299512)
		(end 448.846956 -104.299512)
		(width 0.14605)
		(layer "In2.Cu")
		(net "DRIVE_B_23_ACT")
	)
	(segment
		(start 390.976358 -106.203496)
		(end 430.841658 -106.203496)
		(width 0.14605)
		(layer "In2.Cu")
		(net "DRIVE_B_23_ACT")
	)
	(segment
		(start 430.841658 -106.203496)
		(end 432.745642 -104.299512)
		(width 0.14605)
		(layer "In2.Cu")
		(net "DRIVE_B_23_ACT")
	)
	(segment
		(start 311.959752 -178.890676)
		(end 311.959752 -132.056886)
		(width 0.14605)
		(layer "In2.Cu")
		(net "DRIVE_B_23_ACT")
	)
	(segment
		(start 448.846956 -104.299512)
		(end 458.506068 -94.6404)
		(width 0.14605)
		(layer "In2.Cu")
		(net "DRIVE_B_23_ACT")
	)
	(segment
		(start 261.134606 -179.720494)
		(end 261.134606 -175.234854)
		(width 0.17145)
		(layer "F.Cu")
		(net "DRIVE_B_22_PWR")
	)
	(segment
		(start 261.134606 -188.33084)
		(end 248.104406 -201.36104)
		(width 0.17145)
		(layer "F.Cu")
		(net "DRIVE_B_22_PWR")
	)
	(segment
		(start 289.484816 -169.500296)
		(end 310.305196 -169.500296)
		(width 0.17145)
		(layer "F.Cu")
		(net "DRIVE_B_22_PWR")
	)
	(segment
		(start 261.134606 -179.720494)
		(end 261.134606 -188.33084)
		(width 0.17145)
		(layer "F.Cu")
		(net "DRIVE_B_22_PWR")
	)
	(segment
		(start 310.305196 -169.500296)
		(end 311.66816 -170.86326)
		(width 0.17145)
		(layer "F.Cu")
		(net "DRIVE_B_22_PWR")
	)
	(segment
		(start 311.66816 -170.86326)
		(end 313.05246 -170.86326)
		(width 0.17145)
		(layer "F.Cu")
		(net "DRIVE_B_22_PWR")
	)
	(segment
		(start 261.134606 -175.234854)
		(end 265.880342 -170.489118)
		(width 0.17145)
		(layer "F.Cu")
		(net "DRIVE_B_22_PWR")
	)
	(segment
		(start 461.899 -128.2065)
		(end 462.788 -128.2065)
		(width 0.17145)
		(layer "F.Cu")
		(net "DRIVE_B_22_PWR")
	)
	(segment
		(start 248.104406 -201.36104)
		(end 240.6904 -201.36104)
		(width 0.17145)
		(layer "F.Cu")
		(net "DRIVE_B_22_PWR")
	)
	(segment
		(start 265.880342 -170.489118)
		(end 288.495994 -170.489118)
		(width 0.17145)
		(layer "F.Cu")
		(net "DRIVE_B_22_PWR")
	)
	(segment
		(start 288.495994 -170.489118)
		(end 289.484816 -169.500296)
		(width 0.17145)
		(layer "F.Cu")
		(net "DRIVE_B_22_PWR")
	)
	(via
		(at 462.788 -128.2065)
		(size 0.5588)
		(drill 0.3048)
		(layers "F.Cu" "B.Cu")
		(net "DRIVE_B_22_PWR")
	)
	(via
		(at 313.05246 -170.86326)
		(size 0.5588)
		(drill 0.3048)
		(layers "F.Cu" "B.Cu")
		(net "DRIVE_B_22_PWR")
	)
	(via
		(at 261.134606 -179.720494)
		(size 0.6604)
		(drill 0.3302)
		(layers "F.Cu" "B.Cu")
		(net "DRIVE_B_22_PWR")
	)
	(segment
		(start 461.772 -136.611868)
		(end 439.125868 -159.258)
		(width 0.14605)
		(layer "In2.Cu")
		(net "DRIVE_B_22_PWR")
	)
	(segment
		(start 313.557412 -170.358308)
		(end 313.05246 -170.86326)
		(width 0.14605)
		(layer "In2.Cu")
		(net "DRIVE_B_22_PWR")
	)
	(segment
		(start 461.772 -129.2225)
		(end 461.772 -136.611868)
		(width 0.14605)
		(layer "In2.Cu")
		(net "DRIVE_B_22_PWR")
	)
	(segment
		(start 321.91071 -159.258)
		(end 316.920118 -164.248592)
		(width 0.14605)
		(layer "In2.Cu")
		(net "DRIVE_B_22_PWR")
	)
	(segment
		(start 315.135514 -170.358308)
		(end 313.557412 -170.358308)
		(width 0.14605)
		(layer "In2.Cu")
		(net "DRIVE_B_22_PWR")
	)
	(segment
		(start 462.788 -128.2065)
		(end 461.772 -129.2225)
		(width 0.14605)
		(layer "In2.Cu")
		(net "DRIVE_B_22_PWR")
	)
	(segment
		(start 316.920118 -168.573704)
		(end 315.135514 -170.358308)
		(width 0.14605)
		(layer "In2.Cu")
		(net "DRIVE_B_22_PWR")
	)
	(segment
		(start 316.920118 -164.248592)
		(end 316.920118 -168.573704)
		(width 0.14605)
		(layer "In2.Cu")
		(net "DRIVE_B_22_PWR")
	)
	(segment
		(start 439.125868 -159.258)
		(end 321.91071 -159.258)
		(width 0.14605)
		(layer "In2.Cu")
		(net "DRIVE_B_22_PWR")
	)
	(segment
		(start 215.687148 -210.476084)
		(end 215.687148 -202.93203)
		(width 0.17145)
		(layer "F.Cu")
		(net "DRIVE_B_22_INS")
	)
	(segment
		(start 218.7194 -211.57184)
		(end 216.782904 -211.57184)
		(width 0.17145)
		(layer "F.Cu")
		(net "DRIVE_B_22_INS")
	)
	(segment
		(start 314.891928 -149.631654)
		(end 314.891928 -126.901956)
		(width 0.17145)
		(layer "F.Cu")
		(net "DRIVE_B_22_INS")
	)
	(segment
		(start 241.934746 -161.658808)
		(end 302.864774 -161.658808)
		(width 0.17145)
		(layer "F.Cu")
		(net "DRIVE_B_22_INS")
	)
	(segment
		(start 323.426582 -116.50345)
		(end 323.849238 -116.50345)
		(width 0.17145)
		(layer "F.Cu")
		(net "DRIVE_B_22_INS")
	)
	(segment
		(start 422.248584 -116.50345)
		(end 432.23688 -126.491746)
		(width 0.17145)
		(layer "F.Cu")
		(net "DRIVE_B_22_INS")
	)
	(segment
		(start 444.125096 -138.379962)
		(end 432.23688 -126.491746)
		(width 0.17145)
		(layer "F.Cu")
		(net "DRIVE_B_22_INS")
	)
	(segment
		(start 320.406776 -119.523256)
		(end 323.426582 -116.50345)
		(width 0.17145)
		(layer "F.Cu")
		(net "DRIVE_B_22_INS")
	)
	(segment
		(start 223.449134 -191.766444)
		(end 223.418654 -191.735964)
		(width 0.17145)
		(layer "F.Cu")
		(net "DRIVE_B_22_INS")
	)
	(segment
		(start 221.773496 -199.274684)
		(end 222.1992 -199.274684)
		(width 0.17145)
		(layer "F.Cu")
		(net "DRIVE_B_22_INS")
	)
	(segment
		(start 219.344748 -199.27443)
		(end 221.773242 -199.27443)
		(width 0.17145)
		(layer "F.Cu")
		(net "DRIVE_B_22_INS")
	)
	(segment
		(start 222.1992 -199.274684)
		(end 223.418654 -198.05523)
		(width 0.17145)
		(layer "F.Cu")
		(net "DRIVE_B_22_INS")
	)
	(segment
		(start 324.367906 -116.50345)
		(end 422.248584 -116.50345)
		(width 0.17145)
		(layer "F.Cu")
		(net "DRIVE_B_22_INS")
	)
	(segment
		(start 323.849492 -116.503196)
		(end 324.367652 -116.503196)
		(width 0.17145)
		(layer "F.Cu")
		(net "DRIVE_B_22_INS")
	)
	(segment
		(start 314.891928 -126.901956)
		(end 320.406776 -121.387108)
		(width 0.17145)
		(layer "F.Cu")
		(net "DRIVE_B_22_INS")
	)
	(segment
		(start 223.418654 -193.222372)
		(end 223.449134 -193.191892)
		(width 0.17145)
		(layer "F.Cu")
		(net "DRIVE_B_22_INS")
	)
	(segment
		(start 444.125096 -150.067264)
		(end 444.125096 -138.379962)
		(width 0.17145)
		(layer "F.Cu")
		(net "DRIVE_B_22_INS")
	)
	(segment
		(start 223.449134 -193.191892)
		(end 223.449134 -191.766444)
		(width 0.17145)
		(layer "F.Cu")
		(net "DRIVE_B_22_INS")
	)
	(segment
		(start 216.782904 -211.57184)
		(end 215.687148 -210.476084)
		(width 0.17145)
		(layer "F.Cu")
		(net "DRIVE_B_22_INS")
	)
	(segment
		(start 221.773242 -199.27443)
		(end 221.773496 -199.274684)
		(width 0.17145)
		(layer "F.Cu")
		(net "DRIVE_B_22_INS")
	)
	(segment
		(start 302.864774 -161.658808)
		(end 314.891928 -149.631654)
		(width 0.17145)
		(layer "F.Cu")
		(net "DRIVE_B_22_INS")
	)
	(segment
		(start 324.367652 -116.503196)
		(end 324.367906 -116.50345)
		(width 0.17145)
		(layer "F.Cu")
		(net "DRIVE_B_22_INS")
	)
	(segment
		(start 446.278 -151.13)
		(end 445.187832 -151.13)
		(width 0.17145)
		(layer "F.Cu")
		(net "DRIVE_B_22_INS")
	)
	(segment
		(start 445.187832 -151.13)
		(end 444.125096 -150.067264)
		(width 0.17145)
		(layer "F.Cu")
		(net "DRIVE_B_22_INS")
	)
	(segment
		(start 223.418654 -191.735964)
		(end 223.418654 -178.04384)
		(width 0.17145)
		(layer "F.Cu")
		(net "DRIVE_B_22_INS")
	)
	(segment
		(start 320.406776 -121.387108)
		(end 320.406776 -119.523256)
		(width 0.17145)
		(layer "F.Cu")
		(net "DRIVE_B_22_INS")
	)
	(segment
		(start 223.418654 -198.05523)
		(end 223.418654 -193.222372)
		(width 0.17145)
		(layer "F.Cu")
		(net "DRIVE_B_22_INS")
	)
	(segment
		(start 223.418654 -178.04384)
		(end 239.80394 -161.658554)
		(width 0.17145)
		(layer "F.Cu")
		(net "DRIVE_B_22_INS")
	)
	(segment
		(start 215.687148 -202.93203)
		(end 219.344748 -199.27443)
		(width 0.17145)
		(layer "F.Cu")
		(net "DRIVE_B_22_INS")
	)
	(segment
		(start 323.849238 -116.50345)
		(end 323.849492 -116.503196)
		(width 0.17145)
		(layer "F.Cu")
		(net "DRIVE_B_22_INS")
	)
	(segment
		(start 241.934492 -161.658554)
		(end 241.934746 -161.658808)
		(width 0.17145)
		(layer "F.Cu")
		(net "DRIVE_B_22_INS")
	)
	(segment
		(start 239.80394 -161.658554)
		(end 241.934492 -161.658554)
		(width 0.17145)
		(layer "F.Cu")
		(net "DRIVE_B_22_INS")
	)
	(via
		(at 432.23688 -126.491746)
		(size 0.6604)
		(drill 0.3302)
		(layers "F.Cu" "B.Cu")
		(net "DRIVE_B_22_INS")
	)
	(segment
		(start 302.225456 -160.115758)
		(end 312.123328 -150.217886)
		(width 0.17145)
		(layer "F.Cu")
		(net "DRIVE_B_22_FLT_LED")
	)
	(segment
		(start 318.863472 -120.748044)
		(end 318.863472 -118.884192)
		(width 0.17145)
		(layer "F.Cu")
		(net "DRIVE_B_22_FLT_LED")
	)
	(segment
		(start 448.987164 -102.180644)
		(end 448.983354 -102.184454)
		(width 0.17145)
		(layer "F.Cu")
		(net "DRIVE_B_22_FLT_LED")
	)
	(segment
		(start 437.209946 -104.524556)
		(end 437.230774 -104.545384)
		(width 0.17145)
		(layer "F.Cu")
		(net "DRIVE_B_22_FLT_LED")
	)
	(segment
		(start 447.830956 -104.545384)
		(end 448.983354 -103.392986)
		(width 0.17145)
		(layer "F.Cu")
		(net "DRIVE_B_22_FLT_LED")
	)
	(segment
		(start 312.123328 -127.488188)
		(end 318.863472 -120.748044)
		(width 0.17145)
		(layer "F.Cu")
		(net "DRIVE_B_22_FLT_LED")
	)
	(segment
		(start 242.574064 -160.115758)
		(end 302.225456 -160.115758)
		(width 0.17145)
		(layer "F.Cu")
		(net "DRIVE_B_22_FLT_LED")
	)
	(segment
		(start 448.987164 -100.659438)
		(end 448.987164 -102.180644)
		(width 0.17145)
		(layer "F.Cu")
		(net "DRIVE_B_22_FLT_LED")
	)
	(segment
		(start 238.457232 -160.417002)
		(end 238.457232 -160.416748)
		(width 0.17145)
		(layer "F.Cu")
		(net "DRIVE_B_22_FLT_LED")
	)
	(segment
		(start 210.661504 -190.51016)
		(end 210.143598 -189.992254)
		(width 0.17145)
		(layer "F.Cu")
		(net "DRIVE_B_22_FLT_LED")
	)
	(segment
		(start 413.122618 -114.54765)
		(end 423.145712 -104.524556)
		(width 0.17145)
		(layer "F.Cu")
		(net "DRIVE_B_22_FLT_LED")
	)
	(segment
		(start 210.143598 -189.992254)
		(end 210.143598 -188.730636)
		(width 0.17145)
		(layer "F.Cu")
		(net "DRIVE_B_22_FLT_LED")
	)
	(segment
		(start 323.200014 -114.54765)
		(end 413.122618 -114.54765)
		(width 0.17145)
		(layer "F.Cu")
		(net "DRIVE_B_22_FLT_LED")
	)
	(segment
		(start 242.57381 -160.115504)
		(end 242.574064 -160.115758)
		(width 0.17145)
		(layer "F.Cu")
		(net "DRIVE_B_22_FLT_LED")
	)
	(segment
		(start 318.863472 -118.884192)
		(end 323.200014 -114.54765)
		(width 0.17145)
		(layer "F.Cu")
		(net "DRIVE_B_22_FLT_LED")
	)
	(segment
		(start 448.983354 -103.392986)
		(end 448.983354 -102.184454)
		(width 0.17145)
		(layer "F.Cu")
		(net "DRIVE_B_22_FLT_LED")
	)
	(segment
		(start 239.164368 -160.115758)
		(end 239.164622 -160.115504)
		(width 0.17145)
		(layer "F.Cu")
		(net "DRIVE_B_22_FLT_LED")
	)
	(segment
		(start 312.123328 -150.217886)
		(end 312.123328 -127.488188)
		(width 0.17145)
		(layer "F.Cu")
		(net "DRIVE_B_22_FLT_LED")
	)
	(segment
		(start 211.6328 -190.51016)
		(end 210.661504 -190.51016)
		(width 0.17145)
		(layer "F.Cu")
		(net "DRIVE_B_22_FLT_LED")
	)
	(segment
		(start 437.230774 -104.545384)
		(end 447.830956 -104.545384)
		(width 0.17145)
		(layer "F.Cu")
		(net "DRIVE_B_22_FLT_LED")
	)
	(segment
		(start 239.164622 -160.115504)
		(end 242.57381 -160.115504)
		(width 0.17145)
		(layer "F.Cu")
		(net "DRIVE_B_22_FLT_LED")
	)
	(segment
		(start 210.143598 -188.730636)
		(end 238.457232 -160.417002)
		(width 0.17145)
		(layer "F.Cu")
		(net "DRIVE_B_22_FLT_LED")
	)
	(segment
		(start 423.145712 -104.524556)
		(end 437.209946 -104.524556)
		(width 0.17145)
		(layer "F.Cu")
		(net "DRIVE_B_22_FLT_LED")
	)
	(segment
		(start 238.457232 -160.416748)
		(end 238.758222 -160.115758)
		(width 0.17145)
		(layer "F.Cu")
		(net "DRIVE_B_22_FLT_LED")
	)
	(segment
		(start 238.758222 -160.115758)
		(end 239.164368 -160.115758)
		(width 0.17145)
		(layer "F.Cu")
		(net "DRIVE_B_22_FLT_LED")
	)
	(via
		(at 437.230774 -104.545384)
		(size 0.6604)
		(drill 0.3302)
		(layers "F.Cu" "B.Cu")
		(net "DRIVE_B_22_FLT_LED")
	)
	(segment
		(start 445.374268 -103.032814)
		(end 445.422274 -103.08082)
		(width 0.17145)
		(layer "F.Cu")
		(net "DRIVE_B_22_ACT")
	)
	(segment
		(start 445.374268 -102.26802)
		(end 445.374268 -103.032814)
		(width 0.17145)
		(layer "F.Cu")
		(net "DRIVE_B_22_ACT")
	)
	(segment
		(start 445.391286 -102.251002)
		(end 445.374268 -102.26802)
		(width 0.17145)
		(layer "F.Cu")
		(net "DRIVE_B_22_ACT")
	)
	(segment
		(start 445.391286 -100.658422)
		(end 445.391286 -102.251002)
		(width 0.17145)
		(layer "F.Cu")
		(net "DRIVE_B_22_ACT")
	)
	(via
		(at 445.422274 -103.08082)
		(size 0.5588)
		(drill 0.3048)
		(layers "F.Cu" "B.Cu")
		(net "DRIVE_B_22_ACT")
	)
	(via
		(at 304.346102 -183.92013)
		(size 0.6096)
		(drill 0.3048)
		(layers "F.Cu" "B.Cu")
		(net "DRIVE_B_22_ACT")
	)
	(via
		(at 307.997098 -183.92013)
		(size 0.5588)
		(drill 0.3048)
		(layers "F.Cu" "B.Cu")
		(net "DRIVE_B_22_ACT")
	)
	(segment
		(start 284.236668 -188.294518)
		(end 284.87497 -188.93282)
		(width 0.17145)
		(layer "B.Cu")
		(net "DRIVE_B_22_ACT")
	)
	(segment
		(start 297.646598 -183.92013)
		(end 304.346102 -183.92013)
		(width 0.17145)
		(layer "B.Cu")
		(net "DRIVE_B_22_ACT")
	)
	(segment
		(start 304.346102 -183.92013)
		(end 307.997098 -183.92013)
		(width 0.17145)
		(layer "B.Cu")
		(net "DRIVE_B_22_ACT")
	)
	(segment
		(start 292.633908 -188.93282)
		(end 297.646598 -183.92013)
		(width 0.17145)
		(layer "B.Cu")
		(net "DRIVE_B_22_ACT")
	)
	(segment
		(start 284.87497 -188.93282)
		(end 292.633908 -188.93282)
		(width 0.17145)
		(layer "B.Cu")
		(net "DRIVE_B_22_ACT")
	)
	(segment
		(start 311.521602 -178.46802)
		(end 307.44414 -182.545482)
		(width 0.14605)
		(layer "In2.Cu")
		(net "DRIVE_B_22_ACT")
	)
	(segment
		(start 307.44414 -183.367172)
		(end 307.997098 -183.92013)
		(width 0.14605)
		(layer "In2.Cu")
		(net "DRIVE_B_22_ACT")
	)
	(segment
		(start 311.521602 -131.875276)
		(end 311.521602 -178.46802)
		(width 0.14605)
		(layer "In2.Cu")
		(net "DRIVE_B_22_ACT")
	)
	(segment
		(start 445.422274 -103.08082)
		(end 444.641732 -103.861362)
		(width 0.14605)
		(layer "In2.Cu")
		(net "DRIVE_B_22_ACT")
	)
	(segment
		(start 431.143664 -105.28173)
		(end 390.49833 -105.28173)
		(width 0.14605)
		(layer "In2.Cu")
		(net "DRIVE_B_22_ACT")
	)
	(segment
		(start 378.13361 -117.64645)
		(end 325.750428 -117.64645)
		(width 0.14605)
		(layer "In2.Cu")
		(net "DRIVE_B_22_ACT")
	)
	(segment
		(start 325.750428 -117.64645)
		(end 311.521602 -131.875276)
		(width 0.14605)
		(layer "In2.Cu")
		(net "DRIVE_B_22_ACT")
	)
	(segment
		(start 432.564032 -103.861362)
		(end 431.143664 -105.28173)
		(width 0.14605)
		(layer "In2.Cu")
		(net "DRIVE_B_22_ACT")
	)
	(segment
		(start 390.49833 -105.28173)
		(end 378.13361 -117.64645)
		(width 0.14605)
		(layer "In2.Cu")
		(net "DRIVE_B_22_ACT")
	)
	(segment
		(start 444.641732 -103.861362)
		(end 432.564032 -103.861362)
		(width 0.14605)
		(layer "In2.Cu")
		(net "DRIVE_B_22_ACT")
	)
	(segment
		(start 307.44414 -182.545482)
		(end 307.44414 -183.367172)
		(width 0.14605)
		(layer "In2.Cu")
		(net "DRIVE_B_22_ACT")
	)
	(segment
		(start 259.903722 -175.274732)
		(end 265.203686 -169.974768)
		(width 0.17145)
		(layer "F.Cu")
		(net "DRIVE_B_21_PWR")
	)
	(segment
		(start 310.518302 -168.985946)
		(end 311.846468 -170.314112)
		(width 0.17145)
		(layer "F.Cu")
		(net "DRIVE_B_21_PWR")
	)
	(segment
		(start 311.846468 -170.314112)
		(end 313.601608 -170.314112)
		(width 0.17145)
		(layer "F.Cu")
		(net "DRIVE_B_21_PWR")
	)
	(segment
		(start 265.203686 -169.974768)
		(end 288.282888 -169.974768)
		(width 0.17145)
		(layer "F.Cu")
		(net "DRIVE_B_21_PWR")
	)
	(segment
		(start 430.403 -128.2065)
		(end 431.292 -128.2065)
		(width 0.17145)
		(layer "F.Cu")
		(net "DRIVE_B_21_PWR")
	)
	(segment
		(start 313.601608 -170.314112)
		(end 314.11926 -169.79646)
		(width 0.17145)
		(layer "F.Cu")
		(net "DRIVE_B_21_PWR")
	)
	(segment
		(start 289.27171 -168.985946)
		(end 310.518302 -168.985946)
		(width 0.17145)
		(layer "F.Cu")
		(net "DRIVE_B_21_PWR")
	)
	(segment
		(start 259.903722 -186.146694)
		(end 259.903722 -175.274732)
		(width 0.17145)
		(layer "F.Cu")
		(net "DRIVE_B_21_PWR")
	)
	(segment
		(start 288.282888 -169.974768)
		(end 289.27171 -168.985946)
		(width 0.17145)
		(layer "F.Cu")
		(net "DRIVE_B_21_PWR")
	)
	(segment
		(start 240.6904 -200.7108)
		(end 248.02719 -200.7108)
		(width 0.17145)
		(layer "F.Cu")
		(net "DRIVE_B_21_PWR")
	)
	(segment
		(start 248.02719 -200.7108)
		(end 259.903722 -188.834268)
		(width 0.17145)
		(layer "F.Cu")
		(net "DRIVE_B_21_PWR")
	)
	(segment
		(start 259.903722 -188.834268)
		(end 259.903722 -186.146694)
		(width 0.17145)
		(layer "F.Cu")
		(net "DRIVE_B_21_PWR")
	)
	(via
		(at 259.903722 -186.146694)
		(size 0.6604)
		(drill 0.3302)
		(layers "F.Cu" "B.Cu")
		(net "DRIVE_B_21_PWR")
	)
	(via
		(at 431.292 -128.2065)
		(size 0.5588)
		(drill 0.3048)
		(layers "F.Cu" "B.Cu")
		(net "DRIVE_B_21_PWR")
	)
	(via
		(at 314.11926 -169.79646)
		(size 0.5588)
		(drill 0.3048)
		(layers "F.Cu" "B.Cu")
		(net "DRIVE_B_21_PWR")
	)
	(segment
		(start 321.45224 -158.369)
		(end 408.46502 -158.369)
		(width 0.14605)
		(layer "In2.Cu")
		(net "DRIVE_B_21_PWR")
	)
	(segment
		(start 314.11926 -169.79646)
		(end 314.764674 -169.79646)
		(width 0.14605)
		(layer "In2.Cu")
		(net "DRIVE_B_21_PWR")
	)
	(segment
		(start 431.041048 -130.346958)
		(end 431.292 -130.096006)
		(width 0.14605)
		(layer "In2.Cu")
		(net "DRIVE_B_21_PWR")
	)
	(segment
		(start 431.041048 -135.792972)
		(end 431.041048 -130.346958)
		(width 0.14605)
		(layer "In2.Cu")
		(net "DRIVE_B_21_PWR")
	)
	(segment
		(start 314.764674 -169.79646)
		(end 316.021974 -168.53916)
		(width 0.14605)
		(layer "In2.Cu")
		(net "DRIVE_B_21_PWR")
	)
	(segment
		(start 408.46502 -158.369)
		(end 431.041048 -135.792972)
		(width 0.14605)
		(layer "In2.Cu")
		(net "DRIVE_B_21_PWR")
	)
	(segment
		(start 316.021974 -163.799266)
		(end 321.45224 -158.369)
		(width 0.14605)
		(layer "In2.Cu")
		(net "DRIVE_B_21_PWR")
	)
	(segment
		(start 316.021974 -168.53916)
		(end 316.021974 -163.799266)
		(width 0.14605)
		(layer "In2.Cu")
		(net "DRIVE_B_21_PWR")
	)
	(segment
		(start 431.292 -130.096006)
		(end 431.292 -128.2065)
		(width 0.14605)
		(layer "In2.Cu")
		(net "DRIVE_B_21_PWR")
	)
	(segment
		(start 222.364808 -199.836532)
		(end 219.510102 -199.836532)
		(width 0.17145)
		(layer "F.Cu")
		(net "DRIVE_B_21_INS")
	)
	(segment
		(start 224.00006 -179.042314)
		(end 224.00006 -198.20128)
		(width 0.17145)
		(layer "F.Cu")
		(net "DRIVE_B_21_INS")
	)
	(segment
		(start 315.729112 -126.792228)
		(end 315.729112 -149.521926)
		(width 0.17145)
		(layer "F.Cu")
		(net "DRIVE_B_21_INS")
	)
	(segment
		(start 216.201498 -203.145136)
		(end 216.201498 -210.0707)
		(width 0.17145)
		(layer "F.Cu")
		(net "DRIVE_B_21_INS")
	)
	(segment
		(start 241.721386 -162.172904)
		(end 240.017046 -162.172904)
		(width 0.17145)
		(layer "F.Cu")
		(net "DRIVE_B_21_INS")
	)
	(segment
		(start 240.017046 -162.172904)
		(end 223.999806 -178.190144)
		(width 0.17145)
		(layer "F.Cu")
		(net "DRIVE_B_21_INS")
	)
	(segment
		(start 219.510102 -199.836532)
		(end 216.201498 -203.145136)
		(width 0.17145)
		(layer "F.Cu")
		(net "DRIVE_B_21_INS")
	)
	(segment
		(start 403.103842 -120.462294)
		(end 399.659348 -117.0178)
		(width 0.17145)
		(layer "F.Cu")
		(net "DRIVE_B_21_INS")
	)
	(segment
		(start 399.659348 -117.0178)
		(end 323.639688 -117.0178)
		(width 0.17145)
		(layer "F.Cu")
		(net "DRIVE_B_21_INS")
	)
	(segment
		(start 303.07788 -162.173158)
		(end 241.72164 -162.173158)
		(width 0.17145)
		(layer "F.Cu")
		(net "DRIVE_B_21_INS")
	)
	(segment
		(start 223.999806 -178.190144)
		(end 223.999806 -179.04206)
		(width 0.17145)
		(layer "F.Cu")
		(net "DRIVE_B_21_INS")
	)
	(segment
		(start 323.639688 -117.0178)
		(end 320.921126 -119.736362)
		(width 0.17145)
		(layer "F.Cu")
		(net "DRIVE_B_21_INS")
	)
	(segment
		(start 315.729112 -149.521926)
		(end 303.07788 -162.173158)
		(width 0.17145)
		(layer "F.Cu")
		(net "DRIVE_B_21_INS")
	)
	(segment
		(start 217.052398 -210.9216)
		(end 218.7194 -210.9216)
		(width 0.17145)
		(layer "F.Cu")
		(net "DRIVE_B_21_INS")
	)
	(segment
		(start 224.00006 -198.20128)
		(end 222.364808 -199.836532)
		(width 0.17145)
		(layer "F.Cu")
		(net "DRIVE_B_21_INS")
	)
	(segment
		(start 412.877 -130.235452)
		(end 403.103842 -120.462294)
		(width 0.17145)
		(layer "F.Cu")
		(net "DRIVE_B_21_INS")
	)
	(segment
		(start 223.999806 -179.04206)
		(end 224.00006 -179.042314)
		(width 0.17145)
		(layer "F.Cu")
		(net "DRIVE_B_21_INS")
	)
	(segment
		(start 320.921126 -121.600214)
		(end 315.729112 -126.792228)
		(width 0.17145)
		(layer "F.Cu")
		(net "DRIVE_B_21_INS")
	)
	(segment
		(start 216.201498 -210.0707)
		(end 217.052398 -210.9216)
		(width 0.17145)
		(layer "F.Cu")
		(net "DRIVE_B_21_INS")
	)
	(segment
		(start 412.877 -145.542)
		(end 412.877 -130.235452)
		(width 0.17145)
		(layer "F.Cu")
		(net "DRIVE_B_21_INS")
	)
	(segment
		(start 320.921126 -119.736362)
		(end 320.921126 -121.600214)
		(width 0.17145)
		(layer "F.Cu")
		(net "DRIVE_B_21_INS")
	)
	(segment
		(start 241.72164 -162.173158)
		(end 241.721386 -162.172904)
		(width 0.17145)
		(layer "F.Cu")
		(net "DRIVE_B_21_INS")
	)
	(via
		(at 403.103842 -120.462294)
		(size 0.6604)
		(drill 0.3302)
		(layers "F.Cu" "B.Cu")
		(net "DRIVE_B_21_INS")
	)
	(segment
		(start 322.986908 -114.0333)
		(end 396.470124 -114.0333)
		(width 0.17145)
		(layer "F.Cu")
		(net "DRIVE_B_21_FLT_LED")
	)
	(segment
		(start 318.349122 -120.534938)
		(end 318.349122 -118.671086)
		(width 0.17145)
		(layer "F.Cu")
		(net "DRIVE_B_21_FLT_LED")
	)
	(segment
		(start 407.538428 -102.964996)
		(end 407.538428 -102.413562)
		(width 0.17145)
		(layer "F.Cu")
		(net "DRIVE_B_21_FLT_LED")
	)
	(segment
		(start 210.584288 -191.1604)
		(end 209.629248 -190.20536)
		(width 0.17145)
		(layer "F.Cu")
		(net "DRIVE_B_21_FLT_LED")
	)
	(segment
		(start 238.545116 -159.601408)
		(end 238.951262 -159.601408)
		(width 0.17145)
		(layer "F.Cu")
		(net "DRIVE_B_21_FLT_LED")
	)
	(segment
		(start 209.629248 -188.51753)
		(end 237.942882 -160.203896)
		(width 0.17145)
		(layer "F.Cu")
		(net "DRIVE_B_21_FLT_LED")
	)
	(segment
		(start 396.470124 -114.0333)
		(end 400.896582 -109.606842)
		(width 0.17145)
		(layer "F.Cu")
		(net "DRIVE_B_21_FLT_LED")
	)
	(segment
		(start 302.01235 -159.601408)
		(end 311.229756 -150.384002)
		(width 0.17145)
		(layer "F.Cu")
		(net "DRIVE_B_21_FLT_LED")
	)
	(segment
		(start 400.896582 -109.606842)
		(end 407.538428 -102.964996)
		(width 0.17145)
		(layer "F.Cu")
		(net "DRIVE_B_21_FLT_LED")
	)
	(segment
		(start 311.229756 -150.384002)
		(end 311.229756 -127.654304)
		(width 0.17145)
		(layer "F.Cu")
		(net "DRIVE_B_21_FLT_LED")
	)
	(segment
		(start 237.942882 -160.203896)
		(end 237.942882 -160.203642)
		(width 0.17145)
		(layer "F.Cu")
		(net "DRIVE_B_21_FLT_LED")
	)
	(segment
		(start 407.538428 -102.413562)
		(end 407.538428 -100.709476)
		(width 0.17145)
		(layer "F.Cu")
		(net "DRIVE_B_21_FLT_LED")
	)
	(segment
		(start 211.6328 -191.1604)
		(end 210.584288 -191.1604)
		(width 0.17145)
		(layer "F.Cu")
		(net "DRIVE_B_21_FLT_LED")
	)
	(segment
		(start 237.942882 -160.203642)
		(end 238.545116 -159.601408)
		(width 0.17145)
		(layer "F.Cu")
		(net "DRIVE_B_21_FLT_LED")
	)
	(segment
		(start 242.786916 -159.601154)
		(end 242.78717 -159.601408)
		(width 0.17145)
		(layer "F.Cu")
		(net "DRIVE_B_21_FLT_LED")
	)
	(segment
		(start 209.629248 -190.20536)
		(end 209.629248 -188.51753)
		(width 0.17145)
		(layer "F.Cu")
		(net "DRIVE_B_21_FLT_LED")
	)
	(segment
		(start 311.229756 -127.654304)
		(end 318.349122 -120.534938)
		(width 0.17145)
		(layer "F.Cu")
		(net "DRIVE_B_21_FLT_LED")
	)
	(segment
		(start 238.951262 -159.601408)
		(end 238.951516 -159.601154)
		(width 0.17145)
		(layer "F.Cu")
		(net "DRIVE_B_21_FLT_LED")
	)
	(segment
		(start 238.951516 -159.601154)
		(end 242.786916 -159.601154)
		(width 0.17145)
		(layer "F.Cu")
		(net "DRIVE_B_21_FLT_LED")
	)
	(segment
		(start 318.349122 -118.671086)
		(end 322.986908 -114.0333)
		(width 0.17145)
		(layer "F.Cu")
		(net "DRIVE_B_21_FLT_LED")
	)
	(segment
		(start 242.78717 -159.601408)
		(end 302.01235 -159.601408)
		(width 0.17145)
		(layer "F.Cu")
		(net "DRIVE_B_21_FLT_LED")
	)
	(via
		(at 400.896582 -109.606842)
		(size 0.6604)
		(drill 0.3302)
		(layers "F.Cu" "B.Cu")
		(net "DRIVE_B_21_FLT_LED")
	)
	(segment
		(start 403.796246 -97.390204)
		(end 403.796246 -98.876104)
		(width 0.17145)
		(layer "F.Cu")
		(net "DRIVE_B_21_ACT")
	)
	(segment
		(start 403.796246 -94.549976)
		(end 403.796246 -97.390204)
		(width 0.17145)
		(layer "F.Cu")
		(net "DRIVE_B_21_ACT")
	)
	(via
		(at 307.997098 -184.98693)
		(size 0.5588)
		(drill 0.3048)
		(layers "F.Cu" "B.Cu")
		(net "DRIVE_B_21_ACT")
	)
	(via
		(at 302.984662 -184.98693)
		(size 0.6096)
		(drill 0.3048)
		(layers "F.Cu" "B.Cu")
		(net "DRIVE_B_21_ACT")
	)
	(via
		(at 403.796246 -94.549976)
		(size 0.5588)
		(drill 0.3048)
		(layers "F.Cu" "B.Cu")
		(net "DRIVE_B_21_ACT")
	)
	(segment
		(start 302.984662 -184.98693)
		(end 307.997098 -184.98693)
		(width 0.17145)
		(layer "B.Cu")
		(net "DRIVE_B_21_ACT")
	)
	(segment
		(start 292.834314 -189.45987)
		(end 292.838124 -189.45606)
		(width 0.17145)
		(layer "B.Cu")
		(net "DRIVE_B_21_ACT")
	)
	(segment
		(start 292.838124 -189.45606)
		(end 293.178484 -189.45606)
		(width 0.17145)
		(layer "B.Cu")
		(net "DRIVE_B_21_ACT")
	)
	(segment
		(start 282.471114 -189.45987)
		(end 292.834314 -189.45987)
		(width 0.17145)
		(layer "B.Cu")
		(net "DRIVE_B_21_ACT")
	)
	(segment
		(start 297.647614 -184.98693)
		(end 302.984662 -184.98693)
		(width 0.17145)
		(layer "B.Cu")
		(net "DRIVE_B_21_ACT")
	)
	(segment
		(start 281.836622 -190.094362)
		(end 282.471114 -189.45987)
		(width 0.17145)
		(layer "B.Cu")
		(net "DRIVE_B_21_ACT")
	)
	(segment
		(start 293.178484 -189.45606)
		(end 297.647614 -184.98693)
		(width 0.17145)
		(layer "B.Cu")
		(net "DRIVE_B_21_ACT")
	)
	(segment
		(start 325.568818 -117.2083)
		(end 377.1265 -117.2083)
		(width 0.14605)
		(layer "In2.Cu")
		(net "DRIVE_B_21_ACT")
	)
	(segment
		(start 311.083452 -131.693666)
		(end 325.568818 -117.2083)
		(width 0.14605)
		(layer "In2.Cu")
		(net "DRIVE_B_21_ACT")
	)
	(segment
		(start 311.083452 -178.045618)
		(end 311.083452 -131.693666)
		(width 0.14605)
		(layer "In2.Cu")
		(net "DRIVE_B_21_ACT")
	)
	(segment
		(start 399.784824 -94.549976)
		(end 403.796246 -94.549976)
		(width 0.14605)
		(layer "In2.Cu")
		(net "DRIVE_B_21_ACT")
	)
	(segment
		(start 306.98948 -182.13959)
		(end 311.083452 -178.045618)
		(width 0.14605)
		(layer "In2.Cu")
		(net "DRIVE_B_21_ACT")
	)
	(segment
		(start 307.997098 -184.98693)
		(end 306.98948 -183.979312)
		(width 0.14605)
		(layer "In2.Cu")
		(net "DRIVE_B_21_ACT")
	)
	(segment
		(start 377.1265 -117.2083)
		(end 399.784824 -94.549976)
		(width 0.14605)
		(layer "In2.Cu")
		(net "DRIVE_B_21_ACT")
	)
	(segment
		(start 306.98948 -183.979312)
		(end 306.98948 -182.13959)
		(width 0.14605)
		(layer "In2.Cu")
		(net "DRIVE_B_21_ACT")
	)
	(segment
		(start 258.898136 -189.112398)
		(end 258.898136 -183.313832)
		(width 0.17145)
		(layer "F.Cu")
		(net "DRIVE_B_20_PWR")
	)
	(segment
		(start 288.069782 -169.460418)
		(end 289.058604 -168.471596)
		(width 0.17145)
		(layer "F.Cu")
		(net "DRIVE_B_20_PWR")
	)
	(segment
		(start 289.058604 -168.471596)
		(end 310.731408 -168.471596)
		(width 0.17145)
		(layer "F.Cu")
		(net "DRIVE_B_20_PWR")
	)
	(segment
		(start 258.898136 -174.839122)
		(end 264.27684 -169.460418)
		(width 0.17145)
		(layer "F.Cu")
		(net "DRIVE_B_20_PWR")
	)
	(segment
		(start 310.731408 -168.471596)
		(end 312.056272 -169.79646)
		(width 0.17145)
		(layer "F.Cu")
		(net "DRIVE_B_20_PWR")
	)
	(segment
		(start 398.907 -128.2065)
		(end 399.796 -128.2065)
		(width 0.17145)
		(layer "F.Cu")
		(net "DRIVE_B_20_PWR")
	)
	(segment
		(start 312.056272 -169.79646)
		(end 313.05246 -169.79646)
		(width 0.17145)
		(layer "F.Cu")
		(net "DRIVE_B_20_PWR")
	)
	(segment
		(start 247.949974 -200.06056)
		(end 258.898136 -189.112398)
		(width 0.17145)
		(layer "F.Cu")
		(net "DRIVE_B_20_PWR")
	)
	(segment
		(start 240.6904 -200.06056)
		(end 247.949974 -200.06056)
		(width 0.17145)
		(layer "F.Cu")
		(net "DRIVE_B_20_PWR")
	)
	(segment
		(start 264.27684 -169.460418)
		(end 288.069782 -169.460418)
		(width 0.17145)
		(layer "F.Cu")
		(net "DRIVE_B_20_PWR")
	)
	(segment
		(start 258.898136 -183.313832)
		(end 258.898136 -174.839122)
		(width 0.17145)
		(layer "F.Cu")
		(net "DRIVE_B_20_PWR")
	)
	(via
		(at 258.898136 -183.313832)
		(size 0.6604)
		(drill 0.3302)
		(layers "F.Cu" "B.Cu")
		(net "DRIVE_B_20_PWR")
	)
	(via
		(at 313.05246 -169.79646)
		(size 0.5588)
		(drill 0.3048)
		(layers "F.Cu" "B.Cu")
		(net "DRIVE_B_20_PWR")
	)
	(via
		(at 399.796 -128.2065)
		(size 0.5588)
		(drill 0.3048)
		(layers "F.Cu" "B.Cu")
		(net "DRIVE_B_20_PWR")
	)
	(segment
		(start 399.545048 -135.73887)
		(end 378.057918 -157.226)
		(width 0.14605)
		(layer "In2.Cu")
		(net "DRIVE_B_20_PWR")
	)
	(segment
		(start 314.528708 -169.234612)
		(end 313.614308 -169.234612)
		(width 0.14605)
		(layer "In2.Cu")
		(net "DRIVE_B_20_PWR")
	)
	(segment
		(start 399.545048 -130.346958)
		(end 399.545048 -135.73887)
		(width 0.14605)
		(layer "In2.Cu")
		(net "DRIVE_B_20_PWR")
	)
	(segment
		(start 315.245496 -168.517824)
		(end 314.528708 -169.234612)
		(width 0.14605)
		(layer "In2.Cu")
		(net "DRIVE_B_20_PWR")
	)
	(segment
		(start 321.45224 -157.226)
		(end 315.245496 -163.432744)
		(width 0.14605)
		(layer "In2.Cu")
		(net "DRIVE_B_20_PWR")
	)
	(segment
		(start 399.796 -130.096006)
		(end 399.545048 -130.346958)
		(width 0.14605)
		(layer "In2.Cu")
		(net "DRIVE_B_20_PWR")
	)
	(segment
		(start 315.245496 -163.432744)
		(end 315.245496 -168.517824)
		(width 0.14605)
		(layer "In2.Cu")
		(net "DRIVE_B_20_PWR")
	)
	(segment
		(start 399.796 -128.2065)
		(end 399.796 -130.096006)
		(width 0.14605)
		(layer "In2.Cu")
		(net "DRIVE_B_20_PWR")
	)
	(segment
		(start 378.057918 -157.226)
		(end 321.45224 -157.226)
		(width 0.14605)
		(layer "In2.Cu")
		(net "DRIVE_B_20_PWR")
	)
	(segment
		(start 313.614308 -169.234612)
		(end 313.05246 -169.79646)
		(width 0.14605)
		(layer "In2.Cu")
		(net "DRIVE_B_20_PWR")
	)
	(segment
		(start 240.230152 -162.687254)
		(end 224.514156 -178.40325)
		(width 0.17145)
		(layer "F.Cu")
		(net "DRIVE_B_20_INS")
	)
	(segment
		(start 316.673992 -149.304502)
		(end 303.290986 -162.687508)
		(width 0.17145)
		(layer "F.Cu")
		(net "DRIVE_B_20_INS")
	)
	(segment
		(start 216.715848 -203.358242)
		(end 216.715848 -209.665316)
		(width 0.17145)
		(layer "F.Cu")
		(net "DRIVE_B_20_INS")
	)
	(segment
		(start 241.50828 -162.687254)
		(end 240.230152 -162.687254)
		(width 0.17145)
		(layer "F.Cu")
		(net "DRIVE_B_20_INS")
	)
	(segment
		(start 323.175884 -118.20906)
		(end 321.435476 -119.949468)
		(width 0.17145)
		(layer "F.Cu")
		(net "DRIVE_B_20_INS")
	)
	(segment
		(start 217.321892 -210.27136)
		(end 218.7194 -210.27136)
		(width 0.17145)
		(layer "F.Cu")
		(net "DRIVE_B_20_INS")
	)
	(segment
		(start 219.722954 -200.351136)
		(end 216.715848 -203.358242)
		(width 0.17145)
		(layer "F.Cu")
		(net "DRIVE_B_20_INS")
	)
	(segment
		(start 316.673992 -126.574804)
		(end 316.673992 -149.304502)
		(width 0.17145)
		(layer "F.Cu")
		(net "DRIVE_B_20_INS")
	)
	(segment
		(start 367.910618 -118.20906)
		(end 323.175884 -118.20906)
		(width 0.17145)
		(layer "F.Cu")
		(net "DRIVE_B_20_INS")
	)
	(segment
		(start 321.435476 -121.81332)
		(end 316.673992 -126.574804)
		(width 0.17145)
		(layer "F.Cu")
		(net "DRIVE_B_20_INS")
	)
	(segment
		(start 303.290986 -162.687508)
		(end 241.508534 -162.687508)
		(width 0.17145)
		(layer "F.Cu")
		(net "DRIVE_B_20_INS")
	)
	(segment
		(start 381.2032 -145.4912)
		(end 381.2032 -131.501642)
		(width 0.17145)
		(layer "F.Cu")
		(net "DRIVE_B_20_INS")
	)
	(segment
		(start 372.15953 -122.457972)
		(end 367.910618 -118.20906)
		(width 0.17145)
		(layer "F.Cu")
		(net "DRIVE_B_20_INS")
	)
	(segment
		(start 224.51441 -198.414386)
		(end 222.57766 -200.351136)
		(width 0.17145)
		(layer "F.Cu")
		(net "DRIVE_B_20_INS")
	)
	(segment
		(start 216.715848 -209.665316)
		(end 217.321892 -210.27136)
		(width 0.17145)
		(layer "F.Cu")
		(net "DRIVE_B_20_INS")
	)
	(segment
		(start 222.57766 -200.351136)
		(end 219.722954 -200.351136)
		(width 0.17145)
		(layer "F.Cu")
		(net "DRIVE_B_20_INS")
	)
	(segment
		(start 224.514156 -178.828954)
		(end 224.51441 -178.829208)
		(width 0.17145)
		(layer "F.Cu")
		(net "DRIVE_B_20_INS")
	)
	(segment
		(start 224.514156 -178.40325)
		(end 224.514156 -178.828954)
		(width 0.17145)
		(layer "F.Cu")
		(net "DRIVE_B_20_INS")
	)
	(segment
		(start 224.51441 -178.829208)
		(end 224.51441 -198.414386)
		(width 0.17145)
		(layer "F.Cu")
		(net "DRIVE_B_20_INS")
	)
	(segment
		(start 241.508534 -162.687508)
		(end 241.50828 -162.687254)
		(width 0.17145)
		(layer "F.Cu")
		(net "DRIVE_B_20_INS")
	)
	(segment
		(start 321.435476 -119.949468)
		(end 321.435476 -121.81332)
		(width 0.17145)
		(layer "F.Cu")
		(net "DRIVE_B_20_INS")
	)
	(segment
		(start 381.2032 -131.501642)
		(end 372.15953 -122.457972)
		(width 0.17145)
		(layer "F.Cu")
		(net "DRIVE_B_20_INS")
	)
	(via
		(at 372.15953 -122.457972)
		(size 0.6604)
		(drill 0.3302)
		(layers "F.Cu" "B.Cu")
		(net "DRIVE_B_20_INS")
	)
	(segment
		(start 238.33201 -159.087058)
		(end 238.738156 -159.087058)
		(width 0.17145)
		(layer "F.Cu")
		(net "DRIVE_B_20_FLT_LED")
	)
	(segment
		(start 238.738156 -159.087058)
		(end 238.73841 -159.086804)
		(width 0.17145)
		(layer "F.Cu")
		(net "DRIVE_B_20_FLT_LED")
	)
	(segment
		(start 210.507072 -191.81064)
		(end 209.114898 -190.418466)
		(width 0.17145)
		(layer "F.Cu")
		(net "DRIVE_B_20_FLT_LED")
	)
	(segment
		(start 237.428532 -159.990536)
		(end 238.33201 -159.087058)
		(width 0.17145)
		(layer "F.Cu")
		(net "DRIVE_B_20_FLT_LED")
	)
	(segment
		(start 375.988326 -104.2035)
		(end 375.988326 -102.413562)
		(width 0.17145)
		(layer "F.Cu")
		(net "DRIVE_B_20_FLT_LED")
	)
	(segment
		(start 310.264048 -150.195534)
		(end 310.264048 -127.892556)
		(width 0.17145)
		(layer "F.Cu")
		(net "DRIVE_B_20_FLT_LED")
	)
	(segment
		(start 375.988326 -102.413562)
		(end 375.988326 -100.709476)
		(width 0.17145)
		(layer "F.Cu")
		(net "DRIVE_B_20_FLT_LED")
	)
	(segment
		(start 243.000022 -159.086804)
		(end 243.000276 -159.087058)
		(width 0.17145)
		(layer "F.Cu")
		(net "DRIVE_B_20_FLT_LED")
	)
	(segment
		(start 322.773802 -113.51895)
		(end 366.672876 -113.51895)
		(width 0.17145)
		(layer "F.Cu")
		(net "DRIVE_B_20_FLT_LED")
	)
	(segment
		(start 317.834772 -120.321832)
		(end 317.834772 -118.45798)
		(width 0.17145)
		(layer "F.Cu")
		(net "DRIVE_B_20_FLT_LED")
	)
	(segment
		(start 243.000276 -159.087058)
		(end 301.372524 -159.087058)
		(width 0.17145)
		(layer "F.Cu")
		(net "DRIVE_B_20_FLT_LED")
	)
	(segment
		(start 209.114898 -188.304424)
		(end 237.428532 -159.99079)
		(width 0.17145)
		(layer "F.Cu")
		(net "DRIVE_B_20_FLT_LED")
	)
	(segment
		(start 301.372524 -159.087058)
		(end 310.264048 -150.195534)
		(width 0.17145)
		(layer "F.Cu")
		(net "DRIVE_B_20_FLT_LED")
	)
	(segment
		(start 211.6328 -191.81064)
		(end 210.507072 -191.81064)
		(width 0.17145)
		(layer "F.Cu")
		(net "DRIVE_B_20_FLT_LED")
	)
	(segment
		(start 317.834772 -118.45798)
		(end 322.773802 -113.51895)
		(width 0.17145)
		(layer "F.Cu")
		(net "DRIVE_B_20_FLT_LED")
	)
	(segment
		(start 237.428532 -159.99079)
		(end 237.428532 -159.990536)
		(width 0.17145)
		(layer "F.Cu")
		(net "DRIVE_B_20_FLT_LED")
	)
	(segment
		(start 209.114898 -190.418466)
		(end 209.114898 -188.304424)
		(width 0.17145)
		(layer "F.Cu")
		(net "DRIVE_B_20_FLT_LED")
	)
	(segment
		(start 371.4369 -108.754926)
		(end 375.988326 -104.2035)
		(width 0.17145)
		(layer "F.Cu")
		(net "DRIVE_B_20_FLT_LED")
	)
	(segment
		(start 366.672876 -113.51895)
		(end 371.4369 -108.754926)
		(width 0.17145)
		(layer "F.Cu")
		(net "DRIVE_B_20_FLT_LED")
	)
	(segment
		(start 238.73841 -159.086804)
		(end 243.000022 -159.086804)
		(width 0.17145)
		(layer "F.Cu")
		(net "DRIVE_B_20_FLT_LED")
	)
	(segment
		(start 310.264048 -127.892556)
		(end 317.834772 -120.321832)
		(width 0.17145)
		(layer "F.Cu")
		(net "DRIVE_B_20_FLT_LED")
	)
	(via
		(at 371.4369 -108.754926)
		(size 0.6604)
		(drill 0.3302)
		(layers "F.Cu" "B.Cu")
		(net "DRIVE_B_20_FLT_LED")
	)
	(segment
		(start 372.246144 -97.390204)
		(end 372.246144 -98.876104)
		(width 0.17145)
		(layer "F.Cu")
		(net "DRIVE_B_20_ACT")
	)
	(segment
		(start 372.246144 -94.549976)
		(end 372.246144 -97.390204)
		(width 0.17145)
		(layer "F.Cu")
		(net "DRIVE_B_20_ACT")
	)
	(via
		(at 304.251868 -186.05373)
		(size 0.6096)
		(drill 0.3048)
		(layers "F.Cu" "B.Cu")
		(net "DRIVE_B_20_ACT")
	)
	(via
		(at 372.246144 -94.549976)
		(size 0.5588)
		(drill 0.3048)
		(layers "F.Cu" "B.Cu")
		(net "DRIVE_B_20_ACT")
	)
	(via
		(at 307.997098 -186.05373)
		(size 0.5588)
		(drill 0.3048)
		(layers "F.Cu" "B.Cu")
		(net "DRIVE_B_20_ACT")
	)
	(segment
		(start 283.871162 -190.728854)
		(end 293.344346 -190.728854)
		(width 0.17145)
		(layer "B.Cu")
		(net "DRIVE_B_20_ACT")
	)
	(segment
		(start 293.344346 -190.728854)
		(end 298.01947 -186.05373)
		(width 0.17145)
		(layer "B.Cu")
		(net "DRIVE_B_20_ACT")
	)
	(segment
		(start 283.23667 -190.094362)
		(end 283.871162 -190.728854)
		(width 0.17145)
		(layer "B.Cu")
		(net "DRIVE_B_20_ACT")
	)
	(segment
		(start 298.01947 -186.05373)
		(end 304.251868 -186.05373)
		(width 0.17145)
		(layer "B.Cu")
		(net "DRIVE_B_20_ACT")
	)
	(segment
		(start 304.251868 -186.05373)
		(end 307.997098 -186.05373)
		(width 0.17145)
		(layer "B.Cu")
		(net "DRIVE_B_20_ACT")
	)
	(segment
		(start 310.645302 -177.395124)
		(end 310.645302 -131.512056)
		(width 0.14605)
		(layer "In2.Cu")
		(net "DRIVE_B_20_ACT")
	)
	(segment
		(start 306.388516 -181.65191)
		(end 310.645302 -177.395124)
		(width 0.14605)
		(layer "In2.Cu")
		(net "DRIVE_B_20_ACT")
	)
	(segment
		(start 306.388516 -184.445148)
		(end 306.388516 -181.65191)
		(width 0.14605)
		(layer "In2.Cu")
		(net "DRIVE_B_20_ACT")
	)
	(segment
		(start 369.934236 -96.861884)
		(end 372.246144 -94.549976)
		(width 0.14605)
		(layer "In2.Cu")
		(net "DRIVE_B_20_ACT")
	)
	(segment
		(start 325.387208 -116.77015)
		(end 339.194648 -116.77015)
		(width 0.14605)
		(layer "In2.Cu")
		(net "DRIVE_B_20_ACT")
	)
	(segment
		(start 307.997098 -186.05373)
		(end 306.388516 -184.445148)
		(width 0.14605)
		(layer "In2.Cu")
		(net "DRIVE_B_20_ACT")
	)
	(segment
		(start 359.102914 -96.861884)
		(end 369.934236 -96.861884)
		(width 0.14605)
		(layer "In2.Cu")
		(net "DRIVE_B_20_ACT")
	)
	(segment
		(start 339.194648 -116.77015)
		(end 359.102914 -96.861884)
		(width 0.14605)
		(layer "In2.Cu")
		(net "DRIVE_B_20_ACT")
	)
	(segment
		(start 310.645302 -131.512056)
		(end 325.387208 -116.77015)
		(width 0.14605)
		(layer "In2.Cu")
		(net "DRIVE_B_20_ACT")
	)
	(segment
		(start 217.9828 -233.44124)
		(end 216.763092 -232.221532)
		(width 0.17145)
		(layer "F.Cu")
		(net "DRIVE_B_2_PWR")
	)
	(segment
		(start 216.763092 -232.221532)
		(end 214.98179 -230.44023)
		(width 0.17145)
		(layer "F.Cu")
		(net "DRIVE_B_2_PWR")
	)
	(segment
		(start 203.693522 -230.44023)
		(end 203.558902 -230.57485)
		(width 0.17145)
		(layer "F.Cu")
		(net "DRIVE_B_2_PWR")
	)
	(segment
		(start 203.558902 -230.57485)
		(end 152.582626 -230.57485)
		(width 0.17145)
		(layer "F.Cu")
		(net "DRIVE_B_2_PWR")
	)
	(segment
		(start 229.82428 -229.251256)
		(end 229.82428 -230.769922)
		(width 0.17145)
		(layer "F.Cu")
		(net "DRIVE_B_2_PWR")
	)
	(segment
		(start 227.152962 -233.44124)
		(end 217.9828 -233.44124)
		(width 0.17145)
		(layer "F.Cu")
		(net "DRIVE_B_2_PWR")
	)
	(segment
		(start 86.8426 -246.2276)
		(end 85.9155 -246.2276)
		(width 0.17145)
		(layer "F.Cu")
		(net "DRIVE_B_2_PWR")
	)
	(segment
		(start 152.582626 -230.57485)
		(end 150.851616 -228.84384)
		(width 0.17145)
		(layer "F.Cu")
		(net "DRIVE_B_2_PWR")
	)
	(segment
		(start 214.98179 -230.44023)
		(end 203.693522 -230.44023)
		(width 0.17145)
		(layer "F.Cu")
		(net "DRIVE_B_2_PWR")
	)
	(segment
		(start 229.82428 -230.769922)
		(end 227.152962 -233.44124)
		(width 0.17145)
		(layer "F.Cu")
		(net "DRIVE_B_2_PWR")
	)
	(via
		(at 216.763092 -232.221532)
		(size 0.6604)
		(drill 0.3302)
		(layers "F.Cu" "B.Cu")
		(net "DRIVE_B_2_PWR")
	)
	(via
		(at 86.8426 -246.2276)
		(size 0.5588)
		(drill 0.3048)
		(layers "F.Cu" "B.Cu")
		(net "DRIVE_B_2_PWR")
	)
	(via
		(at 150.851616 -228.84384)
		(size 0.5588)
		(drill 0.3048)
		(layers "F.Cu" "B.Cu")
		(net "DRIVE_B_2_PWR")
	)
	(segment
		(start 96.540066 -236.530134)
		(end 143.165322 -236.530134)
		(width 0.14605)
		(layer "In2.Cu")
		(net "DRIVE_B_2_PWR")
	)
	(segment
		(start 143.165322 -236.530134)
		(end 150.851616 -228.84384)
		(width 0.14605)
		(layer "In2.Cu")
		(net "DRIVE_B_2_PWR")
	)
	(segment
		(start 86.8426 -246.2276)
		(end 96.540066 -236.530134)
		(width 0.14605)
		(layer "In2.Cu")
		(net "DRIVE_B_2_PWR")
	)
	(segment
		(start 206.035148 -272.703544)
		(end 206.035148 -261.358634)
		(width 0.17145)
		(layer "F.Cu")
		(net "DRIVE_B_2_INS")
	)
	(segment
		(start 206.9465 -244.48262)
		(end 206.9465 -247.164606)
		(width 0.17145)
		(layer "F.Cu")
		(net "DRIVE_B_2_INS")
	)
	(segment
		(start 206.035148 -261.358634)
		(end 205.930754 -261.25424)
		(width 0.17145)
		(layer "F.Cu")
		(net "DRIVE_B_2_INS")
	)
	(segment
		(start 206.035148 -261.149846)
		(end 205.930754 -261.25424)
		(width 0.17145)
		(layer "F.Cu")
		(net "DRIVE_B_2_INS")
	)
	(segment
		(start 206.035148 -248.075958)
		(end 206.035148 -261.149846)
		(width 0.17145)
		(layer "F.Cu")
		(net "DRIVE_B_2_INS")
	)
	(segment
		(start 100.56622 -285.3817)
		(end 193.356992 -285.3817)
		(width 0.17145)
		(layer "F.Cu")
		(net "DRIVE_B_2_INS")
	)
	(segment
		(start 193.356992 -285.3817)
		(end 206.035148 -272.703544)
		(width 0.17145)
		(layer "F.Cu")
		(net "DRIVE_B_2_INS")
	)
	(segment
		(start 99.568 -266.065)
		(end 99.568 -284.38348)
		(width 0.17145)
		(layer "F.Cu")
		(net "DRIVE_B_2_INS")
	)
	(segment
		(start 99.568 -284.38348)
		(end 100.56622 -285.3817)
		(width 0.17145)
		(layer "F.Cu")
		(net "DRIVE_B_2_INS")
	)
	(segment
		(start 206.9465 -247.164606)
		(end 206.035148 -248.075958)
		(width 0.17145)
		(layer "F.Cu")
		(net "DRIVE_B_2_INS")
	)
	(via
		(at 205.930754 -261.25424)
		(size 0.6604)
		(drill 0.3302)
		(layers "F.Cu" "B.Cu")
		(net "DRIVE_B_2_INS")
	)
	(segment
		(start 78.55585 -217.413586)
		(end 78.55585 -215.7095)
		(width 0.17145)
		(layer "F.Cu")
		(net "DRIVE_B_2_FLT_LED")
	)
	(segment
		(start 78.55585 -219.738194)
		(end 78.55585 -217.413586)
		(width 0.17145)
		(layer "F.Cu")
		(net "DRIVE_B_2_FLT_LED")
	)
	(segment
		(start 81.667858 -222.850202)
		(end 79.354172 -220.536516)
		(width 0.17145)
		(layer "F.Cu")
		(net "DRIVE_B_2_FLT_LED")
	)
	(segment
		(start 198.757286 -221.55912)
		(end 197.466204 -222.850202)
		(width 0.17145)
		(layer "F.Cu")
		(net "DRIVE_B_2_FLT_LED")
	)
	(segment
		(start 197.466204 -222.850202)
		(end 81.667858 -222.850202)
		(width 0.17145)
		(layer "F.Cu")
		(net "DRIVE_B_2_FLT_LED")
	)
	(segment
		(start 212.9536 -221.55912)
		(end 198.757286 -221.55912)
		(width 0.17145)
		(layer "F.Cu")
		(net "DRIVE_B_2_FLT_LED")
	)
	(segment
		(start 79.354172 -220.536516)
		(end 78.55585 -219.738194)
		(width 0.17145)
		(layer "F.Cu")
		(net "DRIVE_B_2_FLT_LED")
	)
	(via
		(at 79.354172 -220.536516)
		(size 0.6604)
		(drill 0.3302)
		(layers "F.Cu" "B.Cu")
		(net "DRIVE_B_2_FLT_LED")
	)
	(segment
		(start 256.360168 -204.434694)
		(end 255.363726 -203.438252)
		(width 0.17145)
		(layer "F.Cu")
		(net "DRIVE_B_2_ACT")
	)
	(segment
		(start 255.363726 -203.438252)
		(end 242.891056 -203.438252)
		(width 0.17145)
		(layer "F.Cu")
		(net "DRIVE_B_2_ACT")
	)
	(segment
		(start 233.470958 -205.03515)
		(end 232.88117 -205.624938)
		(width 0.17145)
		(layer "F.Cu")
		(net "DRIVE_B_2_ACT")
	)
	(segment
		(start 241.954812 -204.374496)
		(end 235.16844 -204.374496)
		(width 0.17145)
		(layer "F.Cu")
		(net "DRIVE_B_2_ACT")
	)
	(segment
		(start 74.813668 -212.390228)
		(end 74.813668 -213.876128)
		(width 0.17145)
		(layer "F.Cu")
		(net "DRIVE_B_2_ACT")
	)
	(segment
		(start 284.236668 -206.294482)
		(end 283.07411 -205.131924)
		(width 0.17145)
		(layer "F.Cu")
		(net "DRIVE_B_2_ACT")
	)
	(segment
		(start 74.813668 -210.6549)
		(end 74.813668 -212.390228)
		(width 0.17145)
		(layer "F.Cu")
		(net "DRIVE_B_2_ACT")
	)
	(segment
		(start 235.16844 -204.374496)
		(end 234.507786 -205.03515)
		(width 0.17145)
		(layer "F.Cu")
		(net "DRIVE_B_2_ACT")
	)
	(segment
		(start 276.717506 -205.131924)
		(end 276.707346 -205.142084)
		(width 0.17145)
		(layer "F.Cu")
		(net "DRIVE_B_2_ACT")
	)
	(segment
		(start 283.07411 -205.131924)
		(end 276.717506 -205.131924)
		(width 0.17145)
		(layer "F.Cu")
		(net "DRIVE_B_2_ACT")
	)
	(segment
		(start 234.507786 -205.03515)
		(end 233.470958 -205.03515)
		(width 0.17145)
		(layer "F.Cu")
		(net "DRIVE_B_2_ACT")
	)
	(segment
		(start 274.819618 -204.434694)
		(end 256.360168 -204.434694)
		(width 0.17145)
		(layer "F.Cu")
		(net "DRIVE_B_2_ACT")
	)
	(segment
		(start 275.527008 -205.142084)
		(end 274.819618 -204.434694)
		(width 0.17145)
		(layer "F.Cu")
		(net "DRIVE_B_2_ACT")
	)
	(segment
		(start 276.707346 -205.142084)
		(end 275.527008 -205.142084)
		(width 0.17145)
		(layer "F.Cu")
		(net "DRIVE_B_2_ACT")
	)
	(segment
		(start 74.813668 -210.6549)
		(end 74.813668 -209.55)
		(width 0.17145)
		(layer "F.Cu")
		(net "DRIVE_B_2_ACT")
	)
	(segment
		(start 232.88117 -205.624938)
		(end 232.88117 -205.977236)
		(width 0.17145)
		(layer "F.Cu")
		(net "DRIVE_B_2_ACT")
	)
	(segment
		(start 242.891056 -203.438252)
		(end 241.954812 -204.374496)
		(width 0.17145)
		(layer "F.Cu")
		(net "DRIVE_B_2_ACT")
	)
	(via
		(at 232.88117 -205.977236)
		(size 0.5588)
		(drill 0.3048)
		(layers "F.Cu" "B.Cu")
		(net "DRIVE_B_2_ACT")
	)
	(via
		(at 74.813668 -209.55)
		(size 0.5588)
		(drill 0.3048)
		(layers "F.Cu" "B.Cu")
		(net "DRIVE_B_2_ACT")
	)
	(via
		(at 74.813668 -210.6549)
		(size 0.6604)
		(drill 0.3302)
		(layers "F.Cu" "B.Cu")
		(net "DRIVE_B_2_ACT")
	)
	(segment
		(start 78.486 -209.55)
		(end 87.627206 -218.691206)
		(width 0.14605)
		(layer "In5.Cu")
		(net "DRIVE_B_2_ACT")
	)
	(segment
		(start 207.715612 -210.993482)
		(end 227.864924 -210.993482)
		(width 0.14605)
		(layer "In5.Cu")
		(net "DRIVE_B_2_ACT")
	)
	(segment
		(start 74.813668 -209.55)
		(end 78.486 -209.55)
		(width 0.14605)
		(layer "In5.Cu")
		(net "DRIVE_B_2_ACT")
	)
	(segment
		(start 87.627206 -218.691206)
		(end 200.017888 -218.691206)
		(width 0.14605)
		(layer "In5.Cu")
		(net "DRIVE_B_2_ACT")
	)
	(segment
		(start 200.017888 -218.691206)
		(end 207.715612 -210.993482)
		(width 0.14605)
		(layer "In5.Cu")
		(net "DRIVE_B_2_ACT")
	)
	(segment
		(start 227.864924 -210.993482)
		(end 232.88117 -205.977236)
		(width 0.14605)
		(layer "In5.Cu")
		(net "DRIVE_B_2_ACT")
	)
	(segment
		(start 311.021984 -167.957246)
		(end 312.31205 -169.247312)
		(width 0.17145)
		(layer "F.Cu")
		(net "DRIVE_B_19_PWR")
	)
	(segment
		(start 313.601608 -169.247312)
		(end 314.11926 -168.72966)
		(width 0.17145)
		(layer "F.Cu")
		(net "DRIVE_B_19_PWR")
	)
	(segment
		(start 257.966972 -189.316106)
		(end 247.872758 -199.41032)
		(width 0.17145)
		(layer "F.Cu")
		(net "DRIVE_B_19_PWR")
	)
	(segment
		(start 257.966972 -174.627286)
		(end 263.64819 -168.946068)
		(width 0.17145)
		(layer "F.Cu")
		(net "DRIVE_B_19_PWR")
	)
	(segment
		(start 367.284 -128.2065)
		(end 368.173 -128.2065)
		(width 0.17145)
		(layer "F.Cu")
		(net "DRIVE_B_19_PWR")
	)
	(segment
		(start 257.966972 -178.030632)
		(end 257.966972 -174.627286)
		(width 0.17145)
		(layer "F.Cu")
		(net "DRIVE_B_19_PWR")
	)
	(segment
		(start 312.31205 -169.247312)
		(end 313.601608 -169.247312)
		(width 0.17145)
		(layer "F.Cu")
		(net "DRIVE_B_19_PWR")
	)
	(segment
		(start 288.845498 -167.957246)
		(end 311.021984 -167.957246)
		(width 0.17145)
		(layer "F.Cu")
		(net "DRIVE_B_19_PWR")
	)
	(segment
		(start 247.872758 -199.41032)
		(end 240.6904 -199.41032)
		(width 0.17145)
		(layer "F.Cu")
		(net "DRIVE_B_19_PWR")
	)
	(segment
		(start 287.856676 -168.946068)
		(end 288.845498 -167.957246)
		(width 0.17145)
		(layer "F.Cu")
		(net "DRIVE_B_19_PWR")
	)
	(segment
		(start 263.64819 -168.946068)
		(end 287.856676 -168.946068)
		(width 0.17145)
		(layer "F.Cu")
		(net "DRIVE_B_19_PWR")
	)
	(segment
		(start 257.966972 -178.030632)
		(end 257.966972 -189.316106)
		(width 0.17145)
		(layer "F.Cu")
		(net "DRIVE_B_19_PWR")
	)
	(via
		(at 314.11926 -168.72966)
		(size 0.5588)
		(drill 0.3048)
		(layers "F.Cu" "B.Cu")
		(net "DRIVE_B_19_PWR")
	)
	(via
		(at 368.173 -128.2065)
		(size 0.5588)
		(drill 0.3048)
		(layers "F.Cu" "B.Cu")
		(net "DRIVE_B_19_PWR")
	)
	(via
		(at 257.966972 -178.030632)
		(size 0.6604)
		(drill 0.3302)
		(layers "F.Cu" "B.Cu")
		(net "DRIVE_B_19_PWR")
	)
	(segment
		(start 368.173 -128.2065)
		(end 367.922048 -128.457452)
		(width 0.14605)
		(layer "In2.Cu")
		(net "DRIVE_B_19_PWR")
	)
	(segment
		(start 321.811142 -155.470098)
		(end 314.11926 -163.16198)
		(width 0.14605)
		(layer "In2.Cu")
		(net "DRIVE_B_19_PWR")
	)
	(segment
		(start 314.11926 -163.16198)
		(end 314.11926 -168.72966)
		(width 0.14605)
		(layer "In2.Cu")
		(net "DRIVE_B_19_PWR")
	)
	(segment
		(start 367.922048 -135.812022)
		(end 348.263972 -155.470098)
		(width 0.14605)
		(layer "In2.Cu")
		(net "DRIVE_B_19_PWR")
	)
	(segment
		(start 348.263972 -155.470098)
		(end 321.811142 -155.470098)
		(width 0.14605)
		(layer "In2.Cu")
		(net "DRIVE_B_19_PWR")
	)
	(segment
		(start 367.922048 -128.457452)
		(end 367.922048 -135.812022)
		(width 0.14605)
		(layer "In2.Cu")
		(net "DRIVE_B_19_PWR")
	)
	(segment
		(start 225.02876 -198.627492)
		(end 225.02876 -178.616102)
		(width 0.17145)
		(layer "F.Cu")
		(net "DRIVE_B_19_INS")
	)
	(segment
		(start 217.230198 -209.259932)
		(end 217.230198 -203.571348)
		(width 0.17145)
		(layer "F.Cu")
		(net "DRIVE_B_19_INS")
	)
	(segment
		(start 219.919042 -200.882504)
		(end 222.773748 -200.882504)
		(width 0.17145)
		(layer "F.Cu")
		(net "DRIVE_B_19_INS")
	)
	(segment
		(start 225.02876 -178.616102)
		(end 240.443258 -163.201604)
		(width 0.17145)
		(layer "F.Cu")
		(net "DRIVE_B_19_INS")
	)
	(segment
		(start 217.591386 -209.62112)
		(end 217.230198 -209.259932)
		(width 0.17145)
		(layer "F.Cu")
		(net "DRIVE_B_19_INS")
	)
	(segment
		(start 317.402972 -126.57328)
		(end 321.949826 -122.026426)
		(width 0.17145)
		(layer "F.Cu")
		(net "DRIVE_B_19_INS")
	)
	(segment
		(start 218.7194 -209.62112)
		(end 217.591386 -209.62112)
		(width 0.17145)
		(layer "F.Cu")
		(net "DRIVE_B_19_INS")
	)
	(segment
		(start 337.190842 -118.72341)
		(end 341.382096 -122.914664)
		(width 0.17145)
		(layer "F.Cu")
		(net "DRIVE_B_19_INS")
	)
	(segment
		(start 317.402972 -149.302978)
		(end 317.402972 -126.57328)
		(width 0.17145)
		(layer "F.Cu")
		(net "DRIVE_B_19_INS")
	)
	(segment
		(start 321.949826 -122.026426)
		(end 321.949826 -120.162574)
		(width 0.17145)
		(layer "F.Cu")
		(net "DRIVE_B_19_INS")
	)
	(segment
		(start 217.230198 -203.571348)
		(end 219.919042 -200.882504)
		(width 0.17145)
		(layer "F.Cu")
		(net "DRIVE_B_19_INS")
	)
	(segment
		(start 349.7834 -131.315968)
		(end 341.382096 -122.914664)
		(width 0.17145)
		(layer "F.Cu")
		(net "DRIVE_B_19_INS")
	)
	(segment
		(start 241.295428 -163.201858)
		(end 303.504092 -163.201858)
		(width 0.17145)
		(layer "F.Cu")
		(net "DRIVE_B_19_INS")
	)
	(segment
		(start 303.504092 -163.201858)
		(end 317.402972 -149.302978)
		(width 0.17145)
		(layer "F.Cu")
		(net "DRIVE_B_19_INS")
	)
	(segment
		(start 222.773748 -200.882504)
		(end 225.02876 -198.627492)
		(width 0.17145)
		(layer "F.Cu")
		(net "DRIVE_B_19_INS")
	)
	(segment
		(start 323.38899 -118.72341)
		(end 337.190842 -118.72341)
		(width 0.17145)
		(layer "F.Cu")
		(net "DRIVE_B_19_INS")
	)
	(segment
		(start 349.7834 -145.5928)
		(end 349.7834 -131.315968)
		(width 0.17145)
		(layer "F.Cu")
		(net "DRIVE_B_19_INS")
	)
	(segment
		(start 241.295174 -163.201604)
		(end 241.295428 -163.201858)
		(width 0.17145)
		(layer "F.Cu")
		(net "DRIVE_B_19_INS")
	)
	(segment
		(start 240.443258 -163.201604)
		(end 241.295174 -163.201604)
		(width 0.17145)
		(layer "F.Cu")
		(net "DRIVE_B_19_INS")
	)
	(segment
		(start 321.949826 -120.162574)
		(end 323.38899 -118.72341)
		(width 0.17145)
		(layer "F.Cu")
		(net "DRIVE_B_19_INS")
	)
	(via
		(at 341.382096 -122.914664)
		(size 0.6604)
		(drill 0.3302)
		(layers "F.Cu" "B.Cu")
		(net "DRIVE_B_19_INS")
	)
	(segment
		(start 208.600548 -190.631572)
		(end 210.429856 -192.46088)
		(width 0.17145)
		(layer "F.Cu")
		(net "DRIVE_B_19_FLT_LED")
	)
	(segment
		(start 317.320168 -120.10898)
		(end 309.330344 -128.098804)
		(width 0.17145)
		(layer "F.Cu")
		(net "DRIVE_B_19_FLT_LED")
	)
	(segment
		(start 344.438478 -104.682544)
		(end 344.438478 -102.413562)
		(width 0.17145)
		(layer "F.Cu")
		(net "DRIVE_B_19_FLT_LED")
	)
	(segment
		(start 236.914182 -159.777684)
		(end 208.600294 -188.091572)
		(width 0.17145)
		(layer "F.Cu")
		(net "DRIVE_B_19_FLT_LED")
	)
	(segment
		(start 344.438478 -102.413562)
		(end 344.438478 -100.709476)
		(width 0.17145)
		(layer "F.Cu")
		(net "DRIVE_B_19_FLT_LED")
	)
	(segment
		(start 301.159418 -158.572708)
		(end 243.213382 -158.572708)
		(width 0.17145)
		(layer "F.Cu")
		(net "DRIVE_B_19_FLT_LED")
	)
	(segment
		(start 243.213382 -158.572708)
		(end 243.213128 -158.572454)
		(width 0.17145)
		(layer "F.Cu")
		(net "DRIVE_B_19_FLT_LED")
	)
	(segment
		(start 238.525304 -158.572454)
		(end 238.52505 -158.572708)
		(width 0.17145)
		(layer "F.Cu")
		(net "DRIVE_B_19_FLT_LED")
	)
	(segment
		(start 339.959442 -109.16158)
		(end 336.116422 -113.0046)
		(width 0.17145)
		(layer "F.Cu")
		(net "DRIVE_B_19_FLT_LED")
	)
	(segment
		(start 236.914182 -159.77743)
		(end 236.914182 -159.777684)
		(width 0.17145)
		(layer "F.Cu")
		(net "DRIVE_B_19_FLT_LED")
	)
	(segment
		(start 238.118904 -158.572708)
		(end 236.914182 -159.77743)
		(width 0.17145)
		(layer "F.Cu")
		(net "DRIVE_B_19_FLT_LED")
	)
	(segment
		(start 210.429856 -192.46088)
		(end 211.6328 -192.46088)
		(width 0.17145)
		(layer "F.Cu")
		(net "DRIVE_B_19_FLT_LED")
	)
	(segment
		(start 243.213128 -158.572454)
		(end 238.525304 -158.572454)
		(width 0.17145)
		(layer "F.Cu")
		(net "DRIVE_B_19_FLT_LED")
	)
	(segment
		(start 238.52505 -158.572708)
		(end 238.118904 -158.572708)
		(width 0.17145)
		(layer "F.Cu")
		(net "DRIVE_B_19_FLT_LED")
	)
	(segment
		(start 309.330344 -128.098804)
		(end 309.330344 -150.401782)
		(width 0.17145)
		(layer "F.Cu")
		(net "DRIVE_B_19_FLT_LED")
	)
	(segment
		(start 339.959442 -109.16158)
		(end 344.438478 -104.682544)
		(width 0.17145)
		(layer "F.Cu")
		(net "DRIVE_B_19_FLT_LED")
	)
	(segment
		(start 322.560696 -113.0046)
		(end 317.320168 -118.245128)
		(width 0.17145)
		(layer "F.Cu")
		(net "DRIVE_B_19_FLT_LED")
	)
	(segment
		(start 317.320168 -118.245128)
		(end 317.320168 -120.10898)
		(width 0.17145)
		(layer "F.Cu")
		(net "DRIVE_B_19_FLT_LED")
	)
	(segment
		(start 208.600548 -188.51753)
		(end 208.600548 -190.631572)
		(width 0.17145)
		(layer "F.Cu")
		(net "DRIVE_B_19_FLT_LED")
	)
	(segment
		(start 208.600294 -188.517276)
		(end 208.600548 -188.51753)
		(width 0.17145)
		(layer "F.Cu")
		(net "DRIVE_B_19_FLT_LED")
	)
	(segment
		(start 208.600294 -188.091572)
		(end 208.600294 -188.517276)
		(width 0.17145)
		(layer "F.Cu")
		(net "DRIVE_B_19_FLT_LED")
	)
	(segment
		(start 336.116422 -113.0046)
		(end 322.560696 -113.0046)
		(width 0.17145)
		(layer "F.Cu")
		(net "DRIVE_B_19_FLT_LED")
	)
	(segment
		(start 309.330344 -150.401782)
		(end 301.159418 -158.572708)
		(width 0.17145)
		(layer "F.Cu")
		(net "DRIVE_B_19_FLT_LED")
	)
	(via
		(at 339.959442 -109.16158)
		(size 0.6604)
		(drill 0.3302)
		(layers "F.Cu" "B.Cu")
		(net "DRIVE_B_19_FLT_LED")
	)
	(segment
		(start 340.696296 -97.390204)
		(end 340.696296 -98.876104)
		(width 0.17145)
		(layer "F.Cu")
		(net "DRIVE_B_19_ACT")
	)
	(segment
		(start 340.696296 -94.549976)
		(end 340.696296 -97.390204)
		(width 0.17145)
		(layer "F.Cu")
		(net "DRIVE_B_19_ACT")
	)
	(via
		(at 307.997098 -187.12053)
		(size 0.5588)
		(drill 0.3048)
		(layers "F.Cu" "B.Cu")
		(net "DRIVE_B_19_ACT")
	)
	(via
		(at 340.696296 -94.549976)
		(size 0.5588)
		(drill 0.3048)
		(layers "F.Cu" "B.Cu")
		(net "DRIVE_B_19_ACT")
	)
	(via
		(at 302.808132 -187.12053)
		(size 0.6096)
		(drill 0.3048)
		(layers "F.Cu" "B.Cu")
		(net "DRIVE_B_19_ACT")
	)
	(segment
		(start 302.808132 -187.12053)
		(end 307.997098 -187.12053)
		(width 0.17145)
		(layer "B.Cu")
		(net "DRIVE_B_19_ACT")
	)
	(segment
		(start 282.83662 -191.89446)
		(end 283.475176 -191.255904)
		(width 0.17145)
		(layer "B.Cu")
		(net "DRIVE_B_19_ACT")
	)
	(segment
		(start 298.078144 -187.12053)
		(end 302.808132 -187.12053)
		(width 0.17145)
		(layer "B.Cu")
		(net "DRIVE_B_19_ACT")
	)
	(segment
		(start 283.475176 -191.255904)
		(end 293.94277 -191.255904)
		(width 0.17145)
		(layer "B.Cu")
		(net "DRIVE_B_19_ACT")
	)
	(segment
		(start 293.94277 -191.255904)
		(end 298.078144 -187.12053)
		(width 0.17145)
		(layer "B.Cu")
		(net "DRIVE_B_19_ACT")
	)
	(segment
		(start 325.205598 -116.332)
		(end 333.66329 -116.332)
		(width 0.14605)
		(layer "In2.Cu")
		(net "DRIVE_B_19_ACT")
	)
	(segment
		(start 305.836066 -181.229762)
		(end 310.207152 -176.858676)
		(width 0.14605)
		(layer "In2.Cu")
		(net "DRIVE_B_19_ACT")
	)
	(segment
		(start 310.207152 -176.858676)
		(end 310.207152 -131.330446)
		(width 0.14605)
		(layer "In2.Cu")
		(net "DRIVE_B_19_ACT")
	)
	(segment
		(start 310.207152 -131.330446)
		(end 325.205598 -116.332)
		(width 0.14605)
		(layer "In2.Cu")
		(net "DRIVE_B_19_ACT")
	)
	(segment
		(start 333.66329 -116.332)
		(end 337.213448 -112.781842)
		(width 0.14605)
		(layer "In2.Cu")
		(net "DRIVE_B_19_ACT")
	)
	(segment
		(start 337.213448 -98.032824)
		(end 340.696296 -94.549976)
		(width 0.14605)
		(layer "In2.Cu")
		(net "DRIVE_B_19_ACT")
	)
	(segment
		(start 337.213448 -112.781842)
		(end 337.213448 -98.032824)
		(width 0.14605)
		(layer "In2.Cu")
		(net "DRIVE_B_19_ACT")
	)
	(segment
		(start 307.997098 -187.12053)
		(end 305.836066 -184.959498)
		(width 0.14605)
		(layer "In2.Cu")
		(net "DRIVE_B_19_ACT")
	)
	(segment
		(start 305.836066 -184.959498)
		(end 305.836066 -181.229762)
		(width 0.14605)
		(layer "In2.Cu")
		(net "DRIVE_B_19_ACT")
	)
	(segment
		(start 256.803398 -189.752224)
		(end 256.803398 -187.164472)
		(width 0.17145)
		(layer "F.Cu")
		(net "DRIVE_B_18_PWR")
	)
	(segment
		(start 256.803398 -174.664116)
		(end 263.035796 -168.431718)
		(width 0.17145)
		(layer "F.Cu")
		(net "DRIVE_B_18_PWR")
	)
	(segment
		(start 247.795542 -198.76008)
		(end 256.803398 -189.752224)
		(width 0.17145)
		(layer "F.Cu")
		(net "DRIVE_B_18_PWR")
	)
	(segment
		(start 263.035796 -168.431718)
		(end 287.643062 -168.431718)
		(width 0.17145)
		(layer "F.Cu")
		(net "DRIVE_B_18_PWR")
	)
	(segment
		(start 335.788 -128.2065)
		(end 336.677 -128.2065)
		(width 0.17145)
		(layer "F.Cu")
		(net "DRIVE_B_18_PWR")
	)
	(segment
		(start 240.6904 -198.76008)
		(end 247.795542 -198.76008)
		(width 0.17145)
		(layer "F.Cu")
		(net "DRIVE_B_18_PWR")
	)
	(segment
		(start 288.631884 -167.442896)
		(end 311.765696 -167.442896)
		(width 0.17145)
		(layer "F.Cu")
		(net "DRIVE_B_18_PWR")
	)
	(segment
		(start 256.803398 -187.164472)
		(end 256.803398 -174.664116)
		(width 0.17145)
		(layer "F.Cu")
		(net "DRIVE_B_18_PWR")
	)
	(segment
		(start 311.765696 -167.442896)
		(end 313.05246 -168.72966)
		(width 0.17145)
		(layer "F.Cu")
		(net "DRIVE_B_18_PWR")
	)
	(segment
		(start 287.643062 -168.431718)
		(end 288.631884 -167.442896)
		(width 0.17145)
		(layer "F.Cu")
		(net "DRIVE_B_18_PWR")
	)
	(via
		(at 336.677 -128.2065)
		(size 0.5588)
		(drill 0.3048)
		(layers "F.Cu" "B.Cu")
		(net "DRIVE_B_18_PWR")
	)
	(via
		(at 313.05246 -168.72966)
		(size 0.5588)
		(drill 0.3048)
		(layers "F.Cu" "B.Cu")
		(net "DRIVE_B_18_PWR")
	)
	(via
		(at 256.803398 -187.164472)
		(size 0.6604)
		(drill 0.3302)
		(layers "F.Cu" "B.Cu")
		(net "DRIVE_B_18_PWR")
	)
	(segment
		(start 336.15122 -138.92022)
		(end 336.15122 -128.73228)
		(width 0.14605)
		(layer "In2.Cu")
		(net "DRIVE_B_18_PWR")
	)
	(segment
		(start 313.05246 -168.72966)
		(end 313.05246 -162.01898)
		(width 0.14605)
		(layer "In2.Cu")
		(net "DRIVE_B_18_PWR")
	)
	(segment
		(start 336.15122 -128.73228)
		(end 336.677 -128.2065)
		(width 0.14605)
		(layer "In2.Cu")
		(net "DRIVE_B_18_PWR")
	)
	(segment
		(start 313.05246 -162.01898)
		(end 336.15122 -138.92022)
		(width 0.14605)
		(layer "In2.Cu")
		(net "DRIVE_B_18_PWR")
	)
	(segment
		(start 222.986854 -201.396854)
		(end 225.57105 -198.812658)
		(width 0.17145)
		(layer "F.Cu")
		(net "DRIVE_B_18_INS")
	)
	(segment
		(start 225.57105 -198.812658)
		(end 225.57105 -178.801268)
		(width 0.17145)
		(layer "F.Cu")
		(net "DRIVE_B_18_INS")
	)
	(segment
		(start 240.656364 -163.715954)
		(end 241.082068 -163.715954)
		(width 0.17145)
		(layer "F.Cu")
		(net "DRIVE_B_18_INS")
	)
	(segment
		(start 318.2112 -148.6154)
		(end 318.2112 -149.481286)
		(width 0.17145)
		(layer "F.Cu")
		(net "DRIVE_B_18_INS")
	)
	(segment
		(start 218.7194 -208.97088)
		(end 217.86088 -208.97088)
		(width 0.17145)
		(layer "F.Cu")
		(net "DRIVE_B_18_INS")
	)
	(segment
		(start 220.132148 -201.396854)
		(end 222.986854 -201.396854)
		(width 0.17145)
		(layer "F.Cu")
		(net "DRIVE_B_18_INS")
	)
	(segment
		(start 241.082068 -163.715954)
		(end 241.082322 -163.716208)
		(width 0.17145)
		(layer "F.Cu")
		(net "DRIVE_B_18_INS")
	)
	(segment
		(start 303.976278 -163.716208)
		(end 308.87416 -158.818326)
		(width 0.17145)
		(layer "F.Cu")
		(net "DRIVE_B_18_INS")
	)
	(segment
		(start 318.2112 -149.481286)
		(end 308.87416 -158.818326)
		(width 0.17145)
		(layer "F.Cu")
		(net "DRIVE_B_18_INS")
	)
	(segment
		(start 217.86088 -208.97088)
		(end 217.744548 -208.854548)
		(width 0.17145)
		(layer "F.Cu")
		(net "DRIVE_B_18_INS")
	)
	(segment
		(start 241.082322 -163.716208)
		(end 303.976278 -163.716208)
		(width 0.17145)
		(layer "F.Cu")
		(net "DRIVE_B_18_INS")
	)
	(segment
		(start 225.57105 -178.801268)
		(end 240.656364 -163.715954)
		(width 0.17145)
		(layer "F.Cu")
		(net "DRIVE_B_18_INS")
	)
	(segment
		(start 217.744548 -208.854548)
		(end 217.744548 -203.784454)
		(width 0.17145)
		(layer "F.Cu")
		(net "DRIVE_B_18_INS")
	)
	(segment
		(start 217.744548 -203.784454)
		(end 220.132148 -201.396854)
		(width 0.17145)
		(layer "F.Cu")
		(net "DRIVE_B_18_INS")
	)
	(via
		(at 308.87416 -158.818326)
		(size 0.6604)
		(drill 0.3302)
		(layers "F.Cu" "B.Cu")
		(net "DRIVE_B_18_INS")
	)
	(segment
		(start 307.01234 -123.460764)
		(end 307.01234 -149.803104)
		(width 0.17145)
		(layer "F.Cu")
		(net "DRIVE_B_18_FLT_LED")
	)
	(segment
		(start 211.6328 -193.11112)
		(end 209.211418 -193.11112)
		(width 0.17145)
		(layer "F.Cu")
		(net "DRIVE_B_18_FLT_LED")
	)
	(segment
		(start 223.86163 -169.6339)
		(end 223.276668 -169.6339)
		(width 0.17145)
		(layer "F.Cu")
		(net "DRIVE_B_18_FLT_LED")
	)
	(segment
		(start 207.612742 -185.297826)
		(end 207.612742 -189.001146)
		(width 0.17145)
		(layer "F.Cu")
		(net "DRIVE_B_18_FLT_LED")
	)
	(segment
		(start 324.530212 -102.373684)
		(end 324.530212 -100.669598)
		(width 0.17145)
		(layer "F.Cu")
		(net "DRIVE_B_18_FLT_LED")
	)
	(segment
		(start 223.276668 -169.6339)
		(end 207.612742 -185.297826)
		(width 0.17145)
		(layer "F.Cu")
		(net "DRIVE_B_18_FLT_LED")
	)
	(segment
		(start 324.530212 -105.942892)
		(end 307.01234 -123.460764)
		(width 0.17145)
		(layer "F.Cu")
		(net "DRIVE_B_18_FLT_LED")
	)
	(segment
		(start 207.612742 -191.512444)
		(end 207.612742 -189.001146)
		(width 0.17145)
		(layer "F.Cu")
		(net "DRIVE_B_18_FLT_LED")
	)
	(segment
		(start 237.11916 -156.37637)
		(end 223.86163 -169.6339)
		(width 0.17145)
		(layer "F.Cu")
		(net "DRIVE_B_18_FLT_LED")
	)
	(segment
		(start 209.211418 -193.11112)
		(end 207.612742 -191.512444)
		(width 0.17145)
		(layer "F.Cu")
		(net "DRIVE_B_18_FLT_LED")
	)
	(segment
		(start 324.530212 -102.373684)
		(end 324.530212 -105.942892)
		(width 0.17145)
		(layer "F.Cu")
		(net "DRIVE_B_18_FLT_LED")
	)
	(segment
		(start 307.01234 -149.803104)
		(end 300.439074 -156.37637)
		(width 0.17145)
		(layer "F.Cu")
		(net "DRIVE_B_18_FLT_LED")
	)
	(segment
		(start 300.439074 -156.37637)
		(end 237.11916 -156.37637)
		(width 0.17145)
		(layer "F.Cu")
		(net "DRIVE_B_18_FLT_LED")
	)
	(via
		(at 207.612742 -189.001146)
		(size 0.6604)
		(drill 0.3302)
		(layers "F.Cu" "B.Cu")
		(net "DRIVE_B_18_FLT_LED")
	)
	(segment
		(start 320.78803 -95.9104)
		(end 320.78803 -97.350326)
		(width 0.17145)
		(layer "F.Cu")
		(net "DRIVE_B_18_ACT")
	)
	(segment
		(start 320.78803 -97.350326)
		(end 320.78803 -98.836226)
		(width 0.17145)
		(layer "F.Cu")
		(net "DRIVE_B_18_ACT")
	)
	(via
		(at 320.78803 -95.9104)
		(size 0.5588)
		(drill 0.3048)
		(layers "F.Cu" "B.Cu")
		(net "DRIVE_B_18_ACT")
	)
	(via
		(at 307.997098 -188.18733)
		(size 0.5588)
		(drill 0.3048)
		(layers "F.Cu" "B.Cu")
		(net "DRIVE_B_18_ACT")
	)
	(via
		(at 304.338736 -188.18733)
		(size 0.6096)
		(drill 0.3048)
		(layers "F.Cu" "B.Cu")
		(net "DRIVE_B_18_ACT")
	)
	(segment
		(start 285.026608 -192.6844)
		(end 294.136572 -192.6844)
		(width 0.17145)
		(layer "B.Cu")
		(net "DRIVE_B_18_ACT")
	)
	(segment
		(start 298.633642 -188.18733)
		(end 304.338736 -188.18733)
		(width 0.17145)
		(layer "B.Cu")
		(net "DRIVE_B_18_ACT")
	)
	(segment
		(start 294.136572 -192.6844)
		(end 298.633642 -188.18733)
		(width 0.17145)
		(layer "B.Cu")
		(net "DRIVE_B_18_ACT")
	)
	(segment
		(start 307.997098 -188.18733)
		(end 304.338736 -188.18733)
		(width 0.17145)
		(layer "B.Cu")
		(net "DRIVE_B_18_ACT")
	)
	(segment
		(start 284.236668 -191.89446)
		(end 285.026608 -192.6844)
		(width 0.17145)
		(layer "B.Cu")
		(net "DRIVE_B_18_ACT")
	)
	(segment
		(start 304.190146 -113.45291)
		(end 304.190146 -184.380378)
		(width 0.14605)
		(layer "In2.Cu")
		(net "DRIVE_B_18_ACT")
	)
	(segment
		(start 320.78803 -97.096834)
		(end 315.959236 -101.925628)
		(width 0.14605)
		(layer "In2.Cu")
		(net "DRIVE_B_18_ACT")
	)
	(segment
		(start 320.78803 -95.9104)
		(end 320.78803 -97.096834)
		(width 0.14605)
		(layer "In2.Cu")
		(net "DRIVE_B_18_ACT")
	)
	(segment
		(start 315.959236 -101.925628)
		(end 315.717428 -101.925628)
		(width 0.14605)
		(layer "In2.Cu")
		(net "DRIVE_B_18_ACT")
	)
	(segment
		(start 304.190146 -184.380378)
		(end 307.997098 -188.18733)
		(width 0.14605)
		(layer "In2.Cu")
		(net "DRIVE_B_18_ACT")
	)
	(segment
		(start 315.717428 -101.925628)
		(end 304.190146 -113.45291)
		(width 0.14605)
		(layer "In2.Cu")
		(net "DRIVE_B_18_ACT")
	)
	(segment
		(start 239.588548 -198.10984)
		(end 240.6904 -198.10984)
		(width 0.17145)
		(layer "F.Cu")
		(net "DRIVE_B_17_PWR")
	)
	(segment
		(start 237.4392 -202.0062)
		(end 237.67542 -202.0062)
		(width 0.17145)
		(layer "F.Cu")
		(net "DRIVE_B_17_PWR")
	)
	(segment
		(start 239.101884 -200.579736)
		(end 239.101884 -198.596504)
		(width 0.17145)
		(layer "F.Cu")
		(net "DRIVE_B_17_PWR")
	)
	(segment
		(start 178.9811 -130.4163)
		(end 178.6128 -130.048)
		(width 0.17145)
		(layer "F.Cu")
		(net "DRIVE_B_17_PWR")
	)
	(segment
		(start 239.101884 -198.596504)
		(end 239.588548 -198.10984)
		(width 0.17145)
		(layer "F.Cu")
		(net "DRIVE_B_17_PWR")
	)
	(segment
		(start 179.7812 -130.4163)
		(end 178.9811 -130.4163)
		(width 0.17145)
		(layer "F.Cu")
		(net "DRIVE_B_17_PWR")
	)
	(segment
		(start 178.3842 -129.8194)
		(end 178.6128 -130.048)
		(width 0.17145)
		(layer "F.Cu")
		(net "DRIVE_B_17_PWR")
	)
	(segment
		(start 237.67542 -202.0062)
		(end 239.101884 -200.579736)
		(width 0.17145)
		(layer "F.Cu")
		(net "DRIVE_B_17_PWR")
	)
	(segment
		(start 177.4444 -129.8194)
		(end 178.3842 -129.8194)
		(width 0.17145)
		(layer "F.Cu")
		(net "DRIVE_B_17_PWR")
	)
	(via
		(at 178.6128 -130.048)
		(size 0.6604)
		(drill 0.3302)
		(layers "F.Cu" "B.Cu")
		(net "DRIVE_B_17_PWR")
	)
	(via
		(at 177.4444 -129.8194)
		(size 0.5588)
		(drill 0.3048)
		(layers "F.Cu" "B.Cu")
		(net "DRIVE_B_17_PWR")
	)
	(via
		(at 180.307234 -174.306484)
		(size 0.5588)
		(drill 0.3048)
		(layers "F.Cu" "B.Cu")
		(net "DRIVE_B_17_PWR")
	)
	(via
		(at 237.4392 -202.0062)
		(size 0.5588)
		(drill 0.3048)
		(layers "F.Cu" "B.Cu")
		(net "DRIVE_B_17_PWR")
	)
	(segment
		(start 169.802048 -159.667448)
		(end 169.802048 -131.187952)
		(width 0.14605)
		(layer "In2.Cu")
		(net "DRIVE_B_17_PWR")
	)
	(segment
		(start 180.213 -174.21225)
		(end 180.213 -170.0784)
		(width 0.14605)
		(layer "In2.Cu")
		(net "DRIVE_B_17_PWR")
	)
	(segment
		(start 180.307234 -174.306484)
		(end 180.213 -174.21225)
		(width 0.14605)
		(layer "In2.Cu")
		(net "DRIVE_B_17_PWR")
	)
	(segment
		(start 171.1706 -129.8194)
		(end 177.4444 -129.8194)
		(width 0.14605)
		(layer "In2.Cu")
		(net "DRIVE_B_17_PWR")
	)
	(segment
		(start 169.802048 -131.187952)
		(end 171.1706 -129.8194)
		(width 0.14605)
		(layer "In2.Cu")
		(net "DRIVE_B_17_PWR")
	)
	(segment
		(start 180.213 -170.0784)
		(end 169.802048 -159.667448)
		(width 0.14605)
		(layer "In2.Cu")
		(net "DRIVE_B_17_PWR")
	)
	(segment
		(start 197.904862 -185.6613)
		(end 191.66205 -185.6613)
		(width 0.14605)
		(layer "In5.Cu")
		(net "DRIVE_B_17_PWR")
	)
	(segment
		(start 222.172276 -190.320676)
		(end 202.563984 -190.320676)
		(width 0.14605)
		(layer "In5.Cu")
		(net "DRIVE_B_17_PWR")
	)
	(segment
		(start 202.563984 -190.320676)
		(end 200.679812 -188.436504)
		(width 0.14605)
		(layer "In5.Cu")
		(net "DRIVE_B_17_PWR")
	)
	(segment
		(start 200.679812 -188.436504)
		(end 200.679812 -188.43625)
		(width 0.14605)
		(layer "In5.Cu")
		(net "DRIVE_B_17_PWR")
	)
	(segment
		(start 235.005372 -202.0062)
		(end 231.576372 -198.5772)
		(width 0.14605)
		(layer "In5.Cu")
		(net "DRIVE_B_17_PWR")
	)
	(segment
		(start 237.4392 -202.0062)
		(end 235.005372 -202.0062)
		(width 0.14605)
		(layer "In5.Cu")
		(net "DRIVE_B_17_PWR")
	)
	(segment
		(start 200.679812 -188.43625)
		(end 197.904862 -185.6613)
		(width 0.14605)
		(layer "In5.Cu")
		(net "DRIVE_B_17_PWR")
	)
	(segment
		(start 228.981 -198.5772)
		(end 227.6094 -197.2056)
		(width 0.14605)
		(layer "In5.Cu")
		(net "DRIVE_B_17_PWR")
	)
	(segment
		(start 227.6094 -197.2056)
		(end 227.6094 -195.7578)
		(width 0.14605)
		(layer "In5.Cu")
		(net "DRIVE_B_17_PWR")
	)
	(segment
		(start 191.66205 -185.6613)
		(end 180.307234 -174.306484)
		(width 0.14605)
		(layer "In5.Cu")
		(net "DRIVE_B_17_PWR")
	)
	(segment
		(start 231.576372 -198.5772)
		(end 228.981 -198.5772)
		(width 0.14605)
		(layer "In5.Cu")
		(net "DRIVE_B_17_PWR")
	)
	(segment
		(start 227.6094 -195.7578)
		(end 222.172276 -190.320676)
		(width 0.14605)
		(layer "In5.Cu")
		(net "DRIVE_B_17_PWR")
	)
	(segment
		(start 191.135 -150.876)
		(end 191.135 -151.722582)
		(width 0.17145)
		(layer "F.Cu")
		(net "DRIVE_B_17_INS")
	)
	(segment
		(start 190.383414 -158.727902)
		(end 190.383414 -182.120794)
		(width 0.17145)
		(layer "F.Cu")
		(net "DRIVE_B_17_INS")
	)
	(segment
		(start 190.383414 -182.120794)
		(end 190.383414 -191.790828)
		(width 0.17145)
		(layer "F.Cu")
		(net "DRIVE_B_17_INS")
	)
	(segment
		(start 190.383414 -191.790828)
		(end 197.083172 -198.490586)
		(width 0.17145)
		(layer "F.Cu")
		(net "DRIVE_B_17_INS")
	)
	(segment
		(start 193.209418 -155.901898)
		(end 190.383414 -158.727902)
		(width 0.17145)
		(layer "F.Cu")
		(net "DRIVE_B_17_INS")
	)
	(segment
		(start 191.135 -151.722582)
		(end 193.209418 -153.797)
		(width 0.17145)
		(layer "F.Cu")
		(net "DRIVE_B_17_INS")
	)
	(segment
		(start 218.7194 -208.32064)
		(end 220.293946 -208.32064)
		(width 0.17145)
		(layer "F.Cu")
		(net "DRIVE_B_17_INS")
	)
	(segment
		(start 197.083172 -198.490586)
		(end 197.083172 -212.616034)
		(width 0.17145)
		(layer "F.Cu")
		(net "DRIVE_B_17_INS")
	)
	(segment
		(start 220.293946 -208.32064)
		(end 220.980254 -209.006948)
		(width 0.17145)
		(layer "F.Cu")
		(net "DRIVE_B_17_INS")
	)
	(segment
		(start 197.083172 -212.616034)
		(end 197.79869 -213.331552)
		(width 0.17145)
		(layer "F.Cu")
		(net "DRIVE_B_17_INS")
	)
	(segment
		(start 193.209418 -153.797)
		(end 193.209418 -155.901898)
		(width 0.17145)
		(layer "F.Cu")
		(net "DRIVE_B_17_INS")
	)
	(via
		(at 197.79869 -213.331552)
		(size 0.5588)
		(drill 0.3048)
		(layers "F.Cu" "B.Cu")
		(net "DRIVE_B_17_INS")
	)
	(via
		(at 220.980254 -209.006948)
		(size 0.5588)
		(drill 0.3048)
		(layers "F.Cu" "B.Cu")
		(net "DRIVE_B_17_INS")
	)
	(via
		(at 190.383414 -182.120794)
		(size 0.6604)
		(drill 0.3302)
		(layers "F.Cu" "B.Cu")
		(net "DRIVE_B_17_INS")
	)
	(segment
		(start 209.36585 -208.661)
		(end 208.85277 -209.17408)
		(width 0.14605)
		(layer "In5.Cu")
		(net "DRIVE_B_17_INS")
	)
	(segment
		(start 207.055974 -209.17408)
		(end 202.898502 -213.331552)
		(width 0.14605)
		(layer "In5.Cu")
		(net "DRIVE_B_17_INS")
	)
	(segment
		(start 220.980254 -209.006948)
		(end 220.634306 -208.661)
		(width 0.14605)
		(layer "In5.Cu")
		(net "DRIVE_B_17_INS")
	)
	(segment
		(start 220.634306 -208.661)
		(end 209.36585 -208.661)
		(width 0.14605)
		(layer "In5.Cu")
		(net "DRIVE_B_17_INS")
	)
	(segment
		(start 208.85277 -209.17408)
		(end 207.055974 -209.17408)
		(width 0.14605)
		(layer "In5.Cu")
		(net "DRIVE_B_17_INS")
	)
	(segment
		(start 202.898502 -213.331552)
		(end 197.79869 -213.331552)
		(width 0.14605)
		(layer "In5.Cu")
		(net "DRIVE_B_17_INS")
	)
	(segment
		(start 211.759292 -132.913882)
		(end 187.009024 -108.163614)
		(width 0.17145)
		(layer "F.Cu")
		(net "DRIVE_B_17_FLT_LED")
	)
	(segment
		(start 211.759292 -149.801326)
		(end 211.759292 -132.913882)
		(width 0.17145)
		(layer "F.Cu")
		(net "DRIVE_B_17_FLT_LED")
	)
	(segment
		(start 207.366108 -192.915286)
		(end 200.382886 -192.915286)
		(width 0.17145)
		(layer "F.Cu")
		(net "DRIVE_B_17_FLT_LED")
	)
	(segment
		(start 174.634144 -108.163614)
		(end 170.27906 -103.80853)
		(width 0.17145)
		(layer "F.Cu")
		(net "DRIVE_B_17_FLT_LED")
	)
	(segment
		(start 211.6328 -193.76136)
		(end 210.558126 -193.76136)
		(width 0.17145)
		(layer "F.Cu")
		(net "DRIVE_B_17_FLT_LED")
	)
	(segment
		(start 169.91965 -102.351586)
		(end 169.91965 -100.6729)
		(width 0.17145)
		(layer "F.Cu")
		(net "DRIVE_B_17_FLT_LED")
	)
	(segment
		(start 187.009024 -108.163614)
		(end 174.634144 -108.163614)
		(width 0.17145)
		(layer "F.Cu")
		(net "DRIVE_B_17_FLT_LED")
	)
	(segment
		(start 210.558126 -193.76136)
		(end 210.506564 -193.709798)
		(width 0.17145)
		(layer "F.Cu")
		(net "DRIVE_B_17_FLT_LED")
	)
	(segment
		(start 169.91965 -103.44912)
		(end 169.91965 -102.351586)
		(width 0.17145)
		(layer "F.Cu")
		(net "DRIVE_B_17_FLT_LED")
	)
	(segment
		(start 170.27906 -103.80853)
		(end 169.91965 -103.44912)
		(width 0.17145)
		(layer "F.Cu")
		(net "DRIVE_B_17_FLT_LED")
	)
	(segment
		(start 196.9008 -164.659818)
		(end 211.759292 -149.801326)
		(width 0.17145)
		(layer "F.Cu")
		(net "DRIVE_B_17_FLT_LED")
	)
	(segment
		(start 196.9008 -189.4332)
		(end 196.9008 -164.659818)
		(width 0.17145)
		(layer "F.Cu")
		(net "DRIVE_B_17_FLT_LED")
	)
	(segment
		(start 208.16062 -193.709798)
		(end 207.366108 -192.915286)
		(width 0.17145)
		(layer "F.Cu")
		(net "DRIVE_B_17_FLT_LED")
	)
	(segment
		(start 200.382886 -192.915286)
		(end 196.9008 -189.4332)
		(width 0.17145)
		(layer "F.Cu")
		(net "DRIVE_B_17_FLT_LED")
	)
	(segment
		(start 210.506564 -193.709798)
		(end 208.16062 -193.709798)
		(width 0.17145)
		(layer "F.Cu")
		(net "DRIVE_B_17_FLT_LED")
	)
	(via
		(at 170.27906 -103.80853)
		(size 0.6604)
		(drill 0.3302)
		(layers "F.Cu" "B.Cu")
		(net "DRIVE_B_17_FLT_LED")
	)
	(segment
		(start 166.177468 -95.5929)
		(end 166.177468 -94.488)
		(width 0.17145)
		(layer "F.Cu")
		(net "DRIVE_B_17_ACT")
	)
	(segment
		(start 166.177468 -97.328228)
		(end 166.177468 -98.814128)
		(width 0.17145)
		(layer "F.Cu")
		(net "DRIVE_B_17_ACT")
	)
	(segment
		(start 272.079466 -191.002666)
		(end 272.079466 -173.30801)
		(width 0.17145)
		(layer "F.Cu")
		(net "DRIVE_B_17_ACT")
	)
	(segment
		(start 281.836622 -193.694558)
		(end 281.029664 -192.8876)
		(width 0.17145)
		(layer "F.Cu")
		(net "DRIVE_B_17_ACT")
	)
	(segment
		(start 166.177468 -95.5929)
		(end 166.177468 -97.328228)
		(width 0.17145)
		(layer "F.Cu")
		(net "DRIVE_B_17_ACT")
	)
	(segment
		(start 273.9644 -192.8876)
		(end 272.079466 -191.002666)
		(width 0.17145)
		(layer "F.Cu")
		(net "DRIVE_B_17_ACT")
	)
	(segment
		(start 281.029664 -192.8876)
		(end 273.9644 -192.8876)
		(width 0.17145)
		(layer "F.Cu")
		(net "DRIVE_B_17_ACT")
	)
	(via
		(at 272.079466 -173.30801)
		(size 0.5588)
		(drill 0.3048)
		(layers "F.Cu" "B.Cu")
		(net "DRIVE_B_17_ACT")
	)
	(via
		(at 166.177468 -95.5929)
		(size 0.6604)
		(drill 0.3302)
		(layers "F.Cu" "B.Cu")
		(net "DRIVE_B_17_ACT")
	)
	(via
		(at 166.177468 -94.488)
		(size 0.5588)
		(drill 0.3048)
		(layers "F.Cu" "B.Cu")
		(net "DRIVE_B_17_ACT")
	)
	(via
		(at 201.160634 -116.261134)
		(size 0.5588)
		(drill 0.3048)
		(layers "F.Cu" "B.Cu")
		(net "DRIVE_B_17_ACT")
	)
	(segment
		(start 234.487466 -138.368786)
		(end 241.796062 -138.368786)
		(width 0.17145)
		(layer "B.Cu")
		(net "DRIVE_B_17_ACT")
	)
	(segment
		(start 206.409544 -116.261134)
		(end 223.061784 -132.913374)
		(width 0.17145)
		(layer "B.Cu")
		(net "DRIVE_B_17_ACT")
	)
	(segment
		(start 241.796062 -138.368786)
		(end 244.13464 -140.707364)
		(width 0.17145)
		(layer "B.Cu")
		(net "DRIVE_B_17_ACT")
	)
	(segment
		(start 201.160634 -116.261134)
		(end 206.409544 -116.261134)
		(width 0.17145)
		(layer "B.Cu")
		(net "DRIVE_B_17_ACT")
	)
	(segment
		(start 272.079466 -165.784022)
		(end 272.079466 -173.30801)
		(width 0.17145)
		(layer "B.Cu")
		(net "DRIVE_B_17_ACT")
	)
	(segment
		(start 247.002808 -140.707364)
		(end 272.079466 -165.784022)
		(width 0.17145)
		(layer "B.Cu")
		(net "DRIVE_B_17_ACT")
	)
	(segment
		(start 244.13464 -140.707364)
		(end 247.002808 -140.707364)
		(width 0.17145)
		(layer "B.Cu")
		(net "DRIVE_B_17_ACT")
	)
	(segment
		(start 229.032054 -132.913374)
		(end 234.487466 -138.368786)
		(width 0.17145)
		(layer "B.Cu")
		(net "DRIVE_B_17_ACT")
	)
	(segment
		(start 223.061784 -132.913374)
		(end 229.032054 -132.913374)
		(width 0.17145)
		(layer "B.Cu")
		(net "DRIVE_B_17_ACT")
	)
	(segment
		(start 195.4022 -110.5027)
		(end 201.160634 -116.261134)
		(width 0.14605)
		(layer "In2.Cu")
		(net "DRIVE_B_17_ACT")
	)
	(segment
		(start 175.52035 -102.53345)
		(end 183.4896 -110.5027)
		(width 0.14605)
		(layer "In2.Cu")
		(net "DRIVE_B_17_ACT")
	)
	(segment
		(start 183.4896 -110.5027)
		(end 195.4022 -110.5027)
		(width 0.14605)
		(layer "In2.Cu")
		(net "DRIVE_B_17_ACT")
	)
	(segment
		(start 166.177468 -96.783398)
		(end 171.92752 -102.53345)
		(width 0.14605)
		(layer "In2.Cu")
		(net "DRIVE_B_17_ACT")
	)
	(segment
		(start 166.177468 -94.488)
		(end 166.177468 -96.783398)
		(width 0.14605)
		(layer "In2.Cu")
		(net "DRIVE_B_17_ACT")
	)
	(segment
		(start 171.92752 -102.53345)
		(end 175.52035 -102.53345)
		(width 0.14605)
		(layer "In2.Cu")
		(net "DRIVE_B_17_ACT")
	)
	(segment
		(start 236.6772 -201.041)
		(end 236.6772 -200.809606)
		(width 0.17145)
		(layer "F.Cu")
		(net "DRIVE_B_16_PWR")
	)
	(segment
		(start 239.014 -197.4596)
		(end 240.6904 -197.4596)
		(width 0.17145)
		(layer "F.Cu")
		(net "DRIVE_B_16_PWR")
	)
	(segment
		(start 238.264954 -199.221852)
		(end 238.264954 -198.208646)
		(width 0.17145)
		(layer "F.Cu")
		(net "DRIVE_B_16_PWR")
	)
	(segment
		(start 238.264954 -198.208646)
		(end 239.014 -197.4596)
		(width 0.17145)
		(layer "F.Cu")
		(net "DRIVE_B_16_PWR")
	)
	(segment
		(start 236.6772 -200.809606)
		(end 238.264954 -199.221852)
		(width 0.17145)
		(layer "F.Cu")
		(net "DRIVE_B_16_PWR")
	)
	(segment
		(start 148.2217 -130.2512)
		(end 148.2217 -129.2352)
		(width 0.17145)
		(layer "F.Cu")
		(net "DRIVE_B_16_PWR")
	)
	(segment
		(start 148.2217 -128.1684)
		(end 148.2217 -129.2352)
		(width 0.17145)
		(layer "F.Cu")
		(net "DRIVE_B_16_PWR")
	)
	(via
		(at 236.6772 -201.041)
		(size 0.5588)
		(drill 0.3048)
		(layers "F.Cu" "B.Cu")
		(net "DRIVE_B_16_PWR")
	)
	(via
		(at 148.2217 -129.2352)
		(size 0.6604)
		(drill 0.3302)
		(layers "F.Cu" "B.Cu")
		(net "DRIVE_B_16_PWR")
	)
	(via
		(at 169.3926 -169.0116)
		(size 0.5588)
		(drill 0.3048)
		(layers "F.Cu" "B.Cu")
		(net "DRIVE_B_16_PWR")
	)
	(via
		(at 148.2217 -128.1684)
		(size 0.5588)
		(drill 0.3048)
		(layers "F.Cu" "B.Cu")
		(net "DRIVE_B_16_PWR")
	)
	(segment
		(start 169.3926 -164.592)
		(end 169.3926 -169.0116)
		(width 0.14605)
		(layer "In2.Cu")
		(net "DRIVE_B_16_PWR")
	)
	(segment
		(start 149.9616 -128.1684)
		(end 152.781 -130.9878)
		(width 0.14605)
		(layer "In2.Cu")
		(net "DRIVE_B_16_PWR")
	)
	(segment
		(start 166.9542 -149.0472)
		(end 166.9542 -162.1536)
		(width 0.14605)
		(layer "In2.Cu")
		(net "DRIVE_B_16_PWR")
	)
	(segment
		(start 148.2217 -128.1684)
		(end 149.9616 -128.1684)
		(width 0.14605)
		(layer "In2.Cu")
		(net "DRIVE_B_16_PWR")
	)
	(segment
		(start 166.9542 -162.1536)
		(end 169.3926 -164.592)
		(width 0.14605)
		(layer "In2.Cu")
		(net "DRIVE_B_16_PWR")
	)
	(segment
		(start 152.781 -134.874)
		(end 166.9542 -149.0472)
		(width 0.14605)
		(layer "In2.Cu")
		(net "DRIVE_B_16_PWR")
	)
	(segment
		(start 152.781 -130.9878)
		(end 152.781 -134.874)
		(width 0.14605)
		(layer "In2.Cu")
		(net "DRIVE_B_16_PWR")
	)
	(segment
		(start 222.353886 -189.882526)
		(end 202.745848 -189.882526)
		(width 0.14605)
		(layer "In5.Cu")
		(net "DRIVE_B_16_PWR")
	)
	(segment
		(start 236.6772 -201.041)
		(end 234.659932 -201.041)
		(width 0.14605)
		(layer "In5.Cu")
		(net "DRIVE_B_16_PWR")
	)
	(segment
		(start 202.745848 -189.882526)
		(end 198.086472 -185.22315)
		(width 0.14605)
		(layer "In5.Cu")
		(net "DRIVE_B_16_PWR")
	)
	(segment
		(start 179.832 -171.6024)
		(end 171.9834 -171.6024)
		(width 0.14605)
		(layer "In5.Cu")
		(net "DRIVE_B_16_PWR")
	)
	(segment
		(start 234.659932 -201.041)
		(end 231.732582 -198.11365)
		(width 0.14605)
		(layer "In5.Cu")
		(net "DRIVE_B_16_PWR")
	)
	(segment
		(start 229.25405 -198.11365)
		(end 228.04755 -196.90715)
		(width 0.14605)
		(layer "In5.Cu")
		(net "DRIVE_B_16_PWR")
	)
	(segment
		(start 198.086472 -185.22315)
		(end 193.45275 -185.22315)
		(width 0.14605)
		(layer "In5.Cu")
		(net "DRIVE_B_16_PWR")
	)
	(segment
		(start 228.04755 -195.57619)
		(end 222.353886 -189.882526)
		(width 0.14605)
		(layer "In5.Cu")
		(net "DRIVE_B_16_PWR")
	)
	(segment
		(start 193.45275 -185.22315)
		(end 179.832 -171.6024)
		(width 0.14605)
		(layer "In5.Cu")
		(net "DRIVE_B_16_PWR")
	)
	(segment
		(start 231.732582 -198.11365)
		(end 229.25405 -198.11365)
		(width 0.14605)
		(layer "In5.Cu")
		(net "DRIVE_B_16_PWR")
	)
	(segment
		(start 228.04755 -196.90715)
		(end 228.04755 -195.57619)
		(width 0.14605)
		(layer "In5.Cu")
		(net "DRIVE_B_16_PWR")
	)
	(segment
		(start 171.9834 -171.6024)
		(end 169.3926 -169.0116)
		(width 0.14605)
		(layer "In5.Cu")
		(net "DRIVE_B_16_PWR")
	)
	(segment
		(start 218.7194 -207.6704)
		(end 220.660468 -207.6704)
		(width 0.17145)
		(layer "F.Cu")
		(net "DRIVE_B_16_INS")
	)
	(segment
		(start 162.687 -152.654)
		(end 164.25672 -154.22372)
		(width 0.17145)
		(layer "F.Cu")
		(net "DRIVE_B_16_INS")
	)
	(segment
		(start 164.25672 -164.373052)
		(end 164.25672 -172.57522)
		(width 0.17145)
		(layer "F.Cu")
		(net "DRIVE_B_16_INS")
	)
	(segment
		(start 220.660468 -207.6704)
		(end 220.977206 -207.987138)
		(width 0.17145)
		(layer "F.Cu")
		(net "DRIVE_B_16_INS")
	)
	(segment
		(start 164.25672 -154.22372)
		(end 164.25672 -164.373052)
		(width 0.17145)
		(layer "F.Cu")
		(net "DRIVE_B_16_INS")
	)
	(segment
		(start 162.687 -151.003)
		(end 162.687 -152.654)
		(width 0.17145)
		(layer "F.Cu")
		(net "DRIVE_B_16_INS")
	)
	(via
		(at 164.25672 -172.57522)
		(size 0.5588)
		(drill 0.3048)
		(layers "F.Cu" "B.Cu")
		(net "DRIVE_B_16_INS")
	)
	(via
		(at 220.977206 -207.987138)
		(size 0.5588)
		(drill 0.3048)
		(layers "F.Cu" "B.Cu")
		(net "DRIVE_B_16_INS")
	)
	(via
		(at 164.25672 -164.373052)
		(size 0.6604)
		(drill 0.3302)
		(layers "F.Cu" "B.Cu")
		(net "DRIVE_B_16_INS")
	)
	(segment
		(start 220.977206 -207.987138)
		(end 220.793564 -208.17078)
		(width 0.14605)
		(layer "In5.Cu")
		(net "DRIVE_B_16_INS")
	)
	(segment
		(start 220.793564 -208.17078)
		(end 209.23631 -208.17078)
		(width 0.14605)
		(layer "In5.Cu")
		(net "DRIVE_B_16_INS")
	)
	(segment
		(start 190.608712 -192.280794)
		(end 183.962294 -192.280794)
		(width 0.14605)
		(layer "In5.Cu")
		(net "DRIVE_B_16_INS")
	)
	(segment
		(start 183.962294 -192.280794)
		(end 164.25672 -172.57522)
		(width 0.14605)
		(layer "In5.Cu")
		(net "DRIVE_B_16_INS")
	)
	(segment
		(start 209.23631 -208.17078)
		(end 208.75625 -208.65084)
		(width 0.14605)
		(layer "In5.Cu")
		(net "DRIVE_B_16_INS")
	)
	(segment
		(start 201.761598 -205.694788)
		(end 201.761598 -203.43368)
		(width 0.14605)
		(layer "In5.Cu")
		(net "DRIVE_B_16_INS")
	)
	(segment
		(start 201.761598 -203.43368)
		(end 190.608712 -192.280794)
		(width 0.14605)
		(layer "In5.Cu")
		(net "DRIVE_B_16_INS")
	)
	(segment
		(start 204.71765 -208.65084)
		(end 201.761598 -205.694788)
		(width 0.14605)
		(layer "In5.Cu")
		(net "DRIVE_B_16_INS")
	)
	(segment
		(start 208.75625 -208.65084)
		(end 204.71765 -208.65084)
		(width 0.14605)
		(layer "In5.Cu")
		(net "DRIVE_B_16_INS")
	)
	(segment
		(start 207.947514 -194.224148)
		(end 207.153002 -193.429636)
		(width 0.17145)
		(layer "F.Cu")
		(net "DRIVE_B_16_FLT_LED")
	)
	(segment
		(start 210.48091 -194.4116)
		(end 210.293458 -194.224148)
		(width 0.17145)
		(layer "F.Cu")
		(net "DRIVE_B_16_FLT_LED")
	)
	(segment
		(start 187.328302 -109.4486)
		(end 144.354804 -109.4486)
		(width 0.17145)
		(layer "F.Cu")
		(net "DRIVE_B_16_FLT_LED")
	)
	(segment
		(start 207.153002 -193.429636)
		(end 200.16978 -193.429636)
		(width 0.17145)
		(layer "F.Cu")
		(net "DRIVE_B_16_FLT_LED")
	)
	(segment
		(start 141.72565 -106.819446)
		(end 141.72565 -104.671622)
		(width 0.17145)
		(layer "F.Cu")
		(net "DRIVE_B_16_FLT_LED")
	)
	(segment
		(start 211.6328 -194.4116)
		(end 210.48091 -194.4116)
		(width 0.17145)
		(layer "F.Cu")
		(net "DRIVE_B_16_FLT_LED")
	)
	(segment
		(start 196.38645 -189.646306)
		(end 196.38645 -164.446712)
		(width 0.17145)
		(layer "F.Cu")
		(net "DRIVE_B_16_FLT_LED")
	)
	(segment
		(start 144.354804 -109.4486)
		(end 141.72565 -106.819446)
		(width 0.17145)
		(layer "F.Cu")
		(net "DRIVE_B_16_FLT_LED")
	)
	(segment
		(start 200.16978 -193.429636)
		(end 196.38645 -189.646306)
		(width 0.17145)
		(layer "F.Cu")
		(net "DRIVE_B_16_FLT_LED")
	)
	(segment
		(start 141.72565 -100.7237)
		(end 141.72565 -102.427786)
		(width 0.17145)
		(layer "F.Cu")
		(net "DRIVE_B_16_FLT_LED")
	)
	(segment
		(start 196.38645 -164.446712)
		(end 211.244942 -149.58822)
		(width 0.17145)
		(layer "F.Cu")
		(net "DRIVE_B_16_FLT_LED")
	)
	(segment
		(start 141.72565 -102.427786)
		(end 141.72565 -104.671622)
		(width 0.17145)
		(layer "F.Cu")
		(net "DRIVE_B_16_FLT_LED")
	)
	(segment
		(start 211.244942 -133.36524)
		(end 187.328302 -109.4486)
		(width 0.17145)
		(layer "F.Cu")
		(net "DRIVE_B_16_FLT_LED")
	)
	(segment
		(start 211.244942 -149.58822)
		(end 211.244942 -133.36524)
		(width 0.17145)
		(layer "F.Cu")
		(net "DRIVE_B_16_FLT_LED")
	)
	(segment
		(start 210.293458 -194.224148)
		(end 207.947514 -194.224148)
		(width 0.17145)
		(layer "F.Cu")
		(net "DRIVE_B_16_FLT_LED")
	)
	(via
		(at 141.72565 -104.671622)
		(size 0.6604)
		(drill 0.3302)
		(layers "F.Cu" "B.Cu")
		(net "DRIVE_B_16_FLT_LED")
	)
	(segment
		(start 137.983468 -98.890328)
		(end 137.983468 -97.404428)
		(width 0.17145)
		(layer "F.Cu")
		(net "DRIVE_B_16_ACT")
	)
	(segment
		(start 274.467066 -194.330066)
		(end 271.158716 -191.021716)
		(width 0.17145)
		(layer "F.Cu")
		(net "DRIVE_B_16_ACT")
	)
	(segment
		(start 282.601162 -194.330066)
		(end 274.467066 -194.330066)
		(width 0.17145)
		(layer "F.Cu")
		(net "DRIVE_B_16_ACT")
	)
	(segment
		(start 271.158716 -191.021716)
		(end 271.158716 -176.389538)
		(width 0.17145)
		(layer "F.Cu")
		(net "DRIVE_B_16_ACT")
	)
	(segment
		(start 283.23667 -193.694558)
		(end 282.601162 -194.330066)
		(width 0.17145)
		(layer "F.Cu")
		(net "DRIVE_B_16_ACT")
	)
	(segment
		(start 137.983468 -97.404428)
		(end 137.983468 -95.6691)
		(width 0.17145)
		(layer "F.Cu")
		(net "DRIVE_B_16_ACT")
	)
	(segment
		(start 137.983468 -94.5642)
		(end 137.983468 -95.6691)
		(width 0.17145)
		(layer "F.Cu")
		(net "DRIVE_B_16_ACT")
	)
	(via
		(at 200.144634 -116.261134)
		(size 0.5588)
		(drill 0.3048)
		(layers "F.Cu" "B.Cu")
		(net "DRIVE_B_16_ACT")
	)
	(via
		(at 271.158716 -176.389538)
		(size 0.5588)
		(drill 0.3048)
		(layers "F.Cu" "B.Cu")
		(net "DRIVE_B_16_ACT")
	)
	(via
		(at 137.983468 -95.6691)
		(size 0.6604)
		(drill 0.3302)
		(layers "F.Cu" "B.Cu")
		(net "DRIVE_B_16_ACT")
	)
	(via
		(at 137.983468 -94.5642)
		(size 0.5588)
		(drill 0.3048)
		(layers "F.Cu" "B.Cu")
		(net "DRIVE_B_16_ACT")
	)
	(segment
		(start 233.343704 -137.974578)
		(end 237.701836 -142.33271)
		(width 0.17145)
		(layer "B.Cu")
		(net "DRIVE_B_16_ACT")
	)
	(segment
		(start 271.158716 -167.6781)
		(end 271.158716 -176.389538)
		(width 0.17145)
		(layer "B.Cu")
		(net "DRIVE_B_16_ACT")
	)
	(segment
		(start 200.144634 -116.261134)
		(end 200.672192 -116.788692)
		(width 0.17145)
		(layer "B.Cu")
		(net "DRIVE_B_16_ACT")
	)
	(segment
		(start 228.818948 -133.427724)
		(end 233.343704 -137.95248)
		(width 0.17145)
		(layer "B.Cu")
		(net "DRIVE_B_16_ACT")
	)
	(segment
		(start 245.813326 -142.33271)
		(end 271.158716 -167.6781)
		(width 0.17145)
		(layer "B.Cu")
		(net "DRIVE_B_16_ACT")
	)
	(segment
		(start 200.672192 -116.788692)
		(end 206.209646 -116.788692)
		(width 0.17145)
		(layer "B.Cu")
		(net "DRIVE_B_16_ACT")
	)
	(segment
		(start 206.209646 -116.788692)
		(end 222.848678 -133.427724)
		(width 0.17145)
		(layer "B.Cu")
		(net "DRIVE_B_16_ACT")
	)
	(segment
		(start 222.848678 -133.427724)
		(end 228.818948 -133.427724)
		(width 0.17145)
		(layer "B.Cu")
		(net "DRIVE_B_16_ACT")
	)
	(segment
		(start 237.701836 -142.33271)
		(end 245.813326 -142.33271)
		(width 0.17145)
		(layer "B.Cu")
		(net "DRIVE_B_16_ACT")
	)
	(segment
		(start 233.343704 -137.95248)
		(end 233.343704 -137.974578)
		(width 0.17145)
		(layer "B.Cu")
		(net "DRIVE_B_16_ACT")
	)
	(segment
		(start 149.653498 -102.9716)
		(end 175.33874 -102.9716)
		(width 0.14605)
		(layer "In2.Cu")
		(net "DRIVE_B_16_ACT")
	)
	(segment
		(start 175.33874 -102.9716)
		(end 184.20207 -111.83493)
		(width 0.14605)
		(layer "In2.Cu")
		(net "DRIVE_B_16_ACT")
	)
	(segment
		(start 141.246098 -94.5642)
		(end 149.653498 -102.9716)
		(width 0.14605)
		(layer "In2.Cu")
		(net "DRIVE_B_16_ACT")
	)
	(segment
		(start 184.20207 -111.83493)
		(end 195.71843 -111.83493)
		(width 0.14605)
		(layer "In2.Cu")
		(net "DRIVE_B_16_ACT")
	)
	(segment
		(start 137.983468 -94.5642)
		(end 141.246098 -94.5642)
		(width 0.14605)
		(layer "In2.Cu")
		(net "DRIVE_B_16_ACT")
	)
	(segment
		(start 195.71843 -111.83493)
		(end 200.144634 -116.261134)
		(width 0.14605)
		(layer "In2.Cu")
		(net "DRIVE_B_16_ACT")
	)
	(segment
		(start 228.847142 -217.949018)
		(end 228.243384 -217.949018)
		(width 0.17145)
		(layer "F.Cu")
		(net "DRIVE_B_15_PWR")
	)
	(segment
		(start 226.887024 -217.949018)
		(end 226.089718 -218.746324)
		(width 0.17145)
		(layer "F.Cu")
		(net "DRIVE_B_15_PWR")
	)
	(segment
		(start 230.47452 -219.576396)
		(end 228.847142 -217.949018)
		(width 0.17145)
		(layer "F.Cu")
		(net "DRIVE_B_15_PWR")
	)
	(segment
		(start 228.243384 -217.949018)
		(end 226.887024 -217.949018)
		(width 0.17145)
		(layer "F.Cu")
		(net "DRIVE_B_15_PWR")
	)
	(segment
		(start 118.364 -131.2926)
		(end 117.5639 -131.2926)
		(width 0.17145)
		(layer "F.Cu")
		(net "DRIVE_B_15_PWR")
	)
	(segment
		(start 230.47452 -223.612456)
		(end 230.47452 -219.576396)
		(width 0.17145)
		(layer "F.Cu")
		(net "DRIVE_B_15_PWR")
	)
	(via
		(at 228.243384 -217.949018)
		(size 0.6604)
		(drill 0.3302)
		(layers "F.Cu" "B.Cu")
		(net "DRIVE_B_15_PWR")
	)
	(via
		(at 118.364 -131.2926)
		(size 0.5588)
		(drill 0.3048)
		(layers "F.Cu" "B.Cu")
		(net "DRIVE_B_15_PWR")
	)
	(via
		(at 184.8104 -221.5642)
		(size 0.5588)
		(drill 0.3048)
		(layers "F.Cu" "B.Cu")
		(net "DRIVE_B_15_PWR")
	)
	(via
		(at 226.089718 -218.746324)
		(size 0.5588)
		(drill 0.3048)
		(layers "F.Cu" "B.Cu")
		(net "DRIVE_B_15_PWR")
	)
	(segment
		(start 120.107202 -132.7785)
		(end 118.621302 -131.2926)
		(width 0.14605)
		(layer "In2.Cu")
		(net "DRIVE_B_15_PWR")
	)
	(segment
		(start 135.775954 -137.071354)
		(end 121.488454 -137.071354)
		(width 0.14605)
		(layer "In2.Cu")
		(net "DRIVE_B_15_PWR")
	)
	(segment
		(start 184.8104 -221.5642)
		(end 184.777888 -221.5642)
		(width 0.14605)
		(layer "In2.Cu")
		(net "DRIVE_B_15_PWR")
	)
	(segment
		(start 176.751996 -213.538308)
		(end 176.751996 -178.047396)
		(width 0.14605)
		(layer "In2.Cu")
		(net "DRIVE_B_15_PWR")
	)
	(segment
		(start 184.777888 -221.5642)
		(end 176.751996 -213.538308)
		(width 0.14605)
		(layer "In2.Cu")
		(net "DRIVE_B_15_PWR")
	)
	(segment
		(start 118.621302 -131.2926)
		(end 118.364 -131.2926)
		(width 0.14605)
		(layer "In2.Cu")
		(net "DRIVE_B_15_PWR")
	)
	(segment
		(start 176.751996 -178.047396)
		(end 135.775954 -137.071354)
		(width 0.14605)
		(layer "In2.Cu")
		(net "DRIVE_B_15_PWR")
	)
	(segment
		(start 121.488454 -137.071354)
		(end 120.107202 -135.690102)
		(width 0.14605)
		(layer "In2.Cu")
		(net "DRIVE_B_15_PWR")
	)
	(segment
		(start 120.107202 -135.690102)
		(end 120.107202 -132.7785)
		(width 0.14605)
		(layer "In2.Cu")
		(net "DRIVE_B_15_PWR")
	)
	(segment
		(start 185.002932 -221.756732)
		(end 184.8104 -221.5642)
		(width 0.14605)
		(layer "In5.Cu")
		(net "DRIVE_B_15_PWR")
	)
	(segment
		(start 211.288376 -218.746324)
		(end 209.934302 -220.100398)
		(width 0.14605)
		(layer "In5.Cu")
		(net "DRIVE_B_15_PWR")
	)
	(segment
		(start 202.969114 -221.756732)
		(end 185.002932 -221.756732)
		(width 0.14605)
		(layer "In5.Cu")
		(net "DRIVE_B_15_PWR")
	)
	(segment
		(start 204.625448 -220.100398)
		(end 202.969114 -221.756732)
		(width 0.14605)
		(layer "In5.Cu")
		(net "DRIVE_B_15_PWR")
	)
	(segment
		(start 209.934302 -220.100398)
		(end 204.625448 -220.100398)
		(width 0.14605)
		(layer "In5.Cu")
		(net "DRIVE_B_15_PWR")
	)
	(segment
		(start 226.089718 -218.746324)
		(end 211.288376 -218.746324)
		(width 0.14605)
		(layer "In5.Cu")
		(net "DRIVE_B_15_PWR")
	)
	(segment
		(start 207.59674 -237.43158)
		(end 206.43596 -236.2708)
		(width 0.17145)
		(layer "F.Cu")
		(net "DRIVE_B_15_INS")
	)
	(segment
		(start 131.064 -161.902902)
		(end 131.064 -151.003)
		(width 0.17145)
		(layer "F.Cu")
		(net "DRIVE_B_15_INS")
	)
	(segment
		(start 206.43596 -236.2708)
		(end 198.165212 -236.2708)
		(width 0.17145)
		(layer "F.Cu")
		(net "DRIVE_B_15_INS")
	)
	(segment
		(start 194.365372 -232.47096)
		(end 181.067202 -232.47096)
		(width 0.17145)
		(layer "F.Cu")
		(net "DRIVE_B_15_INS")
	)
	(segment
		(start 198.165212 -236.2708)
		(end 195.35902 -233.464608)
		(width 0.17145)
		(layer "F.Cu")
		(net "DRIVE_B_15_INS")
	)
	(segment
		(start 195.35902 -233.464608)
		(end 194.365372 -232.47096)
		(width 0.17145)
		(layer "F.Cu")
		(net "DRIVE_B_15_INS")
	)
	(segment
		(start 181.067202 -232.47096)
		(end 181.04104 -232.444798)
		(width 0.17145)
		(layer "F.Cu")
		(net "DRIVE_B_15_INS")
	)
	(segment
		(start 207.59674 -238.84382)
		(end 207.59674 -237.43158)
		(width 0.17145)
		(layer "F.Cu")
		(net "DRIVE_B_15_INS")
	)
	(via
		(at 131.064 -161.902902)
		(size 0.5588)
		(drill 0.3048)
		(layers "F.Cu" "B.Cu")
		(net "DRIVE_B_15_INS")
	)
	(via
		(at 181.04104 -232.444798)
		(size 0.5588)
		(drill 0.3048)
		(layers "F.Cu" "B.Cu")
		(net "DRIVE_B_15_INS")
	)
	(via
		(at 195.35902 -233.464608)
		(size 0.6604)
		(drill 0.3302)
		(layers "F.Cu" "B.Cu")
		(net "DRIVE_B_15_INS")
	)
	(segment
		(start 173.37405 -213.39175)
		(end 173.37405 -179.650898)
		(width 0.14605)
		(layer "In2.Cu")
		(net "DRIVE_B_15_INS")
	)
	(segment
		(start 181.04104 -232.444798)
		(end 177.666396 -229.070154)
		(width 0.14605)
		(layer "In2.Cu")
		(net "DRIVE_B_15_INS")
	)
	(segment
		(start 153.439876 -167.47236)
		(end 147.870418 -161.902902)
		(width 0.14605)
		(layer "In2.Cu")
		(net "DRIVE_B_15_INS")
	)
	(segment
		(start 173.37405 -179.650898)
		(end 161.195512 -167.47236)
		(width 0.14605)
		(layer "In2.Cu")
		(net "DRIVE_B_15_INS")
	)
	(segment
		(start 177.666396 -229.070154)
		(end 177.666396 -217.684096)
		(width 0.14605)
		(layer "In2.Cu")
		(net "DRIVE_B_15_INS")
	)
	(segment
		(start 147.870418 -161.902902)
		(end 131.064 -161.902902)
		(width 0.14605)
		(layer "In2.Cu")
		(net "DRIVE_B_15_INS")
	)
	(segment
		(start 161.195512 -167.47236)
		(end 153.439876 -167.47236)
		(width 0.14605)
		(layer "In2.Cu")
		(net "DRIVE_B_15_INS")
	)
	(segment
		(start 177.666396 -217.684096)
		(end 173.37405 -213.39175)
		(width 0.14605)
		(layer "In2.Cu")
		(net "DRIVE_B_15_INS")
	)
	(segment
		(start 193.723768 -124.187966)
		(end 193.723768 -156.198062)
		(width 0.17145)
		(layer "F.Cu")
		(net "DRIVE_B_15_FLT_LED")
	)
	(segment
		(start 202.332336 -216.694004)
		(end 213.230714 -216.694004)
		(width 0.17145)
		(layer "F.Cu")
		(net "DRIVE_B_15_FLT_LED")
	)
	(segment
		(start 110.53826 -103.80853)
		(end 125.259846 -118.530116)
		(width 0.17145)
		(layer "F.Cu")
		(net "DRIVE_B_15_FLT_LED")
	)
	(segment
		(start 214.07628 -220.772482)
		(end 215.632538 -222.32874)
		(width 0.17145)
		(layer "F.Cu")
		(net "DRIVE_B_15_FLT_LED")
	)
	(segment
		(start 216.97569 -222.32874)
		(end 217.09507 -222.20936)
		(width 0.17145)
		(layer "F.Cu")
		(net "DRIVE_B_15_FLT_LED")
	)
	(segment
		(start 197.597522 -198.27748)
		(end 197.597522 -211.95919)
		(width 0.17145)
		(layer "F.Cu")
		(net "DRIVE_B_15_FLT_LED")
	)
	(segment
		(start 193.723768 -156.198062)
		(end 191.24295 -158.67888)
		(width 0.17145)
		(layer "F.Cu")
		(net "DRIVE_B_15_FLT_LED")
	)
	(segment
		(start 110.17885 -102.351586)
		(end 110.17885 -100.6729)
		(width 0.17145)
		(layer "F.Cu")
		(net "DRIVE_B_15_FLT_LED")
	)
	(segment
		(start 215.632538 -222.32874)
		(end 216.97569 -222.32874)
		(width 0.17145)
		(layer "F.Cu")
		(net "DRIVE_B_15_FLT_LED")
	)
	(segment
		(start 191.24295 -191.922908)
		(end 197.597522 -198.27748)
		(width 0.17145)
		(layer "F.Cu")
		(net "DRIVE_B_15_FLT_LED")
	)
	(segment
		(start 197.597522 -211.95919)
		(end 202.332336 -216.694004)
		(width 0.17145)
		(layer "F.Cu")
		(net "DRIVE_B_15_FLT_LED")
	)
	(segment
		(start 214.07628 -217.53957)
		(end 214.07628 -220.772482)
		(width 0.17145)
		(layer "F.Cu")
		(net "DRIVE_B_15_FLT_LED")
	)
	(segment
		(start 110.17885 -103.44912)
		(end 110.17885 -102.351586)
		(width 0.17145)
		(layer "F.Cu")
		(net "DRIVE_B_15_FLT_LED")
	)
	(segment
		(start 188.065918 -118.530116)
		(end 193.723768 -124.187966)
		(width 0.17145)
		(layer "F.Cu")
		(net "DRIVE_B_15_FLT_LED")
	)
	(segment
		(start 110.53826 -103.80853)
		(end 110.17885 -103.44912)
		(width 0.17145)
		(layer "F.Cu")
		(net "DRIVE_B_15_FLT_LED")
	)
	(segment
		(start 125.259846 -118.530116)
		(end 188.065918 -118.530116)
		(width 0.17145)
		(layer "F.Cu")
		(net "DRIVE_B_15_FLT_LED")
	)
	(segment
		(start 191.24295 -158.67888)
		(end 191.24295 -191.922908)
		(width 0.17145)
		(layer "F.Cu")
		(net "DRIVE_B_15_FLT_LED")
	)
	(segment
		(start 217.09507 -222.20936)
		(end 218.5924 -222.20936)
		(width 0.17145)
		(layer "F.Cu")
		(net "DRIVE_B_15_FLT_LED")
	)
	(segment
		(start 213.230714 -216.694004)
		(end 214.07628 -217.53957)
		(width 0.17145)
		(layer "F.Cu")
		(net "DRIVE_B_15_FLT_LED")
	)
	(via
		(at 110.53826 -103.80853)
		(size 0.6604)
		(drill 0.3302)
		(layers "F.Cu" "B.Cu")
		(net "DRIVE_B_15_FLT_LED")
	)
	(segment
		(start 270.31188 -190.99911)
		(end 270.31188 -173.67377)
		(width 0.17145)
		(layer "F.Cu")
		(net "DRIVE_B_15_ACT")
	)
	(segment
		(start 106.436668 -98.814128)
		(end 106.436668 -97.328228)
		(width 0.17145)
		(layer "F.Cu")
		(net "DRIVE_B_15_ACT")
	)
	(segment
		(start 282.83662 -195.494402)
		(end 282.199334 -194.857116)
		(width 0.17145)
		(layer "F.Cu")
		(net "DRIVE_B_15_ACT")
	)
	(segment
		(start 106.436668 -97.328228)
		(end 106.436668 -95.5929)
		(width 0.17145)
		(layer "F.Cu")
		(net "DRIVE_B_15_ACT")
	)
	(segment
		(start 106.436668 -95.5929)
		(end 106.436668 -94.488)
		(width 0.17145)
		(layer "F.Cu")
		(net "DRIVE_B_15_ACT")
	)
	(segment
		(start 282.199334 -194.857116)
		(end 274.169886 -194.857116)
		(width 0.17145)
		(layer "F.Cu")
		(net "DRIVE_B_15_ACT")
	)
	(segment
		(start 270.31188 -173.67377)
		(end 270.310864 -173.672754)
		(width 0.17145)
		(layer "F.Cu")
		(net "DRIVE_B_15_ACT")
	)
	(segment
		(start 274.169886 -194.857116)
		(end 270.31188 -190.99911)
		(width 0.17145)
		(layer "F.Cu")
		(net "DRIVE_B_15_ACT")
	)
	(via
		(at 270.310864 -173.672754)
		(size 0.5588)
		(drill 0.3048)
		(layers "F.Cu" "B.Cu")
		(net "DRIVE_B_15_ACT")
	)
	(via
		(at 201.160634 -117.327934)
		(size 0.5588)
		(drill 0.3048)
		(layers "F.Cu" "B.Cu")
		(net "DRIVE_B_15_ACT")
	)
	(via
		(at 106.436668 -94.488)
		(size 0.5588)
		(drill 0.3048)
		(layers "F.Cu" "B.Cu")
		(net "DRIVE_B_15_ACT")
	)
	(via
		(at 106.436668 -95.5929)
		(size 0.6604)
		(drill 0.3302)
		(layers "F.Cu" "B.Cu")
		(net "DRIVE_B_15_ACT")
	)
	(segment
		(start 222.635826 -133.942328)
		(end 223.06153 -133.942328)
		(width 0.17145)
		(layer "B.Cu")
		(net "DRIVE_B_15_ACT")
	)
	(segment
		(start 270.31188 -167.55872)
		(end 270.31188 -173.671738)
		(width 0.17145)
		(layer "B.Cu")
		(net "DRIVE_B_15_ACT")
	)
	(segment
		(start 237.48873 -142.84706)
		(end 245.60022 -142.84706)
		(width 0.17145)
		(layer "B.Cu")
		(net "DRIVE_B_15_ACT")
	)
	(segment
		(start 206.021432 -117.327934)
		(end 222.635826 -133.942328)
		(width 0.17145)
		(layer "B.Cu")
		(net "DRIVE_B_15_ACT")
	)
	(segment
		(start 223.061784 -133.942074)
		(end 228.583744 -133.942074)
		(width 0.17145)
		(layer "B.Cu")
		(net "DRIVE_B_15_ACT")
	)
	(segment
		(start 245.60022 -142.84706)
		(end 270.31188 -167.55872)
		(width 0.17145)
		(layer "B.Cu")
		(net "DRIVE_B_15_ACT")
	)
	(segment
		(start 228.583744 -133.942074)
		(end 237.48873 -142.84706)
		(width 0.17145)
		(layer "B.Cu")
		(net "DRIVE_B_15_ACT")
	)
	(segment
		(start 223.06153 -133.942328)
		(end 223.061784 -133.942074)
		(width 0.17145)
		(layer "B.Cu")
		(net "DRIVE_B_15_ACT")
	)
	(segment
		(start 201.160634 -117.327934)
		(end 206.021432 -117.327934)
		(width 0.17145)
		(layer "B.Cu")
		(net "DRIVE_B_15_ACT")
	)
	(segment
		(start 270.31188 -173.671738)
		(end 270.310864 -173.672754)
		(width 0.17145)
		(layer "B.Cu")
		(net "DRIVE_B_15_ACT")
	)
	(segment
		(start 118.29669 -103.40975)
		(end 174.82185 -103.40975)
		(width 0.14605)
		(layer "In2.Cu")
		(net "DRIVE_B_15_ACT")
	)
	(segment
		(start 195.874386 -112.72012)
		(end 199.950578 -116.796312)
		(width 0.14605)
		(layer "In2.Cu")
		(net "DRIVE_B_15_ACT")
	)
	(segment
		(start 184.13222 -112.72012)
		(end 195.874386 -112.72012)
		(width 0.14605)
		(layer "In2.Cu")
		(net "DRIVE_B_15_ACT")
	)
	(segment
		(start 200.629012 -116.796312)
		(end 201.160634 -117.327934)
		(width 0.14605)
		(layer "In2.Cu")
		(net "DRIVE_B_15_ACT")
	)
	(segment
		(start 106.436668 -94.488)
		(end 109.37494 -94.488)
		(width 0.14605)
		(layer "In2.Cu")
		(net "DRIVE_B_15_ACT")
	)
	(segment
		(start 109.37494 -94.488)
		(end 118.29669 -103.40975)
		(width 0.14605)
		(layer "In2.Cu")
		(net "DRIVE_B_15_ACT")
	)
	(segment
		(start 174.82185 -103.40975)
		(end 184.13222 -112.72012)
		(width 0.14605)
		(layer "In2.Cu")
		(net "DRIVE_B_15_ACT")
	)
	(segment
		(start 199.950578 -116.796312)
		(end 200.629012 -116.796312)
		(width 0.14605)
		(layer "In2.Cu")
		(net "DRIVE_B_15_ACT")
	)
	(segment
		(start 229.82428 -223.612456)
		(end 229.82428 -220.065092)
		(width 0.17145)
		(layer "F.Cu")
		(net "DRIVE_B_14_PWR")
	)
	(segment
		(start 86.8172 -131.2672)
		(end 85.9917 -131.2672)
		(width 0.17145)
		(layer "F.Cu")
		(net "DRIVE_B_14_PWR")
	)
	(segment
		(start 227.161852 -218.751658)
		(end 228.510846 -218.751658)
		(width 0.17145)
		(layer "F.Cu")
		(net "DRIVE_B_14_PWR")
	)
	(segment
		(start 228.510846 -218.751658)
		(end 229.298246 -219.539058)
		(width 0.17145)
		(layer "F.Cu")
		(net "DRIVE_B_14_PWR")
	)
	(segment
		(start 227.156518 -218.746324)
		(end 227.161852 -218.751658)
		(width 0.17145)
		(layer "F.Cu")
		(net "DRIVE_B_14_PWR")
	)
	(segment
		(start 229.82428 -220.065092)
		(end 229.298246 -219.539058)
		(width 0.17145)
		(layer "F.Cu")
		(net "DRIVE_B_14_PWR")
	)
	(via
		(at 227.156518 -218.746324)
		(size 0.5588)
		(drill 0.3048)
		(layers "F.Cu" "B.Cu")
		(net "DRIVE_B_14_PWR")
	)
	(via
		(at 86.8172 -131.2672)
		(size 0.5588)
		(drill 0.3048)
		(layers "F.Cu" "B.Cu")
		(net "DRIVE_B_14_PWR")
	)
	(via
		(at 229.298246 -219.539058)
		(size 0.6604)
		(drill 0.3302)
		(layers "F.Cu" "B.Cu")
		(net "DRIVE_B_14_PWR")
	)
	(via
		(at 183.7944 -221.5896)
		(size 0.5588)
		(drill 0.3048)
		(layers "F.Cu" "B.Cu")
		(net "DRIVE_B_14_PWR")
	)
	(segment
		(start 113.417858 -158.77032)
		(end 106.220514 -151.572976)
		(width 0.14605)
		(layer "In2.Cu")
		(net "DRIVE_B_14_PWR")
	)
	(segment
		(start 175.9458 -179.44084)
		(end 155.27528 -158.77032)
		(width 0.14605)
		(layer "In2.Cu")
		(net "DRIVE_B_14_PWR")
	)
	(segment
		(start 87.731092 -131.2672)
		(end 86.8172 -131.2672)
		(width 0.14605)
		(layer "In2.Cu")
		(net "DRIVE_B_14_PWR")
	)
	(segment
		(start 155.27528 -158.77032)
		(end 113.417858 -158.77032)
		(width 0.14605)
		(layer "In2.Cu")
		(net "DRIVE_B_14_PWR")
	)
	(segment
		(start 183.7944 -221.5896)
		(end 183.7944 -221.200472)
		(width 0.14605)
		(layer "In2.Cu")
		(net "DRIVE_B_14_PWR")
	)
	(segment
		(start 106.220514 -151.572976)
		(end 106.220514 -149.756622)
		(width 0.14605)
		(layer "In2.Cu")
		(net "DRIVE_B_14_PWR")
	)
	(segment
		(start 106.220514 -149.756622)
		(end 87.731092 -131.2672)
		(width 0.14605)
		(layer "In2.Cu")
		(net "DRIVE_B_14_PWR")
	)
	(segment
		(start 183.7944 -221.200472)
		(end 175.9458 -213.351872)
		(width 0.14605)
		(layer "In2.Cu")
		(net "DRIVE_B_14_PWR")
	)
	(segment
		(start 175.9458 -213.351872)
		(end 175.9458 -179.44084)
		(width 0.14605)
		(layer "In2.Cu")
		(net "DRIVE_B_14_PWR")
	)
	(segment
		(start 184.399682 -222.194882)
		(end 203.150724 -222.194882)
		(width 0.14605)
		(layer "In5.Cu")
		(net "DRIVE_B_14_PWR")
	)
	(segment
		(start 203.150724 -222.194882)
		(end 204.807058 -220.538548)
		(width 0.14605)
		(layer "In5.Cu")
		(net "DRIVE_B_14_PWR")
	)
	(segment
		(start 225.61677 -219.184474)
		(end 225.683572 -219.251276)
		(width 0.14605)
		(layer "In5.Cu")
		(net "DRIVE_B_14_PWR")
	)
	(segment
		(start 183.7944 -221.5896)
		(end 184.399682 -222.194882)
		(width 0.14605)
		(layer "In5.Cu")
		(net "DRIVE_B_14_PWR")
	)
	(segment
		(start 210.115912 -220.538548)
		(end 211.469986 -219.184474)
		(width 0.14605)
		(layer "In5.Cu")
		(net "DRIVE_B_14_PWR")
	)
	(segment
		(start 211.469986 -219.184474)
		(end 225.61677 -219.184474)
		(width 0.14605)
		(layer "In5.Cu")
		(net "DRIVE_B_14_PWR")
	)
	(segment
		(start 225.683572 -219.251276)
		(end 226.651566 -219.251276)
		(width 0.14605)
		(layer "In5.Cu")
		(net "DRIVE_B_14_PWR")
	)
	(segment
		(start 204.807058 -220.538548)
		(end 210.115912 -220.538548)
		(width 0.14605)
		(layer "In5.Cu")
		(net "DRIVE_B_14_PWR")
	)
	(segment
		(start 226.651566 -219.251276)
		(end 227.156518 -218.746324)
		(width 0.14605)
		(layer "In5.Cu")
		(net "DRIVE_B_14_PWR")
	)
	(segment
		(start 94.234 -169.53865)
		(end 15.433294 -169.53865)
		(width 0.17145)
		(layer "F.Cu")
		(net "DRIVE_B_14_INS")
	)
	(segment
		(start 206.9465 -237.54334)
		(end 206.18831 -236.78515)
		(width 0.17145)
		(layer "F.Cu")
		(net "DRIVE_B_14_INS")
	)
	(segment
		(start 12.17041 -172.801534)
		(end 12.17041 -203.468478)
		(width 0.17145)
		(layer "F.Cu")
		(net "DRIVE_B_14_INS")
	)
	(segment
		(start 7.805928 -207.83296)
		(end 7.805928 -215.813894)
		(width 0.17145)
		(layer "F.Cu")
		(net "DRIVE_B_14_INS")
	)
	(segment
		(start 10.800334 -218.8083)
		(end 23.1267 -218.8083)
		(width 0.17145)
		(layer "F.Cu")
		(net "DRIVE_B_14_INS")
	)
	(segment
		(start 50.075084 -220.504512)
		(end 62.685422 -233.11485)
		(width 0.17145)
		(layer "F.Cu")
		(net "DRIVE_B_14_INS")
	)
	(segment
		(start 15.433294 -169.53865)
		(end 12.17041 -172.801534)
		(width 0.17145)
		(layer "F.Cu")
		(net "DRIVE_B_14_INS")
	)
	(segment
		(start 34.009584 -216.92235)
		(end 37.591746 -220.504512)
		(width 0.17145)
		(layer "F.Cu")
		(net "DRIVE_B_14_INS")
	)
	(segment
		(start 37.591746 -220.504512)
		(end 50.075084 -220.504512)
		(width 0.17145)
		(layer "F.Cu")
		(net "DRIVE_B_14_INS")
	)
	(segment
		(start 206.9465 -238.84382)
		(end 206.9465 -237.54334)
		(width 0.17145)
		(layer "F.Cu")
		(net "DRIVE_B_14_INS")
	)
	(segment
		(start 193.684398 -233.11485)
		(end 113.865406 -233.11485)
		(width 0.17145)
		(layer "F.Cu")
		(net "DRIVE_B_14_INS")
	)
	(segment
		(start 25.01265 -216.92235)
		(end 34.009584 -216.92235)
		(width 0.17145)
		(layer "F.Cu")
		(net "DRIVE_B_14_INS")
	)
	(segment
		(start 7.805928 -215.813894)
		(end 10.800334 -218.8083)
		(width 0.17145)
		(layer "F.Cu")
		(net "DRIVE_B_14_INS")
	)
	(segment
		(start 206.18831 -236.78515)
		(end 197.354698 -236.78515)
		(width 0.17145)
		(layer "F.Cu")
		(net "DRIVE_B_14_INS")
	)
	(segment
		(start 99.568 -151.003)
		(end 99.568 -164.20465)
		(width 0.17145)
		(layer "F.Cu")
		(net "DRIVE_B_14_INS")
	)
	(segment
		(start 23.1267 -218.8083)
		(end 25.01265 -216.92235)
		(width 0.17145)
		(layer "F.Cu")
		(net "DRIVE_B_14_INS")
	)
	(segment
		(start 99.568 -164.20465)
		(end 94.234 -169.53865)
		(width 0.17145)
		(layer "F.Cu")
		(net "DRIVE_B_14_INS")
	)
	(segment
		(start 62.685422 -233.11485)
		(end 113.865406 -233.11485)
		(width 0.17145)
		(layer "F.Cu")
		(net "DRIVE_B_14_INS")
	)
	(segment
		(start 197.354698 -236.78515)
		(end 193.684398 -233.11485)
		(width 0.17145)
		(layer "F.Cu")
		(net "DRIVE_B_14_INS")
	)
	(segment
		(start 12.17041 -203.468478)
		(end 7.805928 -207.83296)
		(width 0.17145)
		(layer "F.Cu")
		(net "DRIVE_B_14_INS")
	)
	(via
		(at 113.865406 -233.11485)
		(size 0.6604)
		(drill 0.3302)
		(layers "F.Cu" "B.Cu")
		(net "DRIVE_B_14_INS")
	)
	(segment
		(start 191.7573 -158.92907)
		(end 191.7573 -191.709802)
		(width 0.17145)
		(layer "F.Cu")
		(net "DRIVE_B_14_FLT_LED")
	)
	(segment
		(start 202.545188 -216.1794)
		(end 213.443566 -216.1794)
		(width 0.17145)
		(layer "F.Cu")
		(net "DRIVE_B_14_FLT_LED")
	)
	(segment
		(start 122.61723 -89.362534)
		(end 122.61723 -105.18902)
		(width 0.17145)
		(layer "F.Cu")
		(net "DRIVE_B_14_FLT_LED")
	)
	(segment
		(start 191.7573 -191.709802)
		(end 198.111872 -198.064374)
		(width 0.17145)
		(layer "F.Cu")
		(net "DRIVE_B_14_FLT_LED")
	)
	(segment
		(start 122.61723 -89.362534)
		(end 122.61723 -69.977508)
		(width 0.17145)
		(layer "F.Cu")
		(net "DRIVE_B_14_FLT_LED")
	)
	(segment
		(start 216.762584 -221.81439)
		(end 217.017854 -221.55912)
		(width 0.17145)
		(layer "F.Cu")
		(net "DRIVE_B_14_FLT_LED")
	)
	(segment
		(start 214.59063 -220.367098)
		(end 216.037922 -221.81439)
		(width 0.17145)
		(layer "F.Cu")
		(net "DRIVE_B_14_FLT_LED")
	)
	(segment
		(start 213.443566 -216.1794)
		(end 214.59063 -217.326464)
		(width 0.17145)
		(layer "F.Cu")
		(net "DRIVE_B_14_FLT_LED")
	)
	(segment
		(start 83.76158 -102.427786)
		(end 78.55585 -102.427786)
		(width 0.17145)
		(layer "F.Cu")
		(net "DRIVE_B_14_FLT_LED")
	)
	(segment
		(start 86.1822 -60.1218)
		(end 86.1822 -100.007166)
		(width 0.17145)
		(layer "F.Cu")
		(net "DRIVE_B_14_FLT_LED")
	)
	(segment
		(start 86.1822 -100.007166)
		(end 83.76158 -102.427786)
		(width 0.17145)
		(layer "F.Cu")
		(net "DRIVE_B_14_FLT_LED")
	)
	(segment
		(start 89.818464 -56.485536)
		(end 86.1822 -60.1218)
		(width 0.17145)
		(layer "F.Cu")
		(net "DRIVE_B_14_FLT_LED")
	)
	(segment
		(start 194.238118 -156.448252)
		(end 191.7573 -158.92907)
		(width 0.17145)
		(layer "F.Cu")
		(net "DRIVE_B_14_FLT_LED")
	)
	(segment
		(start 198.111872 -198.064374)
		(end 198.111872 -211.746084)
		(width 0.17145)
		(layer "F.Cu")
		(net "DRIVE_B_14_FLT_LED")
	)
	(segment
		(start 216.037922 -221.81439)
		(end 216.762584 -221.81439)
		(width 0.17145)
		(layer "F.Cu")
		(net "DRIVE_B_14_FLT_LED")
	)
	(segment
		(start 78.55585 -102.427786)
		(end 78.55585 -100.7237)
		(width 0.17145)
		(layer "F.Cu")
		(net "DRIVE_B_14_FLT_LED")
	)
	(segment
		(start 214.59063 -217.326464)
		(end 214.59063 -220.367098)
		(width 0.17145)
		(layer "F.Cu")
		(net "DRIVE_B_14_FLT_LED")
	)
	(segment
		(start 217.017854 -221.55912)
		(end 218.5924 -221.55912)
		(width 0.17145)
		(layer "F.Cu")
		(net "DRIVE_B_14_FLT_LED")
	)
	(segment
		(start 198.111872 -211.746084)
		(end 202.545188 -216.1794)
		(width 0.17145)
		(layer "F.Cu")
		(net "DRIVE_B_14_FLT_LED")
	)
	(segment
		(start 134.863586 -117.435376)
		(end 187.698634 -117.435376)
		(width 0.17145)
		(layer "F.Cu")
		(net "DRIVE_B_14_FLT_LED")
	)
	(segment
		(start 187.698634 -117.435376)
		(end 194.238118 -123.97486)
		(width 0.17145)
		(layer "F.Cu")
		(net "DRIVE_B_14_FLT_LED")
	)
	(segment
		(start 122.61723 -105.18902)
		(end 134.863586 -117.435376)
		(width 0.17145)
		(layer "F.Cu")
		(net "DRIVE_B_14_FLT_LED")
	)
	(segment
		(start 122.61723 -69.977508)
		(end 109.125258 -56.485536)
		(width 0.17145)
		(layer "F.Cu")
		(net "DRIVE_B_14_FLT_LED")
	)
	(segment
		(start 194.238118 -123.97486)
		(end 194.238118 -156.448252)
		(width 0.17145)
		(layer "F.Cu")
		(net "DRIVE_B_14_FLT_LED")
	)
	(segment
		(start 109.125258 -56.485536)
		(end 89.818464 -56.485536)
		(width 0.17145)
		(layer "F.Cu")
		(net "DRIVE_B_14_FLT_LED")
	)
	(via
		(at 122.61723 -89.362534)
		(size 0.6604)
		(drill 0.3302)
		(layers "F.Cu" "B.Cu")
		(net "DRIVE_B_14_FLT_LED")
	)
	(segment
		(start 274.673314 -196.130926)
		(end 269.49019 -190.947802)
		(width 0.17145)
		(layer "F.Cu")
		(net "DRIVE_B_14_ACT")
	)
	(segment
		(start 74.813668 -98.890328)
		(end 74.813668 -97.404428)
		(width 0.17145)
		(layer "F.Cu")
		(net "DRIVE_B_14_ACT")
	)
	(segment
		(start 269.49019 -190.947802)
		(end 269.49019 -175.104298)
		(width 0.17145)
		(layer "F.Cu")
		(net "DRIVE_B_14_ACT")
	)
	(segment
		(start 74.813668 -95.6691)
		(end 74.813668 -94.5642)
		(width 0.17145)
		(layer "F.Cu")
		(net "DRIVE_B_14_ACT")
	)
	(segment
		(start 284.236668 -195.494402)
		(end 283.600144 -196.130926)
		(width 0.17145)
		(layer "F.Cu")
		(net "DRIVE_B_14_ACT")
	)
	(segment
		(start 269.49019 -175.104298)
		(end 269.221458 -174.835566)
		(width 0.17145)
		(layer "F.Cu")
		(net "DRIVE_B_14_ACT")
	)
	(segment
		(start 283.600144 -196.130926)
		(end 274.673314 -196.130926)
		(width 0.17145)
		(layer "F.Cu")
		(net "DRIVE_B_14_ACT")
	)
	(segment
		(start 74.813668 -97.404428)
		(end 74.813668 -95.6691)
		(width 0.17145)
		(layer "F.Cu")
		(net "DRIVE_B_14_ACT")
	)
	(via
		(at 200.144634 -117.327934)
		(size 0.5588)
		(drill 0.3048)
		(layers "F.Cu" "B.Cu")
		(net "DRIVE_B_14_ACT")
	)
	(via
		(at 269.221458 -174.835566)
		(size 0.5588)
		(drill 0.3048)
		(layers "F.Cu" "B.Cu")
		(net "DRIVE_B_14_ACT")
	)
	(via
		(at 74.813668 -94.5642)
		(size 0.5588)
		(drill 0.3048)
		(layers "F.Cu" "B.Cu")
		(net "DRIVE_B_14_ACT")
	)
	(via
		(at 74.813668 -95.6691)
		(size 0.6604)
		(drill 0.3302)
		(layers "F.Cu" "B.Cu")
		(net "DRIVE_B_14_ACT")
	)
	(segment
		(start 269.49019 -173.564042)
		(end 269.49019 -167.464486)
		(width 0.17145)
		(layer "B.Cu")
		(net "DRIVE_B_14_ACT")
	)
	(segment
		(start 222.848678 -134.456932)
		(end 222.422974 -134.456932)
		(width 0.17145)
		(layer "B.Cu")
		(net "DRIVE_B_14_ACT")
	)
	(segment
		(start 223.274636 -134.456678)
		(end 222.848932 -134.456678)
		(width 0.17145)
		(layer "B.Cu")
		(net "DRIVE_B_14_ACT")
	)
	(segment
		(start 223.27489 -134.456424)
		(end 223.274636 -134.456678)
		(width 0.17145)
		(layer "B.Cu")
		(net "DRIVE_B_14_ACT")
	)
	(segment
		(start 269.49019 -167.464486)
		(end 245.387114 -143.36141)
		(width 0.17145)
		(layer "B.Cu")
		(net "DRIVE_B_14_ACT")
	)
	(segment
		(start 228.24186 -134.456424)
		(end 223.27489 -134.456424)
		(width 0.17145)
		(layer "B.Cu")
		(net "DRIVE_B_14_ACT")
	)
	(segment
		(start 222.848932 -134.456678)
		(end 222.848678 -134.456932)
		(width 0.17145)
		(layer "B.Cu")
		(net "DRIVE_B_14_ACT")
	)
	(segment
		(start 237.146846 -143.36141)
		(end 228.24186 -134.456424)
		(width 0.17145)
		(layer "B.Cu")
		(net "DRIVE_B_14_ACT")
	)
	(segment
		(start 269.221458 -173.832774)
		(end 269.49019 -173.564042)
		(width 0.17145)
		(layer "B.Cu")
		(net "DRIVE_B_14_ACT")
	)
	(segment
		(start 269.221458 -174.835566)
		(end 269.221458 -173.832774)
		(width 0.17145)
		(layer "B.Cu")
		(net "DRIVE_B_14_ACT")
	)
	(segment
		(start 222.422974 -134.456932)
		(end 205.829154 -117.863112)
		(width 0.17145)
		(layer "B.Cu")
		(net "DRIVE_B_14_ACT")
	)
	(segment
		(start 205.829154 -117.863112)
		(end 200.679812 -117.863112)
		(width 0.17145)
		(layer "B.Cu")
		(net "DRIVE_B_14_ACT")
	)
	(segment
		(start 200.679812 -117.863112)
		(end 200.144634 -117.327934)
		(width 0.17145)
		(layer "B.Cu")
		(net "DRIVE_B_14_ACT")
	)
	(segment
		(start 245.387114 -143.36141)
		(end 237.146846 -143.36141)
		(width 0.17145)
		(layer "B.Cu")
		(net "DRIVE_B_14_ACT")
	)
	(segment
		(start 199.798686 -117.327934)
		(end 200.144634 -117.327934)
		(width 0.14605)
		(layer "In2.Cu")
		(net "DRIVE_B_14_ACT")
	)
	(segment
		(start 87.673434 -103.8479)
		(end 174.64024 -103.8479)
		(width 0.14605)
		(layer "In2.Cu")
		(net "DRIVE_B_14_ACT")
	)
	(segment
		(start 78.389734 -94.5642)
		(end 87.673434 -103.8479)
		(width 0.14605)
		(layer "In2.Cu")
		(net "DRIVE_B_14_ACT")
	)
	(segment
		(start 184.10428 -113.31194)
		(end 195.782692 -113.31194)
		(width 0.14605)
		(layer "In2.Cu")
		(net "DRIVE_B_14_ACT")
	)
	(segment
		(start 174.64024 -103.8479)
		(end 184.10428 -113.31194)
		(width 0.14605)
		(layer "In2.Cu")
		(net "DRIVE_B_14_ACT")
	)
	(segment
		(start 195.782692 -113.31194)
		(end 199.798686 -117.327934)
		(width 0.14605)
		(layer "In2.Cu")
		(net "DRIVE_B_14_ACT")
	)
	(segment
		(start 74.813668 -94.5642)
		(end 78.389734 -94.5642)
		(width 0.14605)
		(layer "In2.Cu")
		(net "DRIVE_B_14_ACT")
	)
	(segment
		(start 228.687884 -220.411548)
		(end 227.563172 -219.286836)
		(width 0.17145)
		(layer "F.Cu")
		(net "DRIVE_B_13_PWR")
	)
	(segment
		(start 229.17404 -223.612456)
		(end 229.17404 -222.21444)
		(width 0.17145)
		(layer "F.Cu")
		(net "DRIVE_B_13_PWR")
	)
	(segment
		(start 229.17404 -222.21444)
		(end 228.687884 -221.728284)
		(width 0.17145)
		(layer "F.Cu")
		(net "DRIVE_B_13_PWR")
	)
	(segment
		(start 55.372 -131.2164)
		(end 54.5211 -131.2164)
		(width 0.17145)
		(layer "F.Cu")
		(net "DRIVE_B_13_PWR")
	)
	(segment
		(start 228.687884 -221.312486)
		(end 228.687884 -220.411548)
		(width 0.17145)
		(layer "F.Cu")
		(net "DRIVE_B_13_PWR")
	)
	(segment
		(start 226.616006 -219.286836)
		(end 226.089718 -219.813124)
		(width 0.17145)
		(layer "F.Cu")
		(net "DRIVE_B_13_PWR")
	)
	(segment
		(start 228.687884 -221.728284)
		(end 228.687884 -221.312486)
		(width 0.17145)
		(layer "F.Cu")
		(net "DRIVE_B_13_PWR")
	)
	(segment
		(start 227.563172 -219.286836)
		(end 226.616006 -219.286836)
		(width 0.17145)
		(layer "F.Cu")
		(net "DRIVE_B_13_PWR")
	)
	(via
		(at 55.372 -131.2164)
		(size 0.5588)
		(drill 0.3048)
		(layers "F.Cu" "B.Cu")
		(net "DRIVE_B_13_PWR")
	)
	(via
		(at 228.687884 -221.312486)
		(size 0.6604)
		(drill 0.3302)
		(layers "F.Cu" "B.Cu")
		(net "DRIVE_B_13_PWR")
	)
	(via
		(at 226.089718 -219.813124)
		(size 0.5588)
		(drill 0.3048)
		(layers "F.Cu" "B.Cu")
		(net "DRIVE_B_13_PWR")
	)
	(via
		(at 181.483 -221.0054)
		(size 0.5588)
		(drill 0.3048)
		(layers "F.Cu" "B.Cu")
		(net "DRIVE_B_13_PWR")
	)
	(segment
		(start 174.9552 -213.233)
		(end 174.9552 -179.992528)
		(width 0.14605)
		(layer "In2.Cu")
		(net "DRIVE_B_13_PWR")
	)
	(segment
		(start 75.187048 -150.273258)
		(end 56.13019 -131.2164)
		(width 0.14605)
		(layer "In2.Cu")
		(net "DRIVE_B_13_PWR")
	)
	(segment
		(start 75.187048 -150.831042)
		(end 75.187048 -150.273258)
		(width 0.14605)
		(layer "In2.Cu")
		(net "DRIVE_B_13_PWR")
	)
	(segment
		(start 174.9552 -179.992528)
		(end 154.449272 -159.4866)
		(width 0.14605)
		(layer "In2.Cu")
		(net "DRIVE_B_13_PWR")
	)
	(segment
		(start 56.13019 -131.2164)
		(end 55.372 -131.2164)
		(width 0.14605)
		(layer "In2.Cu")
		(net "DRIVE_B_13_PWR")
	)
	(segment
		(start 83.842606 -159.4866)
		(end 75.187048 -150.831042)
		(width 0.14605)
		(layer "In2.Cu")
		(net "DRIVE_B_13_PWR")
	)
	(segment
		(start 181.483 -219.7608)
		(end 174.9552 -213.233)
		(width 0.14605)
		(layer "In2.Cu")
		(net "DRIVE_B_13_PWR")
	)
	(segment
		(start 154.449272 -159.4866)
		(end 83.842606 -159.4866)
		(width 0.14605)
		(layer "In2.Cu")
		(net "DRIVE_B_13_PWR")
	)
	(segment
		(start 181.483 -221.0054)
		(end 181.483 -219.7608)
		(width 0.14605)
		(layer "In2.Cu")
		(net "DRIVE_B_13_PWR")
	)
	(segment
		(start 204.988668 -220.976698)
		(end 203.332334 -222.633032)
		(width 0.14605)
		(layer "In5.Cu")
		(net "DRIVE_B_13_PWR")
	)
	(segment
		(start 210.297522 -220.976698)
		(end 204.988668 -220.976698)
		(width 0.14605)
		(layer "In5.Cu")
		(net "DRIVE_B_13_PWR")
	)
	(segment
		(start 226.089718 -219.813124)
		(end 225.62566 -219.813124)
		(width 0.14605)
		(layer "In5.Cu")
		(net "DRIVE_B_13_PWR")
	)
	(segment
		(start 181.70525 -221.22765)
		(end 181.483 -221.0054)
		(width 0.14605)
		(layer "In5.Cu")
		(net "DRIVE_B_13_PWR")
	)
	(segment
		(start 211.651596 -219.622624)
		(end 210.297522 -220.976698)
		(width 0.14605)
		(layer "In5.Cu")
		(net "DRIVE_B_13_PWR")
	)
	(segment
		(start 183.882792 -222.633032)
		(end 182.47741 -221.22765)
		(width 0.14605)
		(layer "In5.Cu")
		(net "DRIVE_B_13_PWR")
	)
	(segment
		(start 182.47741 -221.22765)
		(end 181.70525 -221.22765)
		(width 0.14605)
		(layer "In5.Cu")
		(net "DRIVE_B_13_PWR")
	)
	(segment
		(start 225.62566 -219.813124)
		(end 225.43516 -219.622624)
		(width 0.14605)
		(layer "In5.Cu")
		(net "DRIVE_B_13_PWR")
	)
	(segment
		(start 225.43516 -219.622624)
		(end 211.651596 -219.622624)
		(width 0.14605)
		(layer "In5.Cu")
		(net "DRIVE_B_13_PWR")
	)
	(segment
		(start 203.332334 -222.633032)
		(end 183.882792 -222.633032)
		(width 0.14605)
		(layer "In5.Cu")
		(net "DRIVE_B_13_PWR")
	)
	(segment
		(start 24.00935 -219.32265)
		(end 10.587228 -219.32265)
		(width 0.17145)
		(layer "F.Cu")
		(net "DRIVE_B_13_INS")
	)
	(segment
		(start 205.94066 -237.2995)
		(end 196.401182 -237.2995)
		(width 0.17145)
		(layer "F.Cu")
		(net "DRIVE_B_13_INS")
	)
	(segment
		(start 34.050478 -217.6907)
		(end 25.6413 -217.6907)
		(width 0.17145)
		(layer "F.Cu")
		(net "DRIVE_B_13_INS")
	)
	(segment
		(start 196.401182 -237.2995)
		(end 195.186046 -236.084364)
		(width 0.17145)
		(layer "F.Cu")
		(net "DRIVE_B_13_INS")
	)
	(segment
		(start 10.587228 -219.32265)
		(end 7.291578 -216.027)
		(width 0.17145)
		(layer "F.Cu")
		(net "DRIVE_B_13_INS")
	)
	(segment
		(start 7.291578 -207.619854)
		(end 11.65606 -203.255372)
		(width 0.17145)
		(layer "F.Cu")
		(net "DRIVE_B_13_INS")
	)
	(segment
		(start 62.544706 -233.70159)
		(end 49.861978 -221.018862)
		(width 0.17145)
		(layer "F.Cu")
		(net "DRIVE_B_13_INS")
	)
	(segment
		(start 206.29626 -237.6551)
		(end 205.94066 -237.2995)
		(width 0.17145)
		(layer "F.Cu")
		(net "DRIVE_B_13_INS")
	)
	(segment
		(start 192.803272 -233.70159)
		(end 62.544706 -233.70159)
		(width 0.17145)
		(layer "F.Cu")
		(net "DRIVE_B_13_INS")
	)
	(segment
		(start 11.65606 -203.255372)
		(end 11.65606 -172.588428)
		(width 0.17145)
		(layer "F.Cu")
		(net "DRIVE_B_13_INS")
	)
	(segment
		(start 67.945 -164.97681)
		(end 67.945 -151.003)
		(width 0.17145)
		(layer "F.Cu")
		(net "DRIVE_B_13_INS")
	)
	(segment
		(start 25.6413 -217.6907)
		(end 24.00935 -219.32265)
		(width 0.17145)
		(layer "F.Cu")
		(net "DRIVE_B_13_INS")
	)
	(segment
		(start 195.186046 -236.084364)
		(end 192.803272 -233.70159)
		(width 0.17145)
		(layer "F.Cu")
		(net "DRIVE_B_13_INS")
	)
	(segment
		(start 49.861978 -221.018862)
		(end 37.37864 -221.018862)
		(width 0.17145)
		(layer "F.Cu")
		(net "DRIVE_B_13_INS")
	)
	(segment
		(start 37.37864 -221.018862)
		(end 34.050478 -217.6907)
		(width 0.17145)
		(layer "F.Cu")
		(net "DRIVE_B_13_INS")
	)
	(segment
		(start 15.330678 -168.91381)
		(end 64.008 -168.91381)
		(width 0.17145)
		(layer "F.Cu")
		(net "DRIVE_B_13_INS")
	)
	(segment
		(start 206.29626 -238.84382)
		(end 206.29626 -237.6551)
		(width 0.17145)
		(layer "F.Cu")
		(net "DRIVE_B_13_INS")
	)
	(segment
		(start 64.008 -168.91381)
		(end 67.945 -164.97681)
		(width 0.17145)
		(layer "F.Cu")
		(net "DRIVE_B_13_INS")
	)
	(segment
		(start 7.291578 -216.027)
		(end 7.291578 -207.619854)
		(width 0.17145)
		(layer "F.Cu")
		(net "DRIVE_B_13_INS")
	)
	(segment
		(start 11.65606 -172.588428)
		(end 15.330678 -168.91381)
		(width 0.17145)
		(layer "F.Cu")
		(net "DRIVE_B_13_INS")
	)
	(via
		(at 195.186046 -236.084364)
		(size 0.6604)
		(drill 0.3302)
		(layers "F.Cu" "B.Cu")
		(net "DRIVE_B_13_INS")
	)
	(segment
		(start 215.922352 -220.779086)
		(end 216.762584 -220.779086)
		(width 0.17145)
		(layer "F.Cu")
		(net "DRIVE_B_13_FLT_LED")
	)
	(segment
		(start 198.626222 -197.851268)
		(end 198.626222 -211.532978)
		(width 0.17145)
		(layer "F.Cu")
		(net "DRIVE_B_13_FLT_LED")
	)
	(segment
		(start 124.065792 -69.623432)
		(end 110.413546 -55.971186)
		(width 0.17145)
		(layer "F.Cu")
		(net "DRIVE_B_13_FLT_LED")
	)
	(segment
		(start 135.740394 -116.469414)
		(end 187.460128 -116.469414)
		(width 0.17145)
		(layer "F.Cu")
		(net "DRIVE_B_13_FLT_LED")
	)
	(segment
		(start 216.762584 -220.779086)
		(end 216.892378 -220.90888)
		(width 0.17145)
		(layer "F.Cu")
		(net "DRIVE_B_13_FLT_LED")
	)
	(segment
		(start 213.164674 -215.1126)
		(end 215.10498 -217.052906)
		(width 0.17145)
		(layer "F.Cu")
		(net "DRIVE_B_13_FLT_LED")
	)
	(segment
		(start 215.10498 -217.052906)
		(end 215.10498 -219.961714)
		(width 0.17145)
		(layer "F.Cu")
		(net "DRIVE_B_13_FLT_LED")
	)
	(segment
		(start 124.065792 -86.046564)
		(end 124.065792 -104.794812)
		(width 0.17145)
		(layer "F.Cu")
		(net "DRIVE_B_13_FLT_LED")
	)
	(segment
		(start 58.5978 -100.391976)
		(end 56.63819 -102.351586)
		(width 0.17145)
		(layer "F.Cu")
		(net "DRIVE_B_13_FLT_LED")
	)
	(segment
		(start 58.5978 -58.3692)
		(end 58.5978 -100.391976)
		(width 0.17145)
		(layer "F.Cu")
		(net "DRIVE_B_13_FLT_LED")
	)
	(segment
		(start 124.065792 -104.794812)
		(end 135.740394 -116.469414)
		(width 0.17145)
		(layer "F.Cu")
		(net "DRIVE_B_13_FLT_LED")
	)
	(segment
		(start 110.413546 -55.971186)
		(end 60.995814 -55.971186)
		(width 0.17145)
		(layer "F.Cu")
		(net "DRIVE_B_13_FLT_LED")
	)
	(segment
		(start 124.065792 -86.046564)
		(end 124.065792 -69.623432)
		(width 0.17145)
		(layer "F.Cu")
		(net "DRIVE_B_13_FLT_LED")
	)
	(segment
		(start 194.752468 -123.761754)
		(end 194.752468 -156.805376)
		(width 0.17145)
		(layer "F.Cu")
		(net "DRIVE_B_13_FLT_LED")
	)
	(segment
		(start 187.460128 -116.469414)
		(end 194.752468 -123.761754)
		(width 0.17145)
		(layer "F.Cu")
		(net "DRIVE_B_13_FLT_LED")
	)
	(segment
		(start 194.752468 -156.805376)
		(end 192.27165 -159.286194)
		(width 0.17145)
		(layer "F.Cu")
		(net "DRIVE_B_13_FLT_LED")
	)
	(segment
		(start 216.892378 -220.90888)
		(end 218.5924 -220.90888)
		(width 0.17145)
		(layer "F.Cu")
		(net "DRIVE_B_13_FLT_LED")
	)
	(segment
		(start 56.63819 -102.351586)
		(end 52.72405 -102.351586)
		(width 0.17145)
		(layer "F.Cu")
		(net "DRIVE_B_13_FLT_LED")
	)
	(segment
		(start 192.27165 -159.286194)
		(end 192.27165 -191.496696)
		(width 0.17145)
		(layer "F.Cu")
		(net "DRIVE_B_13_FLT_LED")
	)
	(segment
		(start 60.995814 -55.971186)
		(end 58.5978 -58.3692)
		(width 0.17145)
		(layer "F.Cu")
		(net "DRIVE_B_13_FLT_LED")
	)
	(segment
		(start 215.10498 -219.961714)
		(end 215.922352 -220.779086)
		(width 0.17145)
		(layer "F.Cu")
		(net "DRIVE_B_13_FLT_LED")
	)
	(segment
		(start 192.27165 -191.496696)
		(end 198.626222 -197.851268)
		(width 0.17145)
		(layer "F.Cu")
		(net "DRIVE_B_13_FLT_LED")
	)
	(segment
		(start 202.205844 -215.1126)
		(end 213.164674 -215.1126)
		(width 0.17145)
		(layer "F.Cu")
		(net "DRIVE_B_13_FLT_LED")
	)
	(segment
		(start 52.72405 -102.351586)
		(end 52.72405 -100.6729)
		(width 0.17145)
		(layer "F.Cu")
		(net "DRIVE_B_13_FLT_LED")
	)
	(segment
		(start 198.626222 -211.532978)
		(end 202.205844 -215.1126)
		(width 0.17145)
		(layer "F.Cu")
		(net "DRIVE_B_13_FLT_LED")
	)
	(via
		(at 124.065792 -86.046564)
		(size 0.6604)
		(drill 0.3302)
		(layers "F.Cu" "B.Cu")
		(net "DRIVE_B_13_FLT_LED")
	)
	(segment
		(start 268.682724 -172.784262)
		(end 268.687804 -172.779182)
		(width 0.17145)
		(layer "F.Cu")
		(net "DRIVE_B_13_ACT")
	)
	(segment
		(start 268.682724 -175.363124)
		(end 268.682724 -172.784262)
		(width 0.17145)
		(layer "F.Cu")
		(net "DRIVE_B_13_ACT")
	)
	(segment
		(start 281.200098 -196.657976)
		(end 274.472908 -196.657976)
		(width 0.17145)
		(layer "F.Cu")
		(net "DRIVE_B_13_ACT")
	)
	(segment
		(start 48.981868 -98.814128)
		(end 48.981868 -97.328228)
		(width 0.17145)
		(layer "F.Cu")
		(net "DRIVE_B_13_ACT")
	)
	(segment
		(start 274.472908 -196.657976)
		(end 268.97584 -191.160908)
		(width 0.17145)
		(layer "F.Cu")
		(net "DRIVE_B_13_ACT")
	)
	(segment
		(start 48.981868 -95.5929)
		(end 48.981868 -94.488)
		(width 0.17145)
		(layer "F.Cu")
		(net "DRIVE_B_13_ACT")
	)
	(segment
		(start 268.97584 -191.160908)
		(end 268.97584 -175.65624)
		(width 0.17145)
		(layer "F.Cu")
		(net "DRIVE_B_13_ACT")
	)
	(segment
		(start 281.836622 -197.2945)
		(end 281.200098 -196.657976)
		(width 0.17145)
		(layer "F.Cu")
		(net "DRIVE_B_13_ACT")
	)
	(segment
		(start 268.97584 -175.65624)
		(end 268.682724 -175.363124)
		(width 0.17145)
		(layer "F.Cu")
		(net "DRIVE_B_13_ACT")
	)
	(segment
		(start 48.981868 -97.328228)
		(end 48.981868 -95.5929)
		(width 0.17145)
		(layer "F.Cu")
		(net "DRIVE_B_13_ACT")
	)
	(via
		(at 201.160634 -118.394734)
		(size 0.5588)
		(drill 0.3048)
		(layers "F.Cu" "B.Cu")
		(net "DRIVE_B_13_ACT")
	)
	(via
		(at 268.687804 -172.779182)
		(size 0.5588)
		(drill 0.3048)
		(layers "F.Cu" "B.Cu")
		(net "DRIVE_B_13_ACT")
	)
	(via
		(at 48.981868 -95.5929)
		(size 0.6604)
		(drill 0.3302)
		(layers "F.Cu" "B.Cu")
		(net "DRIVE_B_13_ACT")
	)
	(via
		(at 48.981868 -94.488)
		(size 0.5588)
		(drill 0.3048)
		(layers "F.Cu" "B.Cu")
		(net "DRIVE_B_13_ACT")
	)
	(segment
		(start 222.209868 -134.971282)
		(end 223.061784 -134.971282)
		(width 0.17145)
		(layer "B.Cu")
		(net "DRIVE_B_13_ACT")
	)
	(segment
		(start 201.160634 -118.394734)
		(end 205.63332 -118.394734)
		(width 0.17145)
		(layer "B.Cu")
		(net "DRIVE_B_13_ACT")
	)
	(segment
		(start 223.062038 -134.971028)
		(end 223.487996 -134.971028)
		(width 0.17145)
		(layer "B.Cu")
		(net "DRIVE_B_13_ACT")
	)
	(segment
		(start 227.355908 -134.970774)
		(end 236.264958 -143.879824)
		(width 0.17145)
		(layer "B.Cu")
		(net "DRIVE_B_13_ACT")
	)
	(segment
		(start 223.061784 -134.971282)
		(end 223.062038 -134.971028)
		(width 0.17145)
		(layer "B.Cu")
		(net "DRIVE_B_13_ACT")
	)
	(segment
		(start 205.63332 -118.394734)
		(end 222.209868 -134.971282)
		(width 0.17145)
		(layer "B.Cu")
		(net "DRIVE_B_13_ACT")
	)
	(segment
		(start 223.487996 -134.971028)
		(end 223.48825 -134.970774)
		(width 0.17145)
		(layer "B.Cu")
		(net "DRIVE_B_13_ACT")
	)
	(segment
		(start 268.682724 -172.774102)
		(end 268.687804 -172.779182)
		(width 0.17145)
		(layer "B.Cu")
		(net "DRIVE_B_13_ACT")
	)
	(segment
		(start 236.264958 -143.879824)
		(end 244.859048 -143.879824)
		(width 0.17145)
		(layer "B.Cu")
		(net "DRIVE_B_13_ACT")
	)
	(segment
		(start 223.48825 -134.970774)
		(end 227.355908 -134.970774)
		(width 0.17145)
		(layer "B.Cu")
		(net "DRIVE_B_13_ACT")
	)
	(segment
		(start 244.859048 -143.879824)
		(end 268.682724 -167.7035)
		(width 0.17145)
		(layer "B.Cu")
		(net "DRIVE_B_13_ACT")
	)
	(segment
		(start 268.682724 -167.7035)
		(end 268.682724 -172.774102)
		(width 0.17145)
		(layer "B.Cu")
		(net "DRIVE_B_13_ACT")
	)
	(segment
		(start 71.9328 -104.28605)
		(end 174.31385 -104.28605)
		(width 0.14605)
		(layer "In2.Cu")
		(net "DRIVE_B_13_ACT")
	)
	(segment
		(start 48.981868 -94.488)
		(end 51.58232 -94.488)
		(width 0.14605)
		(layer "In2.Cu")
		(net "DRIVE_B_13_ACT")
	)
	(segment
		(start 51.58232 -94.488)
		(end 59.48426 -102.38994)
		(width 0.14605)
		(layer "In2.Cu")
		(net "DRIVE_B_13_ACT")
	)
	(segment
		(start 183.80456 -113.77676)
		(end 195.473828 -113.77676)
		(width 0.14605)
		(layer "In2.Cu")
		(net "DRIVE_B_13_ACT")
	)
	(segment
		(start 200.629012 -117.863112)
		(end 201.160634 -118.394734)
		(width 0.14605)
		(layer "In2.Cu")
		(net "DRIVE_B_13_ACT")
	)
	(segment
		(start 195.473828 -113.77676)
		(end 199.56018 -117.863112)
		(width 0.14605)
		(layer "In2.Cu")
		(net "DRIVE_B_13_ACT")
	)
	(segment
		(start 59.48426 -102.38994)
		(end 70.03669 -102.38994)
		(width 0.14605)
		(layer "In2.Cu")
		(net "DRIVE_B_13_ACT")
	)
	(segment
		(start 70.03669 -102.38994)
		(end 71.9328 -104.28605)
		(width 0.14605)
		(layer "In2.Cu")
		(net "DRIVE_B_13_ACT")
	)
	(segment
		(start 199.56018 -117.863112)
		(end 200.629012 -117.863112)
		(width 0.14605)
		(layer "In2.Cu")
		(net "DRIVE_B_13_ACT")
	)
	(segment
		(start 174.31385 -104.28605)
		(end 183.80456 -113.77676)
		(width 0.14605)
		(layer "In2.Cu")
		(net "DRIVE_B_13_ACT")
	)
	(segment
		(start 228.5238 -222.418402)
		(end 227.417884 -221.312486)
		(width 0.17145)
		(layer "F.Cu")
		(net "DRIVE_B_12_PWR")
	)
	(segment
		(start 227.156518 -221.05112)
		(end 227.417884 -221.312486)
		(width 0.17145)
		(layer "F.Cu")
		(net "DRIVE_B_12_PWR")
	)
	(segment
		(start 228.5238 -223.612456)
		(end 228.5238 -222.418402)
		(width 0.17145)
		(layer "F.Cu")
		(net "DRIVE_B_12_PWR")
	)
	(segment
		(start 227.156518 -219.813124)
		(end 227.156518 -221.05112)
		(width 0.17145)
		(layer "F.Cu")
		(net "DRIVE_B_12_PWR")
	)
	(segment
		(start 22.9489 -131.2672)
		(end 23.8252 -131.2672)
		(width 0.17145)
		(layer "F.Cu")
		(net "DRIVE_B_12_PWR")
	)
	(via
		(at 23.8252 -131.2672)
		(size 0.5588)
		(drill 0.3048)
		(layers "F.Cu" "B.Cu")
		(net "DRIVE_B_12_PWR")
	)
	(via
		(at 178.2318 -221.6658)
		(size 0.5588)
		(drill 0.3048)
		(layers "F.Cu" "B.Cu")
		(net "DRIVE_B_12_PWR")
	)
	(via
		(at 227.156518 -219.813124)
		(size 0.5588)
		(drill 0.3048)
		(layers "F.Cu" "B.Cu")
		(net "DRIVE_B_12_PWR")
	)
	(via
		(at 227.417884 -221.312486)
		(size 0.6604)
		(drill 0.3302)
		(layers "F.Cu" "B.Cu")
		(net "DRIVE_B_12_PWR")
	)
	(segment
		(start 178.2318 -221.6658)
		(end 178.2318 -217.62974)
		(width 0.14605)
		(layer "In2.Cu")
		(net "DRIVE_B_12_PWR")
	)
	(segment
		(start 173.8122 -179.469288)
		(end 154.712162 -160.36925)
		(width 0.14605)
		(layer "In2.Cu")
		(net "DRIVE_B_12_PWR")
	)
	(segment
		(start 53.063902 -160.330896)
		(end 43.564048 -150.831042)
		(width 0.14605)
		(layer "In2.Cu")
		(net "DRIVE_B_12_PWR")
	)
	(segment
		(start 84.054696 -160.36925)
		(end 84.016342 -160.330896)
		(width 0.14605)
		(layer "In2.Cu")
		(net "DRIVE_B_12_PWR")
	)
	(segment
		(start 154.712162 -160.36925)
		(end 84.054696 -160.36925)
		(width 0.14605)
		(layer "In2.Cu")
		(net "DRIVE_B_12_PWR")
	)
	(segment
		(start 43.564048 -149.567392)
		(end 30.271466 -136.27481)
		(width 0.14605)
		(layer "In2.Cu")
		(net "DRIVE_B_12_PWR")
	)
	(segment
		(start 43.564048 -150.831042)
		(end 43.564048 -149.567392)
		(width 0.14605)
		(layer "In2.Cu")
		(net "DRIVE_B_12_PWR")
	)
	(segment
		(start 30.271466 -136.27481)
		(end 28.119832 -136.27481)
		(width 0.14605)
		(layer "In2.Cu")
		(net "DRIVE_B_12_PWR")
	)
	(segment
		(start 84.016342 -160.330896)
		(end 53.063902 -160.330896)
		(width 0.14605)
		(layer "In2.Cu")
		(net "DRIVE_B_12_PWR")
	)
	(segment
		(start 27.005788 -134.447788)
		(end 23.8252 -131.2672)
		(width 0.14605)
		(layer "In2.Cu")
		(net "DRIVE_B_12_PWR")
	)
	(segment
		(start 173.8122 -213.21014)
		(end 173.8122 -179.469288)
		(width 0.14605)
		(layer "In2.Cu")
		(net "DRIVE_B_12_PWR")
	)
	(segment
		(start 28.119832 -136.27481)
		(end 27.005788 -135.160766)
		(width 0.14605)
		(layer "In2.Cu")
		(net "DRIVE_B_12_PWR")
	)
	(segment
		(start 27.005788 -135.160766)
		(end 27.005788 -134.447788)
		(width 0.14605)
		(layer "In2.Cu")
		(net "DRIVE_B_12_PWR")
	)
	(segment
		(start 178.2318 -217.62974)
		(end 173.8122 -213.21014)
		(width 0.14605)
		(layer "In2.Cu")
		(net "DRIVE_B_12_PWR")
	)
	(segment
		(start 225.510852 -220.318076)
		(end 226.651566 -220.318076)
		(width 0.14605)
		(layer "In5.Cu")
		(net "DRIVE_B_12_PWR")
	)
	(segment
		(start 210.479132 -221.414848)
		(end 211.833206 -220.060774)
		(width 0.14605)
		(layer "In5.Cu")
		(net "DRIVE_B_12_PWR")
	)
	(segment
		(start 178.2318 -221.6658)
		(end 182.2958 -221.6658)
		(width 0.14605)
		(layer "In5.Cu")
		(net "DRIVE_B_12_PWR")
	)
	(segment
		(start 203.513944 -223.071182)
		(end 205.170278 -221.414848)
		(width 0.14605)
		(layer "In5.Cu")
		(net "DRIVE_B_12_PWR")
	)
	(segment
		(start 205.170278 -221.414848)
		(end 210.479132 -221.414848)
		(width 0.14605)
		(layer "In5.Cu")
		(net "DRIVE_B_12_PWR")
	)
	(segment
		(start 226.651566 -220.318076)
		(end 227.156518 -219.813124)
		(width 0.14605)
		(layer "In5.Cu")
		(net "DRIVE_B_12_PWR")
	)
	(segment
		(start 225.25355 -220.060774)
		(end 225.510852 -220.318076)
		(width 0.14605)
		(layer "In5.Cu")
		(net "DRIVE_B_12_PWR")
	)
	(segment
		(start 182.2958 -221.6658)
		(end 183.701182 -223.071182)
		(width 0.14605)
		(layer "In5.Cu")
		(net "DRIVE_B_12_PWR")
	)
	(segment
		(start 183.701182 -223.071182)
		(end 203.513944 -223.071182)
		(width 0.14605)
		(layer "In5.Cu")
		(net "DRIVE_B_12_PWR")
	)
	(segment
		(start 211.833206 -220.060774)
		(end 225.25355 -220.060774)
		(width 0.14605)
		(layer "In5.Cu")
		(net "DRIVE_B_12_PWR")
	)
	(segment
		(start 11.14171 -172.375322)
		(end 15.238222 -168.27881)
		(width 0.17145)
		(layer "F.Cu")
		(net "DRIVE_B_12_INS")
	)
	(segment
		(start 25.908 -219.837)
		(end 10.373868 -219.837)
		(width 0.17145)
		(layer "F.Cu")
		(net "DRIVE_B_12_INS")
	)
	(segment
		(start 34.091372 -218.45905)
		(end 27.28595 -218.45905)
		(width 0.17145)
		(layer "F.Cu")
		(net "DRIVE_B_12_INS")
	)
	(segment
		(start 11.14171 -203.042266)
		(end 11.14171 -172.375322)
		(width 0.17145)
		(layer "F.Cu")
		(net "DRIVE_B_12_INS")
	)
	(segment
		(start 49.648872 -221.533212)
		(end 37.165534 -221.533212)
		(width 0.17145)
		(layer "F.Cu")
		(net "DRIVE_B_12_INS")
	)
	(segment
		(start 205.645766 -238.253016)
		(end 205.2066 -237.81385)
		(width 0.17145)
		(layer "F.Cu")
		(net "DRIVE_B_12_INS")
	)
	(segment
		(start 6.77672 -207.407256)
		(end 11.14171 -203.042266)
		(width 0.17145)
		(layer "F.Cu")
		(net "DRIVE_B_12_INS")
	)
	(segment
		(start 195.466716 -237.81385)
		(end 192.674748 -235.021882)
		(width 0.17145)
		(layer "F.Cu")
		(net "DRIVE_B_12_INS")
	)
	(segment
		(start 192.674748 -235.021882)
		(end 191.868806 -234.21594)
		(width 0.17145)
		(layer "F.Cu")
		(net "DRIVE_B_12_INS")
	)
	(segment
		(start 205.64602 -238.84382)
		(end 205.645766 -238.844074)
		(width 0.17145)
		(layer "F.Cu")
		(net "DRIVE_B_12_INS")
	)
	(segment
		(start 10.373868 -219.837)
		(end 6.77672 -216.239852)
		(width 0.17145)
		(layer "F.Cu")
		(net "DRIVE_B_12_INS")
	)
	(segment
		(start 37.165534 -221.533212)
		(end 34.091372 -218.45905)
		(width 0.17145)
		(layer "F.Cu")
		(net "DRIVE_B_12_INS")
	)
	(segment
		(start 6.77672 -216.239852)
		(end 6.77672 -207.407256)
		(width 0.17145)
		(layer "F.Cu")
		(net "DRIVE_B_12_INS")
	)
	(segment
		(start 27.28595 -218.45905)
		(end 25.908 -219.837)
		(width 0.17145)
		(layer "F.Cu")
		(net "DRIVE_B_12_INS")
	)
	(segment
		(start 205.2066 -237.81385)
		(end 195.466716 -237.81385)
		(width 0.17145)
		(layer "F.Cu")
		(net "DRIVE_B_12_INS")
	)
	(segment
		(start 31.877 -168.27881)
		(end 36.449 -163.70681)
		(width 0.17145)
		(layer "F.Cu")
		(net "DRIVE_B_12_INS")
	)
	(segment
		(start 15.238222 -168.27881)
		(end 31.877 -168.27881)
		(width 0.17145)
		(layer "F.Cu")
		(net "DRIVE_B_12_INS")
	)
	(segment
		(start 205.645766 -238.844074)
		(end 205.645766 -238.253016)
		(width 0.17145)
		(layer "F.Cu")
		(net "DRIVE_B_12_INS")
	)
	(segment
		(start 62.030356 -233.91495)
		(end 62.030356 -233.914696)
		(width 0.17145)
		(layer "F.Cu")
		(net "DRIVE_B_12_INS")
	)
	(segment
		(start 36.449 -163.70681)
		(end 36.449 -151.003)
		(width 0.17145)
		(layer "F.Cu")
		(net "DRIVE_B_12_INS")
	)
	(segment
		(start 62.030356 -233.914696)
		(end 49.648872 -221.533212)
		(width 0.17145)
		(layer "F.Cu")
		(net "DRIVE_B_12_INS")
	)
	(segment
		(start 191.868806 -234.21594)
		(end 62.331346 -234.21594)
		(width 0.17145)
		(layer "F.Cu")
		(net "DRIVE_B_12_INS")
	)
	(segment
		(start 62.331346 -234.21594)
		(end 62.030356 -233.91495)
		(width 0.17145)
		(layer "F.Cu")
		(net "DRIVE_B_12_INS")
	)
	(via
		(at 192.674748 -235.021882)
		(size 0.6604)
		(drill 0.3302)
		(layers "F.Cu" "B.Cu")
		(net "DRIVE_B_12_INS")
	)
	(segment
		(start 23.6982 -59.9694)
		(end 23.6982 -100.203)
		(width 0.17145)
		(layer "F.Cu")
		(net "DRIVE_B_12_FLT_LED")
	)
	(segment
		(start 195.266818 -123.548648)
		(end 195.266818 -157.026356)
		(width 0.17145)
		(layer "F.Cu")
		(net "DRIVE_B_12_FLT_LED")
	)
	(segment
		(start 199.140572 -211.319872)
		(end 202.41895 -214.59825)
		(width 0.17145)
		(layer "F.Cu")
		(net "DRIVE_B_12_FLT_LED")
	)
	(segment
		(start 18.654268 -102.43947)
		(end 18.654268 -100.735384)
		(width 0.17145)
		(layer "F.Cu")
		(net "DRIVE_B_12_FLT_LED")
	)
	(segment
		(start 202.41895 -214.59825)
		(end 213.37778 -214.59825)
		(width 0.17145)
		(layer "F.Cu")
		(net "DRIVE_B_12_FLT_LED")
	)
	(segment
		(start 213.37778 -214.59825)
		(end 215.61933 -216.8398)
		(width 0.17145)
		(layer "F.Cu")
		(net "DRIVE_B_12_FLT_LED")
	)
	(segment
		(start 111.895382 -55.456836)
		(end 28.210764 -55.456836)
		(width 0.17145)
		(layer "F.Cu")
		(net "DRIVE_B_12_FLT_LED")
	)
	(segment
		(start 199.140572 -197.638162)
		(end 199.140572 -211.319872)
		(width 0.17145)
		(layer "F.Cu")
		(net "DRIVE_B_12_FLT_LED")
	)
	(segment
		(start 195.266818 -157.026356)
		(end 192.786 -159.507174)
		(width 0.17145)
		(layer "F.Cu")
		(net "DRIVE_B_12_FLT_LED")
	)
	(segment
		(start 125.450346 -81.50733)
		(end 125.450346 -69.0118)
		(width 0.17145)
		(layer "F.Cu")
		(net "DRIVE_B_12_FLT_LED")
	)
	(segment
		(start 125.450346 -104.22509)
		(end 136.889998 -115.664742)
		(width 0.17145)
		(layer "F.Cu")
		(net "DRIVE_B_12_FLT_LED")
	)
	(segment
		(start 125.450346 -81.50733)
		(end 125.450346 -104.22509)
		(width 0.17145)
		(layer "F.Cu")
		(net "DRIVE_B_12_FLT_LED")
	)
	(segment
		(start 192.786 -159.507174)
		(end 192.786 -191.28359)
		(width 0.17145)
		(layer "F.Cu")
		(net "DRIVE_B_12_FLT_LED")
	)
	(segment
		(start 192.786 -191.28359)
		(end 199.140572 -197.638162)
		(width 0.17145)
		(layer "F.Cu")
		(net "DRIVE_B_12_FLT_LED")
	)
	(segment
		(start 125.450346 -69.0118)
		(end 111.895382 -55.456836)
		(width 0.17145)
		(layer "F.Cu")
		(net "DRIVE_B_12_FLT_LED")
	)
	(segment
		(start 187.382912 -115.664742)
		(end 195.266818 -123.548648)
		(width 0.17145)
		(layer "F.Cu")
		(net "DRIVE_B_12_FLT_LED")
	)
	(segment
		(start 215.61933 -219.55633)
		(end 216.32164 -220.25864)
		(width 0.17145)
		(layer "F.Cu")
		(net "DRIVE_B_12_FLT_LED")
	)
	(segment
		(start 23.6982 -100.203)
		(end 21.46173 -102.43947)
		(width 0.17145)
		(layer "F.Cu")
		(net "DRIVE_B_12_FLT_LED")
	)
	(segment
		(start 215.61933 -216.8398)
		(end 215.61933 -219.55633)
		(width 0.17145)
		(layer "F.Cu")
		(net "DRIVE_B_12_FLT_LED")
	)
	(segment
		(start 216.32164 -220.25864)
		(end 218.5924 -220.25864)
		(width 0.17145)
		(layer "F.Cu")
		(net "DRIVE_B_12_FLT_LED")
	)
	(segment
		(start 136.889998 -115.664742)
		(end 187.382912 -115.664742)
		(width 0.17145)
		(layer "F.Cu")
		(net "DRIVE_B_12_FLT_LED")
	)
	(segment
		(start 28.210764 -55.456836)
		(end 23.6982 -59.9694)
		(width 0.17145)
		(layer "F.Cu")
		(net "DRIVE_B_12_FLT_LED")
	)
	(segment
		(start 21.46173 -102.43947)
		(end 18.654268 -102.43947)
		(width 0.17145)
		(layer "F.Cu")
		(net "DRIVE_B_12_FLT_LED")
	)
	(via
		(at 125.450346 -81.50733)
		(size 0.6604)
		(drill 0.3302)
		(layers "F.Cu" "B.Cu")
		(net "DRIVE_B_12_FLT_LED")
	)
	(segment
		(start 14.912086 -98.902012)
		(end 14.912086 -97.416112)
		(width 0.17145)
		(layer "F.Cu")
		(net "DRIVE_B_12_ACT")
	)
	(segment
		(start 14.912086 -95.680784)
		(end 14.912086 -94.575884)
		(width 0.17145)
		(layer "F.Cu")
		(net "DRIVE_B_12_ACT")
	)
	(segment
		(start 275.0312 -198.0692)
		(end 268.250416 -191.288416)
		(width 0.17145)
		(layer "F.Cu")
		(net "DRIVE_B_12_ACT")
	)
	(segment
		(start 282.816554 -197.714616)
		(end 282.718764 -197.714616)
		(width 0.17145)
		(layer "F.Cu")
		(net "DRIVE_B_12_ACT")
	)
	(segment
		(start 268.250416 -177.066448)
		(end 268.253464 -177.0634)
		(width 0.17145)
		(layer "F.Cu")
		(net "DRIVE_B_12_ACT")
	)
	(segment
		(start 282.36418 -198.0692)
		(end 275.0312 -198.0692)
		(width 0.17145)
		(layer "F.Cu")
		(net "DRIVE_B_12_ACT")
	)
	(segment
		(start 268.250416 -191.288416)
		(end 268.250416 -177.066448)
		(width 0.17145)
		(layer "F.Cu")
		(net "DRIVE_B_12_ACT")
	)
	(segment
		(start 14.912086 -97.416112)
		(end 14.912086 -95.680784)
		(width 0.17145)
		(layer "F.Cu")
		(net "DRIVE_B_12_ACT")
	)
	(segment
		(start 282.718764 -197.714616)
		(end 282.36418 -198.0692)
		(width 0.17145)
		(layer "F.Cu")
		(net "DRIVE_B_12_ACT")
	)
	(segment
		(start 283.23667 -197.2945)
		(end 282.816554 -197.714616)
		(width 0.17145)
		(layer "F.Cu")
		(net "DRIVE_B_12_ACT")
	)
	(via
		(at 14.912086 -94.575884)
		(size 0.5588)
		(drill 0.3048)
		(layers "F.Cu" "B.Cu")
		(net "DRIVE_B_12_ACT")
	)
	(via
		(at 14.912086 -95.680784)
		(size 0.6604)
		(drill 0.3302)
		(layers "F.Cu" "B.Cu")
		(net "DRIVE_B_12_ACT")
	)
	(via
		(at 200.144634 -118.394734)
		(size 0.5588)
		(drill 0.3048)
		(layers "F.Cu" "B.Cu")
		(net "DRIVE_B_12_ACT")
	)
	(via
		(at 268.253464 -177.0634)
		(size 0.5588)
		(drill 0.3048)
		(layers "F.Cu" "B.Cu")
		(net "DRIVE_B_12_ACT")
	)
	(segment
		(start 223.701102 -135.485378)
		(end 223.275144 -135.485378)
		(width 0.17145)
		(layer "B.Cu")
		(net "DRIVE_B_12_ACT")
	)
	(segment
		(start 223.275144 -135.485378)
		(end 223.27489 -135.485632)
		(width 0.17145)
		(layer "B.Cu")
		(net "DRIVE_B_12_ACT")
	)
	(segment
		(start 268.168374 -168.60774)
		(end 243.958872 -144.398238)
		(width 0.17145)
		(layer "B.Cu")
		(net "DRIVE_B_12_ACT")
	)
	(segment
		(start 235.689648 -144.398238)
		(end 226.776534 -135.485124)
		(width 0.17145)
		(layer "B.Cu")
		(net "DRIVE_B_12_ACT")
	)
	(segment
		(start 205.516226 -119.005096)
		(end 200.754996 -119.005096)
		(width 0.17145)
		(layer "B.Cu")
		(net "DRIVE_B_12_ACT")
	)
	(segment
		(start 200.754996 -119.005096)
		(end 200.144634 -118.394734)
		(width 0.17145)
		(layer "B.Cu")
		(net "DRIVE_B_12_ACT")
	)
	(segment
		(start 268.253464 -177.0634)
		(end 268.250416 -177.060352)
		(width 0.17145)
		(layer "B.Cu")
		(net "DRIVE_B_12_ACT")
	)
	(segment
		(start 243.958872 -144.398238)
		(end 235.689648 -144.398238)
		(width 0.17145)
		(layer "B.Cu")
		(net "DRIVE_B_12_ACT")
	)
	(segment
		(start 223.701356 -135.485124)
		(end 223.701102 -135.485378)
		(width 0.17145)
		(layer "B.Cu")
		(net "DRIVE_B_12_ACT")
	)
	(segment
		(start 268.250416 -177.060352)
		(end 268.250416 -173.073822)
		(width 0.17145)
		(layer "B.Cu")
		(net "DRIVE_B_12_ACT")
	)
	(segment
		(start 221.996762 -135.485632)
		(end 205.516226 -119.005096)
		(width 0.17145)
		(layer "B.Cu")
		(net "DRIVE_B_12_ACT")
	)
	(segment
		(start 268.170152 -172.993558)
		(end 268.170152 -172.988986)
		(width 0.17145)
		(layer "B.Cu")
		(net "DRIVE_B_12_ACT")
	)
	(segment
		(start 268.170152 -172.988986)
		(end 268.168374 -172.987208)
		(width 0.17145)
		(layer "B.Cu")
		(net "DRIVE_B_12_ACT")
	)
	(segment
		(start 268.250416 -173.073822)
		(end 268.170152 -172.993558)
		(width 0.17145)
		(layer "B.Cu")
		(net "DRIVE_B_12_ACT")
	)
	(segment
		(start 268.168374 -172.987208)
		(end 268.168374 -168.60774)
		(width 0.17145)
		(layer "B.Cu")
		(net "DRIVE_B_12_ACT")
	)
	(segment
		(start 226.776534 -135.485124)
		(end 223.701356 -135.485124)
		(width 0.17145)
		(layer "B.Cu")
		(net "DRIVE_B_12_ACT")
	)
	(segment
		(start 223.27489 -135.485632)
		(end 221.996762 -135.485632)
		(width 0.17145)
		(layer "B.Cu")
		(net "DRIVE_B_12_ACT")
	)
	(segment
		(start 183.48071 -114.21491)
		(end 195.2879 -114.21491)
		(width 0.14605)
		(layer "In2.Cu")
		(net "DRIVE_B_12_ACT")
	)
	(segment
		(start 58.919618 -103.081582)
		(end 69.680074 -103.081582)
		(width 0.14605)
		(layer "In2.Cu")
		(net "DRIVE_B_12_ACT")
	)
	(segment
		(start 71.3232 -104.724708)
		(end 173.990508 -104.724708)
		(width 0.14605)
		(layer "In2.Cu")
		(net "DRIVE_B_12_ACT")
	)
	(segment
		(start 173.990508 -104.724708)
		(end 183.48071 -114.21491)
		(width 0.14605)
		(layer "In2.Cu")
		(net "DRIVE_B_12_ACT")
	)
	(segment
		(start 69.680074 -103.081582)
		(end 71.3232 -104.724708)
		(width 0.14605)
		(layer "In2.Cu")
		(net "DRIVE_B_12_ACT")
	)
	(segment
		(start 54.253638 -98.415602)
		(end 58.919618 -103.081582)
		(width 0.14605)
		(layer "In2.Cu")
		(net "DRIVE_B_12_ACT")
	)
	(segment
		(start 199.467724 -118.394734)
		(end 200.144634 -118.394734)
		(width 0.14605)
		(layer "In2.Cu")
		(net "DRIVE_B_12_ACT")
	)
	(segment
		(start 195.2879 -114.21491)
		(end 199.467724 -118.394734)
		(width 0.14605)
		(layer "In2.Cu")
		(net "DRIVE_B_12_ACT")
	)
	(segment
		(start 14.912086 -94.575884)
		(end 18.751804 -98.415602)
		(width 0.14605)
		(layer "In2.Cu")
		(net "DRIVE_B_12_ACT")
	)
	(segment
		(start 18.751804 -98.415602)
		(end 54.253638 -98.415602)
		(width 0.14605)
		(layer "In2.Cu")
		(net "DRIVE_B_12_ACT")
	)
	(segment
		(start 464.2358 -238.8108)
		(end 469.519 -238.8108)
		(width 0.17145)
		(layer "F.Cu")
		(net "DRIVE_B_11_PWR")
	)
	(segment
		(start 443.813438 -227.634038)
		(end 450.1896 -234.0102)
		(width 0.17145)
		(layer "F.Cu")
		(net "DRIVE_B_11_PWR")
	)
	(segment
		(start 312.21172 -253.419102)
		(end 312.21172 -237.444026)
		(width 0.17145)
		(layer "F.Cu")
		(net "DRIVE_B_11_PWR")
	)
	(segment
		(start 236.202982 -227.340414)
		(end 236.202982 -228.642418)
		(width 0.17145)
		(layer "F.Cu")
		(net "DRIVE_B_11_PWR")
	)
	(segment
		(start 241.380264 -233.8197)
		(end 248.504964 -233.8197)
		(width 0.17145)
		(layer "F.Cu")
		(net "DRIVE_B_11_PWR")
	)
	(segment
		(start 275.610574 -260.92531)
		(end 304.705512 -260.92531)
		(width 0.17145)
		(layer "F.Cu")
		(net "DRIVE_B_11_PWR")
	)
	(segment
		(start 322.021708 -227.634038)
		(end 443.813438 -227.634038)
		(width 0.17145)
		(layer "F.Cu")
		(net "DRIVE_B_11_PWR")
	)
	(segment
		(start 459.4352 -234.0102)
		(end 464.2358 -238.8108)
		(width 0.17145)
		(layer "F.Cu")
		(net "DRIVE_B_11_PWR")
	)
	(segment
		(start 236.202982 -228.642418)
		(end 241.380264 -233.8197)
		(width 0.17145)
		(layer "F.Cu")
		(net "DRIVE_B_11_PWR")
	)
	(segment
		(start 234.427014 -225.564446)
		(end 236.202982 -227.340414)
		(width 0.17145)
		(layer "F.Cu")
		(net "DRIVE_B_11_PWR")
	)
	(segment
		(start 248.504964 -233.8197)
		(end 268.332712 -253.647448)
		(width 0.17145)
		(layer "F.Cu")
		(net "DRIVE_B_11_PWR")
	)
	(segment
		(start 469.519 -243.9035)
		(end 469.519 -243.078)
		(width 0.17145)
		(layer "F.Cu")
		(net "DRIVE_B_11_PWR")
	)
	(segment
		(start 304.705512 -260.92531)
		(end 312.21172 -253.419102)
		(width 0.17145)
		(layer "F.Cu")
		(net "DRIVE_B_11_PWR")
	)
	(segment
		(start 450.1896 -234.0102)
		(end 459.4352 -234.0102)
		(width 0.17145)
		(layer "F.Cu")
		(net "DRIVE_B_11_PWR")
	)
	(segment
		(start 228.83876 -225.564446)
		(end 234.427014 -225.564446)
		(width 0.17145)
		(layer "F.Cu")
		(net "DRIVE_B_11_PWR")
	)
	(segment
		(start 312.21172 -237.444026)
		(end 322.021708 -227.634038)
		(width 0.17145)
		(layer "F.Cu")
		(net "DRIVE_B_11_PWR")
	)
	(segment
		(start 227.87356 -223.612456)
		(end 227.87356 -224.599246)
		(width 0.17145)
		(layer "F.Cu")
		(net "DRIVE_B_11_PWR")
	)
	(segment
		(start 227.87356 -224.599246)
		(end 228.83876 -225.564446)
		(width 0.17145)
		(layer "F.Cu")
		(net "DRIVE_B_11_PWR")
	)
	(segment
		(start 268.332712 -253.647448)
		(end 275.610574 -260.92531)
		(width 0.17145)
		(layer "F.Cu")
		(net "DRIVE_B_11_PWR")
	)
	(via
		(at 469.519 -238.8108)
		(size 0.5588)
		(drill 0.3048)
		(layers "F.Cu" "B.Cu")
		(net "DRIVE_B_11_PWR")
	)
	(via
		(at 268.332712 -253.647448)
		(size 0.6604)
		(drill 0.3302)
		(layers "F.Cu" "B.Cu")
		(net "DRIVE_B_11_PWR")
	)
	(via
		(at 469.519 -243.078)
		(size 0.5588)
		(drill 0.3048)
		(layers "F.Cu" "B.Cu")
		(net "DRIVE_B_11_PWR")
	)
	(segment
		(start 469.519 -243.078)
		(end 469.519 -238.8108)
		(width 0.14605)
		(layer "In2.Cu")
		(net "DRIVE_B_11_PWR")
	)
	(segment
		(start 205.71587 -240.88471)
		(end 226.649788 -240.88471)
		(width 0.17145)
		(layer "F.Cu")
		(net "DRIVE_B_11_INS")
	)
	(segment
		(start 448.193922 -233.469434)
		(end 449.763388 -235.0389)
		(width 0.17145)
		(layer "F.Cu")
		(net "DRIVE_B_11_INS")
	)
	(segment
		(start 456.2729 -235.0389)
		(end 460.883 -239.649)
		(width 0.17145)
		(layer "F.Cu")
		(net "DRIVE_B_11_INS")
	)
	(segment
		(start 233.08437 -249.728736)
		(end 247.952514 -264.59688)
		(width 0.17145)
		(layer "F.Cu")
		(net "DRIVE_B_11_INS")
	)
	(segment
		(start 204.99578 -238.84382)
		(end 204.99578 -240.16462)
		(width 0.17145)
		(layer "F.Cu")
		(net "DRIVE_B_11_INS")
	)
	(segment
		(start 338.7344 -232.878122)
		(end 338.7344 -232.878376)
		(width 0.17145)
		(layer "F.Cu")
		(net "DRIVE_B_11_INS")
	)
	(segment
		(start 475.9198 -247.904)
		(end 475.9198 -246.321326)
		(width 0.17145)
		(layer "F.Cu")
		(net "DRIVE_B_11_INS")
	)
	(segment
		(start 315.427868 -254.56769)
		(end 315.427868 -238.815626)
		(width 0.17145)
		(layer "F.Cu")
		(net "DRIVE_B_11_INS")
	)
	(segment
		(start 247.952514 -264.59688)
		(end 305.398678 -264.59688)
		(width 0.17145)
		(layer "F.Cu")
		(net "DRIVE_B_11_INS")
	)
	(segment
		(start 305.398678 -264.59688)
		(end 315.427868 -254.56769)
		(width 0.17145)
		(layer "F.Cu")
		(net "DRIVE_B_11_INS")
	)
	(segment
		(start 204.99578 -240.16462)
		(end 205.71587 -240.88471)
		(width 0.17145)
		(layer "F.Cu")
		(net "DRIVE_B_11_INS")
	)
	(segment
		(start 475.9198 -246.321326)
		(end 474.901006 -245.302532)
		(width 0.17145)
		(layer "F.Cu")
		(net "DRIVE_B_11_INS")
	)
	(segment
		(start 472.764612 -239.649)
		(end 474.044772 -240.92916)
		(width 0.17145)
		(layer "F.Cu")
		(net "DRIVE_B_11_INS")
	)
	(segment
		(start 474.901006 -245.302532)
		(end 474.901006 -241.785394)
		(width 0.17145)
		(layer "F.Cu")
		(net "DRIVE_B_11_INS")
	)
	(segment
		(start 474.901006 -241.785394)
		(end 474.044772 -240.92916)
		(width 0.17145)
		(layer "F.Cu")
		(net "DRIVE_B_11_INS")
	)
	(segment
		(start 315.427868 -238.815626)
		(end 322.570348 -231.673146)
		(width 0.17145)
		(layer "F.Cu")
		(net "DRIVE_B_11_INS")
	)
	(segment
		(start 226.649788 -240.88471)
		(end 233.08437 -247.319292)
		(width 0.17145)
		(layer "F.Cu")
		(net "DRIVE_B_11_INS")
	)
	(segment
		(start 233.08437 -247.319292)
		(end 233.08437 -249.728736)
		(width 0.17145)
		(layer "F.Cu")
		(net "DRIVE_B_11_INS")
	)
	(segment
		(start 338.7344 -232.878376)
		(end 339.325458 -233.469434)
		(width 0.17145)
		(layer "F.Cu")
		(net "DRIVE_B_11_INS")
	)
	(segment
		(start 460.883 -239.649)
		(end 472.764612 -239.649)
		(width 0.17145)
		(layer "F.Cu")
		(net "DRIVE_B_11_INS")
	)
	(segment
		(start 474.345 -249.4788)
		(end 475.9198 -247.904)
		(width 0.17145)
		(layer "F.Cu")
		(net "DRIVE_B_11_INS")
	)
	(segment
		(start 337.529424 -231.673146)
		(end 338.7344 -232.878122)
		(width 0.17145)
		(layer "F.Cu")
		(net "DRIVE_B_11_INS")
	)
	(segment
		(start 449.763388 -235.0389)
		(end 456.2729 -235.0389)
		(width 0.17145)
		(layer "F.Cu")
		(net "DRIVE_B_11_INS")
	)
	(segment
		(start 322.570348 -231.673146)
		(end 337.529424 -231.673146)
		(width 0.17145)
		(layer "F.Cu")
		(net "DRIVE_B_11_INS")
	)
	(segment
		(start 339.325458 -233.469434)
		(end 448.193922 -233.469434)
		(width 0.17145)
		(layer "F.Cu")
		(net "DRIVE_B_11_INS")
	)
	(via
		(at 474.044772 -240.92916)
		(size 0.6604)
		(drill 0.3302)
		(layers "F.Cu" "B.Cu")
		(net "DRIVE_B_11_INS")
	)
	(segment
		(start 216.13368 -219.202)
		(end 216.13368 -217.965782)
		(width 0.17145)
		(layer "F.Cu")
		(net "DRIVE_B_11_FLT_LED")
	)
	(segment
		(start 216.133934 -217.965528)
		(end 216.133934 -214.827866)
		(width 0.17145)
		(layer "F.Cu")
		(net "DRIVE_B_11_FLT_LED")
	)
	(segment
		(start 226.142804 -178.95697)
		(end 226.142804 -205.561946)
		(width 0.17145)
		(layer "F.Cu")
		(net "DRIVE_B_11_FLT_LED")
	)
	(segment
		(start 470.638378 -217.413586)
		(end 470.638378 -215.7095)
		(width 0.17145)
		(layer "F.Cu")
		(net "DRIVE_B_11_FLT_LED")
	)
	(segment
		(start 467.271354 -218.92895)
		(end 464.112356 -215.769952)
		(width 0.17145)
		(layer "F.Cu")
		(net "DRIVE_B_11_FLT_LED")
	)
	(segment
		(start 216.133934 -214.827866)
		(end 217.2716 -213.6902)
		(width 0.17145)
		(layer "F.Cu")
		(net "DRIVE_B_11_FLT_LED")
	)
	(segment
		(start 220.391736 -211.313014)
		(end 222.138748 -209.566002)
		(width 0.17145)
		(layer "F.Cu")
		(net "DRIVE_B_11_FLT_LED")
	)
	(segment
		(start 216.54008 -219.6084)
		(end 216.13368 -219.202)
		(width 0.17145)
		(layer "F.Cu")
		(net "DRIVE_B_11_FLT_LED")
	)
	(segment
		(start 226.142804 -205.561946)
		(end 222.138748 -209.566002)
		(width 0.17145)
		(layer "F.Cu")
		(net "DRIVE_B_11_FLT_LED")
	)
	(segment
		(start 318.416178 -164.230558)
		(end 240.869216 -164.230558)
		(width 0.17145)
		(layer "F.Cu")
		(net "DRIVE_B_11_FLT_LED")
	)
	(segment
		(start 219.555314 -213.6902)
		(end 220.391736 -212.853778)
		(width 0.17145)
		(layer "F.Cu")
		(net "DRIVE_B_11_FLT_LED")
	)
	(segment
		(start 220.391736 -212.853778)
		(end 220.391736 -211.313014)
		(width 0.17145)
		(layer "F.Cu")
		(net "DRIVE_B_11_FLT_LED")
	)
	(segment
		(start 470.638378 -217.413586)
		(end 470.638378 -218.455494)
		(width 0.17145)
		(layer "F.Cu")
		(net "DRIVE_B_11_FLT_LED")
	)
	(segment
		(start 323.04482 -168.8592)
		(end 318.416178 -164.230558)
		(width 0.17145)
		(layer "F.Cu")
		(net "DRIVE_B_11_FLT_LED")
	)
	(segment
		(start 217.2716 -213.6902)
		(end 219.555314 -213.6902)
		(width 0.17145)
		(layer "F.Cu")
		(net "DRIVE_B_11_FLT_LED")
	)
	(segment
		(start 464.112356 -215.769952)
		(end 464.112356 -175.025304)
		(width 0.17145)
		(layer "F.Cu")
		(net "DRIVE_B_11_FLT_LED")
	)
	(segment
		(start 216.13368 -217.965782)
		(end 216.133934 -217.965528)
		(width 0.17145)
		(layer "F.Cu")
		(net "DRIVE_B_11_FLT_LED")
	)
	(segment
		(start 464.112356 -175.025304)
		(end 457.946252 -168.8592)
		(width 0.17145)
		(layer "F.Cu")
		(net "DRIVE_B_11_FLT_LED")
	)
	(segment
		(start 218.5924 -219.6084)
		(end 216.54008 -219.6084)
		(width 0.17145)
		(layer "F.Cu")
		(net "DRIVE_B_11_FLT_LED")
	)
	(segment
		(start 240.869216 -164.230558)
		(end 226.142804 -178.95697)
		(width 0.17145)
		(layer "F.Cu")
		(net "DRIVE_B_11_FLT_LED")
	)
	(segment
		(start 457.946252 -168.8592)
		(end 323.04482 -168.8592)
		(width 0.17145)
		(layer "F.Cu")
		(net "DRIVE_B_11_FLT_LED")
	)
	(segment
		(start 470.164922 -218.92895)
		(end 467.271354 -218.92895)
		(width 0.17145)
		(layer "F.Cu")
		(net "DRIVE_B_11_FLT_LED")
	)
	(segment
		(start 470.638378 -218.455494)
		(end 470.164922 -218.92895)
		(width 0.17145)
		(layer "F.Cu")
		(net "DRIVE_B_11_FLT_LED")
	)
	(via
		(at 222.138748 -209.566002)
		(size 0.6604)
		(drill 0.3302)
		(layers "F.Cu" "B.Cu")
		(net "DRIVE_B_11_FLT_LED")
	)
	(segment
		(start 466.896196 -213.876128)
		(end 466.896196 -212.390228)
		(width 0.17145)
		(layer "F.Cu")
		(net "DRIVE_B_11_ACT")
	)
	(segment
		(start 466.896196 -212.390228)
		(end 466.896196 -210.6549)
		(width 0.17145)
		(layer "F.Cu")
		(net "DRIVE_B_11_ACT")
	)
	(segment
		(start 466.896196 -210.6549)
		(end 466.896196 -209.55)
		(width 0.17145)
		(layer "F.Cu")
		(net "DRIVE_B_11_ACT")
	)
	(segment
		(start 282.83662 -199.094344)
		(end 283.472128 -199.729852)
		(width 0.17145)
		(layer "F.Cu")
		(net "DRIVE_B_11_ACT")
	)
	(segment
		(start 300.123352 -199.729852)
		(end 301.41926 -201.02576)
		(width 0.17145)
		(layer "F.Cu")
		(net "DRIVE_B_11_ACT")
	)
	(segment
		(start 283.472128 -199.729852)
		(end 300.123352 -199.729852)
		(width 0.17145)
		(layer "F.Cu")
		(net "DRIVE_B_11_ACT")
	)
	(via
		(at 301.41926 -201.02576)
		(size 0.5588)
		(drill 0.3048)
		(layers "F.Cu" "B.Cu")
		(net "DRIVE_B_11_ACT")
	)
	(via
		(at 466.896196 -209.55)
		(size 0.5588)
		(drill 0.3048)
		(layers "F.Cu" "B.Cu")
		(net "DRIVE_B_11_ACT")
	)
	(via
		(at 466.896196 -210.6549)
		(size 0.6604)
		(drill 0.3302)
		(layers "F.Cu" "B.Cu")
		(net "DRIVE_B_11_ACT")
	)
	(segment
		(start 463.93735 -212.508846)
		(end 466.896196 -209.55)
		(width 0.14605)
		(layer "In2.Cu")
		(net "DRIVE_B_11_ACT")
	)
	(segment
		(start 301.41926 -201.02576)
		(end 340.16696 -201.02576)
		(width 0.14605)
		(layer "In2.Cu")
		(net "DRIVE_B_11_ACT")
	)
	(segment
		(start 427.688248 -205.2828)
		(end 434.914294 -212.508846)
		(width 0.14605)
		(layer "In2.Cu")
		(net "DRIVE_B_11_ACT")
	)
	(segment
		(start 344.424 -205.2828)
		(end 427.688248 -205.2828)
		(width 0.14605)
		(layer "In2.Cu")
		(net "DRIVE_B_11_ACT")
	)
	(segment
		(start 340.16696 -201.02576)
		(end 344.424 -205.2828)
		(width 0.14605)
		(layer "In2.Cu")
		(net "DRIVE_B_11_ACT")
	)
	(segment
		(start 434.914294 -212.508846)
		(end 463.93735 -212.508846)
		(width 0.14605)
		(layer "In2.Cu")
		(net "DRIVE_B_11_ACT")
	)
	(segment
		(start 228.625654 -226.078796)
		(end 234.213908 -226.078796)
		(width 0.17145)
		(layer "F.Cu")
		(net "DRIVE_B_10_PWR")
	)
	(segment
		(start 270.152114 -256.271776)
		(end 275.319998 -261.43966)
		(width 0.17145)
		(layer "F.Cu")
		(net "DRIVE_B_10_PWR")
	)
	(segment
		(start 312.72607 -253.632208)
		(end 312.72607 -237.657132)
		(width 0.17145)
		(layer "F.Cu")
		(net "DRIVE_B_10_PWR")
	)
	(segment
		(start 227.22332 -223.612456)
		(end 227.22332 -224.676462)
		(width 0.17145)
		(layer "F.Cu")
		(net "DRIVE_B_10_PWR")
	)
	(segment
		(start 235.688632 -227.55352)
		(end 235.688632 -228.855524)
		(width 0.17145)
		(layer "F.Cu")
		(net "DRIVE_B_10_PWR")
	)
	(segment
		(start 275.319998 -261.43966)
		(end 304.918618 -261.43966)
		(width 0.17145)
		(layer "F.Cu")
		(net "DRIVE_B_10_PWR")
	)
	(segment
		(start 458.06995 -234.52455)
		(end 462.4578 -238.9124)
		(width 0.17145)
		(layer "F.Cu")
		(net "DRIVE_B_10_PWR")
	)
	(segment
		(start 322.153534 -228.229668)
		(end 443.681612 -228.229668)
		(width 0.17145)
		(layer "F.Cu")
		(net "DRIVE_B_10_PWR")
	)
	(segment
		(start 312.72607 -237.657132)
		(end 322.153534 -228.229668)
		(width 0.17145)
		(layer "F.Cu")
		(net "DRIVE_B_10_PWR")
	)
	(segment
		(start 234.213908 -226.078796)
		(end 235.688632 -227.55352)
		(width 0.17145)
		(layer "F.Cu")
		(net "DRIVE_B_10_PWR")
	)
	(segment
		(start 235.688632 -228.855524)
		(end 241.167158 -234.33405)
		(width 0.17145)
		(layer "F.Cu")
		(net "DRIVE_B_10_PWR")
	)
	(segment
		(start 449.976494 -234.52455)
		(end 458.06995 -234.52455)
		(width 0.17145)
		(layer "F.Cu")
		(net "DRIVE_B_10_PWR")
	)
	(segment
		(start 227.22332 -224.676462)
		(end 228.625654 -226.078796)
		(width 0.17145)
		(layer "F.Cu")
		(net "DRIVE_B_10_PWR")
	)
	(segment
		(start 241.167158 -234.33405)
		(end 248.214388 -234.33405)
		(width 0.17145)
		(layer "F.Cu")
		(net "DRIVE_B_10_PWR")
	)
	(segment
		(start 461.899 -243.1415)
		(end 462.788 -243.1415)
		(width 0.17145)
		(layer "F.Cu")
		(net "DRIVE_B_10_PWR")
	)
	(segment
		(start 304.918618 -261.43966)
		(end 312.72607 -253.632208)
		(width 0.17145)
		(layer "F.Cu")
		(net "DRIVE_B_10_PWR")
	)
	(segment
		(start 443.681612 -228.229668)
		(end 449.976494 -234.52455)
		(width 0.17145)
		(layer "F.Cu")
		(net "DRIVE_B_10_PWR")
	)
	(segment
		(start 248.214388 -234.33405)
		(end 270.152114 -256.271776)
		(width 0.17145)
		(layer "F.Cu")
		(net "DRIVE_B_10_PWR")
	)
	(via
		(at 462.4578 -238.9124)
		(size 0.5588)
		(drill 0.3048)
		(layers "F.Cu" "B.Cu")
		(net "DRIVE_B_10_PWR")
	)
	(via
		(at 462.788 -243.1415)
		(size 0.5588)
		(drill 0.3048)
		(layers "F.Cu" "B.Cu")
		(net "DRIVE_B_10_PWR")
	)
	(via
		(at 270.152114 -256.271776)
		(size 0.6604)
		(drill 0.3302)
		(layers "F.Cu" "B.Cu")
		(net "DRIVE_B_10_PWR")
	)
	(segment
		(start 462.4578 -242.8113)
		(end 462.4578 -238.9124)
		(width 0.14605)
		(layer "In2.Cu")
		(net "DRIVE_B_10_PWR")
	)
	(segment
		(start 462.788 -243.1415)
		(end 462.4578 -242.8113)
		(width 0.14605)
		(layer "In2.Cu")
		(net "DRIVE_B_10_PWR")
	)
	(segment
		(start 440.817 -249.7074)
		(end 440.817 -236.417866)
		(width 0.17145)
		(layer "F.Cu")
		(net "DRIVE_B_10_INS")
	)
	(segment
		(start 305.611784 -265.11123)
		(end 315.942218 -254.780796)
		(width 0.17145)
		(layer "F.Cu")
		(net "DRIVE_B_10_INS")
	)
	(segment
		(start 226.436682 -241.39906)
		(end 232.57002 -247.532398)
		(width 0.17145)
		(layer "F.Cu")
		(net "DRIVE_B_10_INS")
	)
	(segment
		(start 438.382918 -233.983784)
		(end 438.599834 -234.2007)
		(width 0.17145)
		(layer "F.Cu")
		(net "DRIVE_B_10_INS")
	)
	(segment
		(start 339.112352 -233.983784)
		(end 438.382918 -233.983784)
		(width 0.17145)
		(layer "F.Cu")
		(net "DRIVE_B_10_INS")
	)
	(segment
		(start 204.34554 -240.434114)
		(end 205.310486 -241.39906)
		(width 0.17145)
		(layer "F.Cu")
		(net "DRIVE_B_10_INS")
	)
	(segment
		(start 444.3222 -253.2126)
		(end 440.817 -249.7074)
		(width 0.17145)
		(layer "F.Cu")
		(net "DRIVE_B_10_INS")
	)
	(segment
		(start 315.942218 -254.780796)
		(end 315.942218 -239.028732)
		(width 0.17145)
		(layer "F.Cu")
		(net "DRIVE_B_10_INS")
	)
	(segment
		(start 444.3222 -260.5786)
		(end 444.3222 -253.2126)
		(width 0.17145)
		(layer "F.Cu")
		(net "DRIVE_B_10_INS")
	)
	(segment
		(start 204.34554 -238.84382)
		(end 204.34554 -240.434114)
		(width 0.17145)
		(layer "F.Cu")
		(net "DRIVE_B_10_INS")
	)
	(segment
		(start 315.942218 -239.028732)
		(end 322.7832 -232.18775)
		(width 0.17145)
		(layer "F.Cu")
		(net "DRIVE_B_10_INS")
	)
	(segment
		(start 232.57002 -249.941842)
		(end 247.739408 -265.11123)
		(width 0.17145)
		(layer "F.Cu")
		(net "DRIVE_B_10_INS")
	)
	(segment
		(start 247.739408 -265.11123)
		(end 305.611784 -265.11123)
		(width 0.17145)
		(layer "F.Cu")
		(net "DRIVE_B_10_INS")
	)
	(segment
		(start 322.7832 -232.18775)
		(end 337.316318 -232.18775)
		(width 0.17145)
		(layer "F.Cu")
		(net "DRIVE_B_10_INS")
	)
	(segment
		(start 232.57002 -247.532398)
		(end 232.57002 -249.941842)
		(width 0.17145)
		(layer "F.Cu")
		(net "DRIVE_B_10_INS")
	)
	(segment
		(start 440.817 -236.417866)
		(end 438.599834 -234.2007)
		(width 0.17145)
		(layer "F.Cu")
		(net "DRIVE_B_10_INS")
	)
	(segment
		(start 337.316318 -232.18775)
		(end 339.112352 -233.983784)
		(width 0.17145)
		(layer "F.Cu")
		(net "DRIVE_B_10_INS")
	)
	(segment
		(start 205.310486 -241.39906)
		(end 226.436682 -241.39906)
		(width 0.17145)
		(layer "F.Cu")
		(net "DRIVE_B_10_INS")
	)
	(via
		(at 438.599834 -234.2007)
		(size 0.6604)
		(drill 0.3302)
		(layers "F.Cu" "B.Cu")
		(net "DRIVE_B_10_INS")
	)
	(segment
		(start 224.4725 -208.8515)
		(end 226.657154 -206.666846)
		(width 0.17145)
		(layer "F.Cu")
		(net "DRIVE_B_10_FLT_LED")
	)
	(segment
		(start 322.447158 -169.37355)
		(end 422.50995 -169.37355)
		(width 0.17145)
		(layer "F.Cu")
		(net "DRIVE_B_10_FLT_LED")
	)
	(segment
		(start 226.657154 -179.170076)
		(end 241.082322 -164.744908)
		(width 0.17145)
		(layer "F.Cu")
		(net "DRIVE_B_10_FLT_LED")
	)
	(segment
		(start 438.79135 -218.544902)
		(end 439.088276 -218.247976)
		(width 0.17145)
		(layer "F.Cu")
		(net "DRIVE_B_10_FLT_LED")
	)
	(segment
		(start 434.91912 -218.544902)
		(end 438.79135 -218.544902)
		(width 0.17145)
		(layer "F.Cu")
		(net "DRIVE_B_10_FLT_LED")
	)
	(segment
		(start 226.657154 -206.666846)
		(end 226.657154 -179.170076)
		(width 0.17145)
		(layer "F.Cu")
		(net "DRIVE_B_10_FLT_LED")
	)
	(segment
		(start 439.088276 -217.413586)
		(end 439.088276 -215.7095)
		(width 0.17145)
		(layer "F.Cu")
		(net "DRIVE_B_10_FLT_LED")
	)
	(segment
		(start 218.5924 -218.95816)
		(end 216.984072 -218.95816)
		(width 0.17145)
		(layer "F.Cu")
		(net "DRIVE_B_10_FLT_LED")
	)
	(segment
		(start 317.818516 -164.744908)
		(end 322.447158 -169.37355)
		(width 0.17145)
		(layer "F.Cu")
		(net "DRIVE_B_10_FLT_LED")
	)
	(segment
		(start 422.50995 -169.37355)
		(end 424.7388 -171.6024)
		(width 0.17145)
		(layer "F.Cu")
		(net "DRIVE_B_10_FLT_LED")
	)
	(segment
		(start 439.088276 -218.247976)
		(end 439.088276 -217.413586)
		(width 0.17145)
		(layer "F.Cu")
		(net "DRIVE_B_10_FLT_LED")
	)
	(segment
		(start 220.906086 -213.066884)
		(end 220.906086 -212.417914)
		(width 0.17145)
		(layer "F.Cu")
		(net "DRIVE_B_10_FLT_LED")
	)
	(segment
		(start 220.906086 -212.417914)
		(end 224.4725 -208.8515)
		(width 0.17145)
		(layer "F.Cu")
		(net "DRIVE_B_10_FLT_LED")
	)
	(segment
		(start 219.76842 -214.20455)
		(end 220.906086 -213.066884)
		(width 0.17145)
		(layer "F.Cu")
		(net "DRIVE_B_10_FLT_LED")
	)
	(segment
		(start 217.721688 -214.20455)
		(end 219.76842 -214.20455)
		(width 0.17145)
		(layer "F.Cu")
		(net "DRIVE_B_10_FLT_LED")
	)
	(segment
		(start 216.984072 -218.95816)
		(end 216.648284 -218.622372)
		(width 0.17145)
		(layer "F.Cu")
		(net "DRIVE_B_10_FLT_LED")
	)
	(segment
		(start 216.648284 -215.277954)
		(end 217.721688 -214.20455)
		(width 0.17145)
		(layer "F.Cu")
		(net "DRIVE_B_10_FLT_LED")
	)
	(segment
		(start 424.7388 -171.6024)
		(end 424.7388 -208.364582)
		(width 0.17145)
		(layer "F.Cu")
		(net "DRIVE_B_10_FLT_LED")
	)
	(segment
		(start 216.648284 -218.622372)
		(end 216.648284 -215.277954)
		(width 0.17145)
		(layer "F.Cu")
		(net "DRIVE_B_10_FLT_LED")
	)
	(segment
		(start 424.7388 -208.364582)
		(end 434.91912 -218.544902)
		(width 0.17145)
		(layer "F.Cu")
		(net "DRIVE_B_10_FLT_LED")
	)
	(segment
		(start 241.082322 -164.744908)
		(end 317.818516 -164.744908)
		(width 0.17145)
		(layer "F.Cu")
		(net "DRIVE_B_10_FLT_LED")
	)
	(via
		(at 224.4725 -208.8515)
		(size 0.6604)
		(drill 0.3302)
		(layers "F.Cu" "B.Cu")
		(net "DRIVE_B_10_FLT_LED")
	)
	(segment
		(start 435.346094 -212.390228)
		(end 435.346094 -210.6549)
		(width 0.17145)
		(layer "F.Cu")
		(net "DRIVE_B_10_ACT")
	)
	(segment
		(start 435.346094 -213.876128)
		(end 435.346094 -212.390228)
		(width 0.17145)
		(layer "F.Cu")
		(net "DRIVE_B_10_ACT")
	)
	(segment
		(start 284.236668 -199.094344)
		(end 285.005272 -198.32574)
		(width 0.17145)
		(layer "F.Cu")
		(net "DRIVE_B_10_ACT")
	)
	(segment
		(start 285.005272 -198.32574)
		(end 301.39132 -198.32574)
		(width 0.17145)
		(layer "F.Cu")
		(net "DRIVE_B_10_ACT")
	)
	(segment
		(start 435.346094 -210.6549)
		(end 435.346094 -209.55)
		(width 0.17145)
		(layer "F.Cu")
		(net "DRIVE_B_10_ACT")
	)
	(segment
		(start 301.39132 -198.32574)
		(end 302.51273 -197.20433)
		(width 0.17145)
		(layer "F.Cu")
		(net "DRIVE_B_10_ACT")
	)
	(via
		(at 302.51273 -197.20433)
		(size 0.5588)
		(drill 0.3048)
		(layers "F.Cu" "B.Cu")
		(net "DRIVE_B_10_ACT")
	)
	(via
		(at 435.346094 -209.55)
		(size 0.5588)
		(drill 0.3048)
		(layers "F.Cu" "B.Cu")
		(net "DRIVE_B_10_ACT")
	)
	(via
		(at 435.346094 -210.6549)
		(size 0.6604)
		(drill 0.3302)
		(layers "F.Cu" "B.Cu")
		(net "DRIVE_B_10_ACT")
	)
	(segment
		(start 344.46718 -198.92518)
		(end 348.3102 -202.7682)
		(width 0.14605)
		(layer "In2.Cu")
		(net "DRIVE_B_10_ACT")
	)
	(segment
		(start 304.23358 -198.92518)
		(end 344.46718 -198.92518)
		(width 0.14605)
		(layer "In2.Cu")
		(net "DRIVE_B_10_ACT")
	)
	(segment
		(start 302.51273 -197.20433)
		(end 304.23358 -198.92518)
		(width 0.14605)
		(layer "In2.Cu")
		(net "DRIVE_B_10_ACT")
	)
	(segment
		(start 428.564294 -202.7682)
		(end 435.346094 -209.55)
		(width 0.14605)
		(layer "In2.Cu")
		(net "DRIVE_B_10_ACT")
	)
	(segment
		(start 348.3102 -202.7682)
		(end 428.564294 -202.7682)
		(width 0.14605)
		(layer "In2.Cu")
		(net "DRIVE_B_10_ACT")
	)
	(segment
		(start 206.25054 -230.95458)
		(end 203.906628 -230.95458)
		(width 0.17145)
		(layer "F.Cu")
		(net "DRIVE_B_1_PWR")
	)
	(segment
		(start 152.080976 -231.0892)
		(end 149.835616 -228.84384)
		(width 0.17145)
		(layer "F.Cu")
		(net "DRIVE_B_1_PWR")
	)
	(segment
		(start 203.906628 -230.95458)
		(end 203.772008 -231.0892)
		(width 0.17145)
		(layer "F.Cu")
		(net "DRIVE_B_1_PWR")
	)
	(segment
		(start 230.47452 -229.251256)
		(end 230.47452 -231.039416)
		(width 0.17145)
		(layer "F.Cu")
		(net "DRIVE_B_1_PWR")
	)
	(segment
		(start 212.98154 -230.954834)
		(end 206.250794 -230.954834)
		(width 0.17145)
		(layer "F.Cu")
		(net "DRIVE_B_1_PWR")
	)
	(segment
		(start 215.982296 -233.95559)
		(end 214.61476 -232.588054)
		(width 0.17145)
		(layer "F.Cu")
		(net "DRIVE_B_1_PWR")
	)
	(segment
		(start 203.772008 -231.0892)
		(end 152.080976 -231.0892)
		(width 0.17145)
		(layer "F.Cu")
		(net "DRIVE_B_1_PWR")
	)
	(segment
		(start 206.250794 -230.954834)
		(end 206.25054 -230.95458)
		(width 0.17145)
		(layer "F.Cu")
		(net "DRIVE_B_1_PWR")
	)
	(segment
		(start 214.61476 -232.588054)
		(end 212.98154 -230.954834)
		(width 0.17145)
		(layer "F.Cu")
		(net "DRIVE_B_1_PWR")
	)
	(segment
		(start 230.47452 -231.039416)
		(end 227.558346 -233.95559)
		(width 0.17145)
		(layer "F.Cu")
		(net "DRIVE_B_1_PWR")
	)
	(segment
		(start 227.558346 -233.95559)
		(end 215.982296 -233.95559)
		(width 0.17145)
		(layer "F.Cu")
		(net "DRIVE_B_1_PWR")
	)
	(segment
		(start 55.3974 -246.3038)
		(end 54.4449 -246.3038)
		(width 0.17145)
		(layer "F.Cu")
		(net "DRIVE_B_1_PWR")
	)
	(via
		(at 55.3974 -246.3038)
		(size 0.5588)
		(drill 0.3048)
		(layers "F.Cu" "B.Cu")
		(net "DRIVE_B_1_PWR")
	)
	(via
		(at 149.835616 -228.84384)
		(size 0.5588)
		(drill 0.3048)
		(layers "F.Cu" "B.Cu")
		(net "DRIVE_B_1_PWR")
	)
	(via
		(at 214.61476 -232.588054)
		(size 0.6604)
		(drill 0.3302)
		(layers "F.Cu" "B.Cu")
		(net "DRIVE_B_1_PWR")
	)
	(segment
		(start 55.3974 -246.3038)
		(end 55.3974 -245.991888)
		(width 0.14605)
		(layer "In2.Cu")
		(net "DRIVE_B_1_PWR")
	)
	(segment
		(start 55.3974 -245.991888)
		(end 65.297304 -236.091984)
		(width 0.14605)
		(layer "In2.Cu")
		(net "DRIVE_B_1_PWR")
	)
	(segment
		(start 65.297304 -236.091984)
		(end 142.587472 -236.091984)
		(width 0.14605)
		(layer "In2.Cu")
		(net "DRIVE_B_1_PWR")
	)
	(segment
		(start 142.587472 -236.091984)
		(end 149.835616 -228.84384)
		(width 0.14605)
		(layer "In2.Cu")
		(net "DRIVE_B_1_PWR")
	)
	(segment
		(start 206.83982 -273.12239)
		(end 206.83982 -260.695694)
		(width 0.17145)
		(layer "F.Cu")
		(net "DRIVE_B_1_INS")
	)
	(segment
		(start 207.59674 -247.415812)
		(end 206.83982 -248.172732)
		(width 0.17145)
		(layer "F.Cu")
		(net "DRIVE_B_1_INS")
	)
	(segment
		(start 207.59674 -244.48262)
		(end 207.59674 -247.415812)
		(width 0.17145)
		(layer "F.Cu")
		(net "DRIVE_B_1_INS")
	)
	(segment
		(start 69.315584 -285.896304)
		(end 194.065906 -285.896304)
		(width 0.17145)
		(layer "F.Cu")
		(net "DRIVE_B_1_INS")
	)
	(segment
		(start 68.34759 -266.54379)
		(end 68.34759 -284.92831)
		(width 0.17145)
		(layer "F.Cu")
		(net "DRIVE_B_1_INS")
	)
	(segment
		(start 68.34759 -284.92831)
		(end 69.315584 -285.896304)
		(width 0.17145)
		(layer "F.Cu")
		(net "DRIVE_B_1_INS")
	)
	(segment
		(start 194.065906 -285.896304)
		(end 206.83982 -273.12239)
		(width 0.17145)
		(layer "F.Cu")
		(net "DRIVE_B_1_INS")
	)
	(segment
		(start 206.83982 -248.172732)
		(end 206.83982 -260.695694)
		(width 0.17145)
		(layer "F.Cu")
		(net "DRIVE_B_1_INS")
	)
	(segment
		(start 67.8688 -266.065)
		(end 68.34759 -266.54379)
		(width 0.17145)
		(layer "F.Cu")
		(net "DRIVE_B_1_INS")
	)
	(via
		(at 206.83982 -260.695694)
		(size 0.6604)
		(drill 0.3302)
		(layers "F.Cu" "B.Cu")
		(net "DRIVE_B_1_INS")
	)
	(segment
		(start 200.017888 -222.157798)
		(end 199.53224 -222.643446)
		(width 0.17145)
		(layer "F.Cu")
		(net "DRIVE_B_1_FLT_LED")
	)
	(segment
		(start 50.714402 -218.961462)
		(end 47.306992 -218.961462)
		(width 0.17145)
		(layer "F.Cu")
		(net "DRIVE_B_1_FLT_LED")
	)
	(segment
		(start 209.871564 -222.157798)
		(end 200.017888 -222.157798)
		(width 0.17145)
		(layer "F.Cu")
		(net "DRIVE_B_1_FLT_LED")
	)
	(segment
		(start 47.306992 -218.961462)
		(end 46.78045 -218.43492)
		(width 0.17145)
		(layer "F.Cu")
		(net "DRIVE_B_1_FLT_LED")
	)
	(segment
		(start 55.117492 -223.364552)
		(end 50.714402 -218.961462)
		(width 0.17145)
		(layer "F.Cu")
		(net "DRIVE_B_1_FLT_LED")
	)
	(segment
		(start 46.78045 -218.43492)
		(end 46.78045 -217.337386)
		(width 0.17145)
		(layer "F.Cu")
		(net "DRIVE_B_1_FLT_LED")
	)
	(segment
		(start 212.9536 -222.20936)
		(end 209.923126 -222.20936)
		(width 0.17145)
		(layer "F.Cu")
		(net "DRIVE_B_1_FLT_LED")
	)
	(segment
		(start 46.78045 -217.337386)
		(end 46.78045 -215.7095)
		(width 0.17145)
		(layer "F.Cu")
		(net "DRIVE_B_1_FLT_LED")
	)
	(segment
		(start 199.53224 -222.643446)
		(end 198.811134 -223.364552)
		(width 0.17145)
		(layer "F.Cu")
		(net "DRIVE_B_1_FLT_LED")
	)
	(segment
		(start 209.923126 -222.20936)
		(end 209.871564 -222.157798)
		(width 0.17145)
		(layer "F.Cu")
		(net "DRIVE_B_1_FLT_LED")
	)
	(segment
		(start 198.811134 -223.364552)
		(end 55.117492 -223.364552)
		(width 0.17145)
		(layer "F.Cu")
		(net "DRIVE_B_1_FLT_LED")
	)
	(via
		(at 199.53224 -222.643446)
		(size 0.6604)
		(drill 0.3302)
		(layers "F.Cu" "B.Cu")
		(net "DRIVE_B_1_FLT_LED")
	)
	(segment
		(start 42.631868 -212.606128)
		(end 43.800776 -212.606128)
		(width 0.17145)
		(layer "F.Cu")
		(net "DRIVE_B_1_ACT")
	)
	(segment
		(start 243.476272 -205.035404)
		(end 242.544092 -205.967584)
		(width 0.17145)
		(layer "F.Cu")
		(net "DRIVE_B_1_ACT")
	)
	(segment
		(start 44.083732 -212.323172)
		(end 44.083732 -211.624164)
		(width 0.17145)
		(layer "F.Cu")
		(net "DRIVE_B_1_ACT")
	)
	(segment
		(start 44.083732 -211.624164)
		(end 43.038268 -210.5787)
		(width 0.17145)
		(layer "F.Cu")
		(net "DRIVE_B_1_ACT")
	)
	(segment
		(start 255.719834 -205.977744)
		(end 254.777494 -205.035404)
		(width 0.17145)
		(layer "F.Cu")
		(net "DRIVE_B_1_ACT")
	)
	(segment
		(start 235.147866 -206.993998)
		(end 234.521248 -206.993998)
		(width 0.17145)
		(layer "F.Cu")
		(net "DRIVE_B_1_ACT")
	)
	(segment
		(start 281.836622 -208.09458)
		(end 281.199336 -207.457294)
		(width 0.17145)
		(layer "F.Cu")
		(net "DRIVE_B_1_ACT")
	)
	(segment
		(start 254.777494 -205.035404)
		(end 243.476272 -205.035404)
		(width 0.17145)
		(layer "F.Cu")
		(net "DRIVE_B_1_ACT")
	)
	(segment
		(start 234.521248 -206.993998)
		(end 233.945938 -206.418688)
		(width 0.17145)
		(layer "F.Cu")
		(net "DRIVE_B_1_ACT")
	)
	(segment
		(start 236.17428 -205.967584)
		(end 235.147866 -206.993998)
		(width 0.17145)
		(layer "F.Cu")
		(net "DRIVE_B_1_ACT")
	)
	(segment
		(start 43.800776 -212.606128)
		(end 44.083732 -212.323172)
		(width 0.17145)
		(layer "F.Cu")
		(net "DRIVE_B_1_ACT")
	)
	(segment
		(start 281.199336 -207.457294)
		(end 275.244814 -207.457294)
		(width 0.17145)
		(layer "F.Cu")
		(net "DRIVE_B_1_ACT")
	)
	(segment
		(start 242.544092 -205.967584)
		(end 236.17428 -205.967584)
		(width 0.17145)
		(layer "F.Cu")
		(net "DRIVE_B_1_ACT")
	)
	(segment
		(start 275.244814 -207.457294)
		(end 273.765264 -205.977744)
		(width 0.17145)
		(layer "F.Cu")
		(net "DRIVE_B_1_ACT")
	)
	(segment
		(start 43.038268 -210.5787)
		(end 43.038268 -209.4738)
		(width 0.17145)
		(layer "F.Cu")
		(net "DRIVE_B_1_ACT")
	)
	(segment
		(start 273.765264 -205.977744)
		(end 255.719834 -205.977744)
		(width 0.17145)
		(layer "F.Cu")
		(net "DRIVE_B_1_ACT")
	)
	(segment
		(start 233.945938 -206.418688)
		(end 233.945938 -206.111602)
		(width 0.17145)
		(layer "F.Cu")
		(net "DRIVE_B_1_ACT")
	)
	(via
		(at 233.945938 -206.111602)
		(size 0.5588)
		(drill 0.3048)
		(layers "F.Cu" "B.Cu")
		(net "DRIVE_B_1_ACT")
	)
	(via
		(at 43.038268 -210.5787)
		(size 0.6604)
		(drill 0.3302)
		(layers "F.Cu" "B.Cu")
		(net "DRIVE_B_1_ACT")
	)
	(via
		(at 43.038268 -209.4738)
		(size 0.5588)
		(drill 0.3048)
		(layers "F.Cu" "B.Cu")
		(net "DRIVE_B_1_ACT")
	)
	(segment
		(start 228.374448 -211.431632)
		(end 207.897222 -211.431632)
		(width 0.14605)
		(layer "In5.Cu")
		(net "DRIVE_B_1_ACT")
	)
	(segment
		(start 50.346356 -219.129356)
		(end 43.038268 -211.821268)
		(width 0.14605)
		(layer "In5.Cu")
		(net "DRIVE_B_1_ACT")
	)
	(segment
		(start 200.199498 -219.129356)
		(end 50.346356 -219.129356)
		(width 0.14605)
		(layer "In5.Cu")
		(net "DRIVE_B_1_ACT")
	)
	(segment
		(start 207.897222 -211.431632)
		(end 200.199498 -219.129356)
		(width 0.14605)
		(layer "In5.Cu")
		(net "DRIVE_B_1_ACT")
	)
	(segment
		(start 233.945938 -206.111602)
		(end 233.694478 -206.111602)
		(width 0.14605)
		(layer "In5.Cu")
		(net "DRIVE_B_1_ACT")
	)
	(segment
		(start 43.038268 -211.821268)
		(end 43.038268 -209.4738)
		(width 0.14605)
		(layer "In5.Cu")
		(net "DRIVE_B_1_ACT")
	)
	(segment
		(start 233.694478 -206.111602)
		(end 228.374448 -211.431632)
		(width 0.14605)
		(layer "In5.Cu")
		(net "DRIVE_B_1_ACT")
	)
	(segment
		(start 231.12476 -229.251256)
		(end 231.12476 -231.30891)
		(width 0.17145)
		(layer "F.Cu")
		(net "DRIVE_B_0_PWR")
	)
	(segment
		(start 206.037434 -231.46893)
		(end 204.119734 -231.46893)
		(width 0.17145)
		(layer "F.Cu")
		(net "DRIVE_B_0_PWR")
	)
	(segment
		(start 227.96373 -234.46994)
		(end 214.447628 -234.46994)
		(width 0.17145)
		(layer "F.Cu")
		(net "DRIVE_B_0_PWR")
	)
	(segment
		(start 204.119734 -231.46893)
		(end 203.985114 -231.60355)
		(width 0.17145)
		(layer "F.Cu")
		(net "DRIVE_B_0_PWR")
	)
	(segment
		(start 214.447628 -234.46994)
		(end 211.446872 -231.469184)
		(width 0.17145)
		(layer "F.Cu")
		(net "DRIVE_B_0_PWR")
	)
	(segment
		(start 148.819616 -228.84384)
		(end 150.890224 -230.914448)
		(width 0.17145)
		(layer "F.Cu")
		(net "DRIVE_B_0_PWR")
	)
	(segment
		(start 151.579326 -231.60355)
		(end 150.890224 -230.914448)
		(width 0.17145)
		(layer "F.Cu")
		(net "DRIVE_B_0_PWR")
	)
	(segment
		(start 211.446872 -231.469184)
		(end 206.037688 -231.469184)
		(width 0.17145)
		(layer "F.Cu")
		(net "DRIVE_B_0_PWR")
	)
	(segment
		(start 206.037688 -231.469184)
		(end 206.037434 -231.46893)
		(width 0.17145)
		(layer "F.Cu")
		(net "DRIVE_B_0_PWR")
	)
	(segment
		(start 203.985114 -231.60355)
		(end 151.579326 -231.60355)
		(width 0.17145)
		(layer "F.Cu")
		(net "DRIVE_B_0_PWR")
	)
	(segment
		(start 23.4315 -245.872)
		(end 24.257 -245.872)
		(width 0.17145)
		(layer "F.Cu")
		(net "DRIVE_B_0_PWR")
	)
	(segment
		(start 231.12476 -231.30891)
		(end 227.96373 -234.46994)
		(width 0.17145)
		(layer "F.Cu")
		(net "DRIVE_B_0_PWR")
	)
	(via
		(at 24.257 -245.872)
		(size 0.5588)
		(drill 0.3048)
		(layers "F.Cu" "B.Cu")
		(net "DRIVE_B_0_PWR")
	)
	(via
		(at 150.890224 -230.914448)
		(size 0.6604)
		(drill 0.3302)
		(layers "F.Cu" "B.Cu")
		(net "DRIVE_B_0_PWR")
	)
	(via
		(at 148.819616 -228.84384)
		(size 0.5588)
		(drill 0.3048)
		(layers "F.Cu" "B.Cu")
		(net "DRIVE_B_0_PWR")
	)
	(segment
		(start 58.146696 -235.611924)
		(end 53.63464 -240.12398)
		(width 0.14605)
		(layer "In2.Cu")
		(net "DRIVE_B_0_PWR")
	)
	(segment
		(start 148.819616 -228.84384)
		(end 142.051532 -235.611924)
		(width 0.14605)
		(layer "In2.Cu")
		(net "DRIVE_B_0_PWR")
	)
	(segment
		(start 53.63464 -240.12398)
		(end 29.99994 -240.12398)
		(width 0.14605)
		(layer "In2.Cu")
		(net "DRIVE_B_0_PWR")
	)
	(segment
		(start 29.99994 -240.12398)
		(end 24.257 -245.86692)
		(width 0.14605)
		(layer "In2.Cu")
		(net "DRIVE_B_0_PWR")
	)
	(segment
		(start 24.257 -245.86692)
		(end 24.257 -245.872)
		(width 0.14605)
		(layer "In2.Cu")
		(net "DRIVE_B_0_PWR")
	)
	(segment
		(start 142.051532 -235.611924)
		(end 58.146696 -235.611924)
		(width 0.14605)
		(layer "In2.Cu")
		(net "DRIVE_B_0_PWR")
	)
	(segment
		(start 208.24698 -247.97131)
		(end 207.709262 -248.509028)
		(width 0.17145)
		(layer "F.Cu")
		(net "DRIVE_B_0_INS")
	)
	(segment
		(start 207.709262 -248.509028)
		(end 207.709262 -273.830542)
		(width 0.17145)
		(layer "F.Cu")
		(net "DRIVE_B_0_INS")
	)
	(segment
		(start 208.24698 -244.48262)
		(end 208.24698 -247.97131)
		(width 0.17145)
		(layer "F.Cu")
		(net "DRIVE_B_0_INS")
	)
	(segment
		(start 207.709262 -273.830542)
		(end 197.922388 -283.617416)
		(width 0.17145)
		(layer "F.Cu")
		(net "DRIVE_B_0_INS")
	)
	(segment
		(start 36.449 -282.38196)
		(end 40.513 -286.44596)
		(width 0.17145)
		(layer "F.Cu")
		(net "DRIVE_B_0_INS")
	)
	(segment
		(start 195.093844 -286.44596)
		(end 197.922388 -283.617416)
		(width 0.17145)
		(layer "F.Cu")
		(net "DRIVE_B_0_INS")
	)
	(segment
		(start 40.513 -286.44596)
		(end 195.093844 -286.44596)
		(width 0.17145)
		(layer "F.Cu")
		(net "DRIVE_B_0_INS")
	)
	(segment
		(start 36.449 -266.065)
		(end 36.449 -282.38196)
		(width 0.17145)
		(layer "F.Cu")
		(net "DRIVE_B_0_INS")
	)
	(via
		(at 197.922388 -283.617416)
		(size 0.6604)
		(drill 0.3302)
		(layers "F.Cu" "B.Cu")
		(net "DRIVE_B_0_INS")
	)
	(segment
		(start 50.501296 -219.475812)
		(end 38.017958 -219.475812)
		(width 0.17145)
		(layer "F.Cu")
		(net "DRIVE_B_0_FLT_LED")
	)
	(segment
		(start 15.53845 -217.413586)
		(end 15.53845 -215.7095)
		(width 0.17145)
		(layer "F.Cu")
		(net "DRIVE_B_0_FLT_LED")
	)
	(segment
		(start 202.284584 -223.287336)
		(end 201.693018 -223.878902)
		(width 0.17145)
		(layer "F.Cu")
		(net "DRIVE_B_0_FLT_LED")
	)
	(segment
		(start 38.017958 -219.475812)
		(end 33.807146 -215.265)
		(width 0.17145)
		(layer "F.Cu")
		(net "DRIVE_B_0_FLT_LED")
	)
	(segment
		(start 202.899772 -222.672148)
		(end 202.284584 -223.287336)
		(width 0.17145)
		(layer "F.Cu")
		(net "DRIVE_B_0_FLT_LED")
	)
	(segment
		(start 54.904386 -223.878902)
		(end 50.501296 -219.475812)
		(width 0.17145)
		(layer "F.Cu")
		(net "DRIVE_B_0_FLT_LED")
	)
	(segment
		(start 201.693018 -223.878902)
		(end 54.904386 -223.878902)
		(width 0.17145)
		(layer "F.Cu")
		(net "DRIVE_B_0_FLT_LED")
	)
	(segment
		(start 212.9536 -222.8596)
		(end 209.84591 -222.8596)
		(width 0.17145)
		(layer "F.Cu")
		(net "DRIVE_B_0_FLT_LED")
	)
	(segment
		(start 21.981414 -217.413586)
		(end 15.53845 -217.413586)
		(width 0.17145)
		(layer "F.Cu")
		(net "DRIVE_B_0_FLT_LED")
	)
	(segment
		(start 209.658458 -222.672148)
		(end 202.899772 -222.672148)
		(width 0.17145)
		(layer "F.Cu")
		(net "DRIVE_B_0_FLT_LED")
	)
	(segment
		(start 24.13 -215.265)
		(end 21.981414 -217.413586)
		(width 0.17145)
		(layer "F.Cu")
		(net "DRIVE_B_0_FLT_LED")
	)
	(segment
		(start 209.84591 -222.8596)
		(end 209.658458 -222.672148)
		(width 0.17145)
		(layer "F.Cu")
		(net "DRIVE_B_0_FLT_LED")
	)
	(segment
		(start 33.807146 -215.265)
		(end 24.13 -215.265)
		(width 0.17145)
		(layer "F.Cu")
		(net "DRIVE_B_0_FLT_LED")
	)
	(via
		(at 202.284584 -223.287336)
		(size 0.6604)
		(drill 0.3302)
		(layers "F.Cu" "B.Cu")
		(net "DRIVE_B_0_FLT_LED")
	)
	(segment
		(start 11.796268 -210.6549)
		(end 11.796268 -212.390228)
		(width 0.17145)
		(layer "F.Cu")
		(net "DRIVE_B_0_ACT")
	)
	(segment
		(start 11.796268 -212.390228)
		(end 11.796268 -213.876128)
		(width 0.17145)
		(layer "F.Cu")
		(net "DRIVE_B_0_ACT")
	)
	(segment
		(start 282.072334 -206.930244)
		(end 275.860002 -206.930244)
		(width 0.17145)
		(layer "F.Cu")
		(net "DRIVE_B_0_ACT")
	)
	(segment
		(start 235.798106 -205.40345)
		(end 234.818936 -206.38262)
		(width 0.17145)
		(layer "F.Cu")
		(net "DRIVE_B_0_ACT")
	)
	(segment
		(start 275.860002 -206.930244)
		(end 274.393152 -205.463394)
		(width 0.17145)
		(layer "F.Cu")
		(net "DRIVE_B_0_ACT")
	)
	(segment
		(start 255.933702 -205.463394)
		(end 254.93726 -204.466952)
		(width 0.17145)
		(layer "F.Cu")
		(net "DRIVE_B_0_ACT")
	)
	(segment
		(start 243.317268 -204.466952)
		(end 242.38077 -205.40345)
		(width 0.17145)
		(layer "F.Cu")
		(net "DRIVE_B_0_ACT")
	)
	(segment
		(start 11.796268 -210.6549)
		(end 11.796268 -209.55)
		(width 0.17145)
		(layer "F.Cu")
		(net "DRIVE_B_0_ACT")
	)
	(segment
		(start 242.38077 -205.40345)
		(end 235.798106 -205.40345)
		(width 0.17145)
		(layer "F.Cu")
		(net "DRIVE_B_0_ACT")
	)
	(segment
		(start 234.818936 -206.38262)
		(end 234.818936 -206.389732)
		(width 0.17145)
		(layer "F.Cu")
		(net "DRIVE_B_0_ACT")
	)
	(segment
		(start 254.93726 -204.466952)
		(end 243.317268 -204.466952)
		(width 0.17145)
		(layer "F.Cu")
		(net "DRIVE_B_0_ACT")
	)
	(segment
		(start 283.23667 -208.09458)
		(end 282.072334 -206.930244)
		(width 0.17145)
		(layer "F.Cu")
		(net "DRIVE_B_0_ACT")
	)
	(segment
		(start 274.393152 -205.463394)
		(end 255.933702 -205.463394)
		(width 0.17145)
		(layer "F.Cu")
		(net "DRIVE_B_0_ACT")
	)
	(via
		(at 11.796268 -210.6549)
		(size 0.6604)
		(drill 0.3302)
		(layers "F.Cu" "B.Cu")
		(net "DRIVE_B_0_ACT")
	)
	(via
		(at 234.818936 -206.389732)
		(size 0.5588)
		(drill 0.3048)
		(layers "F.Cu" "B.Cu")
		(net "DRIVE_B_0_ACT")
	)
	(via
		(at 11.796268 -209.55)
		(size 0.5588)
		(drill 0.3048)
		(layers "F.Cu" "B.Cu")
		(net "DRIVE_B_0_ACT")
	)
	(segment
		(start 43.442128 -212.860128)
		(end 50.149506 -219.567506)
		(width 0.14605)
		(layer "In5.Cu")
		(net "DRIVE_B_0_ACT")
	)
	(segment
		(start 200.381108 -219.567506)
		(end 208.078832 -211.869782)
		(width 0.14605)
		(layer "In5.Cu")
		(net "DRIVE_B_0_ACT")
	)
	(segment
		(start 11.796268 -209.55)
		(end 15.106396 -212.860128)
		(width 0.14605)
		(layer "In5.Cu")
		(net "DRIVE_B_0_ACT")
	)
	(segment
		(start 228.650292 -211.869782)
		(end 232.8545 -207.665574)
		(width 0.14605)
		(layer "In5.Cu")
		(net "DRIVE_B_0_ACT")
	)
	(segment
		(start 208.078832 -211.869782)
		(end 228.650292 -211.869782)
		(width 0.14605)
		(layer "In5.Cu")
		(net "DRIVE_B_0_ACT")
	)
	(segment
		(start 50.149506 -219.567506)
		(end 200.381108 -219.567506)
		(width 0.14605)
		(layer "In5.Cu")
		(net "DRIVE_B_0_ACT")
	)
	(segment
		(start 233.543094 -207.665574)
		(end 234.818936 -206.389732)
		(width 0.14605)
		(layer "In5.Cu")
		(net "DRIVE_B_0_ACT")
	)
	(segment
		(start 232.8545 -207.665574)
		(end 233.543094 -207.665574)
		(width 0.14605)
		(layer "In5.Cu")
		(net "DRIVE_B_0_ACT")
	)
	(segment
		(start 15.106396 -212.860128)
		(end 43.442128 -212.860128)
		(width 0.14605)
		(layer "In5.Cu")
		(net "DRIVE_B_0_ACT")
	)
	(segment
		(start 207.281272 -158.920942)
		(end 199.48525 -166.716964)
		(width 0.17145)
		(layer "F.Cu")
		(net "DRAWER_CLOSED_N")
	)
	(segment
		(start 211.476844 -172.28058)
		(end 212.69706 -172.28058)
		(width 0.17145)
		(layer "F.Cu")
		(net "DRAWER_CLOSED_N")
	)
	(segment
		(start 207.281272 -158.920942)
		(end 207.731614 -158.4706)
		(width 0.17145)
		(layer "F.Cu")
		(net "DRAWER_CLOSED_N")
	)
	(segment
		(start 212.69706 -172.28058)
		(end 212.778086 -172.361606)
		(width 0.17145)
		(layer "F.Cu")
		(net "DRAWER_CLOSED_N")
	)
	(segment
		(start 208.586832 -158.4706)
		(end 227.21062 -139.846812)
		(width 0.17145)
		(layer "F.Cu")
		(net "DRAWER_CLOSED_N")
	)
	(segment
		(start 199.48525 -173.04385)
		(end 200.85304 -174.41164)
		(width 0.17145)
		(layer "F.Cu")
		(net "DRAWER_CLOSED_N")
	)
	(segment
		(start 207.19796 -174.41164)
		(end 209.016346 -172.593254)
		(width 0.17145)
		(layer "F.Cu")
		(net "DRAWER_CLOSED_N")
	)
	(segment
		(start 266.51204 -372.539514)
		(end 265.92784 -371.955314)
		(width 0.17145)
		(layer "F.Cu")
		(net "DRAWER_CLOSED_N")
	)
	(segment
		(start 199.48525 -166.716964)
		(end 199.48525 -173.04385)
		(width 0.17145)
		(layer "F.Cu")
		(net "DRAWER_CLOSED_N")
	)
	(segment
		(start 207.731614 -158.4706)
		(end 208.586832 -158.4706)
		(width 0.17145)
		(layer "F.Cu")
		(net "DRAWER_CLOSED_N")
	)
	(segment
		(start 227.21062 -139.846812)
		(end 227.21062 -87.093806)
		(width 0.17145)
		(layer "F.Cu")
		(net "DRAWER_CLOSED_N")
	)
	(segment
		(start 265.92784 -371.955314)
		(end 264.328402 -371.955314)
		(width 0.17145)
		(layer "F.Cu")
		(net "DRAWER_CLOSED_N")
	)
	(segment
		(start 227.21062 -87.093806)
		(end 224.237042 -84.120228)
		(width 0.17145)
		(layer "F.Cu")
		(net "DRAWER_CLOSED_N")
	)
	(segment
		(start 212.778086 -172.361606)
		(end 212.778086 -172.99813)
		(width 0.17145)
		(layer "F.Cu")
		(net "DRAWER_CLOSED_N")
	)
	(segment
		(start 209.016346 -172.593254)
		(end 211.16417 -172.593254)
		(width 0.17145)
		(layer "F.Cu")
		(net "DRAWER_CLOSED_N")
	)
	(segment
		(start 211.16417 -172.593254)
		(end 211.476844 -172.28058)
		(width 0.17145)
		(layer "F.Cu")
		(net "DRAWER_CLOSED_N")
	)
	(segment
		(start 264.328402 -371.955314)
		(end 261.915402 -371.955314)
		(width 0.17145)
		(layer "F.Cu")
		(net "DRAWER_CLOSED_N")
	)
	(segment
		(start 200.85304 -174.41164)
		(end 207.19796 -174.41164)
		(width 0.17145)
		(layer "F.Cu")
		(net "DRAWER_CLOSED_N")
	)
	(via
		(at 212.778086 -172.99813)
		(size 0.5588)
		(drill 0.3048)
		(layers "F.Cu" "B.Cu")
		(net "DRAWER_CLOSED_N")
	)
	(via
		(at 196.179694 -368.800888)
		(size 0.5588)
		(drill 0.3048)
		(layers "F.Cu" "B.Cu")
		(net "DRAWER_CLOSED_N")
	)
	(via
		(at 224.237042 -84.120228)
		(size 0.5588)
		(drill 0.3048)
		(layers "F.Cu" "B.Cu")
		(net "DRAWER_CLOSED_N")
	)
	(via
		(at 207.281272 -158.920942)
		(size 0.6604)
		(drill 0.3302)
		(layers "F.Cu" "B.Cu")
		(net "DRAWER_CLOSED_N")
	)
	(via
		(at 266.51204 -372.539514)
		(size 0.5588)
		(drill 0.3048)
		(layers "F.Cu" "B.Cu")
		(net "DRAWER_CLOSED_N")
	)
	(segment
		(start 198.100696 -302.903636)
		(end 205.31074 -295.693592)
		(width 0.14605)
		(layer "In2.Cu")
		(net "DRAWER_CLOSED_N")
	)
	(segment
		(start 207.88376 -246.118126)
		(end 207.88376 -238.405162)
		(width 0.14605)
		(layer "In2.Cu")
		(net "DRAWER_CLOSED_N")
	)
	(segment
		(start 206.927196 -359.577132)
		(end 206.927196 -324.54469)
		(width 0.14605)
		(layer "In2.Cu")
		(net "DRAWER_CLOSED_N")
	)
	(segment
		(start 205.31074 -295.693592)
		(end 205.310994 -295.693592)
		(width 0.14605)
		(layer "In2.Cu")
		(net "DRAWER_CLOSED_N")
	)
	(segment
		(start 207.064864 -293.939722)
		(end 207.064864 -293.939468)
		(width 0.14605)
		(layer "In2.Cu")
		(net "DRAWER_CLOSED_N")
	)
	(segment
		(start 213.187534 -201.85634)
		(end 213.78672 -201.257154)
		(width 0.14605)
		(layer "In2.Cu")
		(net "DRAWER_CLOSED_N")
	)
	(segment
		(start 212.950298 -174.034958)
		(end 212.778086 -173.862746)
		(width 0.14605)
		(layer "In2.Cu")
		(net "DRAWER_CLOSED_N")
	)
	(segment
		(start 207.064864 -246.937022)
		(end 207.88376 -246.118126)
		(width 0.14605)
		(layer "In2.Cu")
		(net "DRAWER_CLOSED_N")
	)
	(segment
		(start 205.310994 -295.693592)
		(end 207.064864 -293.939722)
		(width 0.14605)
		(layer "In2.Cu")
		(net "DRAWER_CLOSED_N")
	)
	(segment
		(start 224.063306 -73.93686)
		(end 224.063306 -83.946492)
		(width 0.14605)
		(layer "In2.Cu")
		(net "DRAWER_CLOSED_N")
	)
	(segment
		(start 213.687152 -218.997022)
		(end 213.687152 -216.81694)
		(width 0.14605)
		(layer "In2.Cu")
		(net "DRAWER_CLOSED_N")
	)
	(segment
		(start 213.187534 -211.637626)
		(end 213.187534 -201.85634)
		(width 0.14605)
		(layer "In2.Cu")
		(net "DRAWER_CLOSED_N")
	)
	(segment
		(start 213.05266 -211.7725)
		(end 213.187534 -211.637626)
		(width 0.14605)
		(layer "In2.Cu")
		(net "DRAWER_CLOSED_N")
	)
	(segment
		(start 213.687152 -216.81694)
		(end 213.05266 -216.182448)
		(width 0.14605)
		(layer "In2.Cu")
		(net "DRAWER_CLOSED_N")
	)
	(segment
		(start 211.524342 -221.159832)
		(end 213.687152 -218.997022)
		(width 0.14605)
		(layer "In2.Cu")
		(net "DRAWER_CLOSED_N")
	)
	(segment
		(start 207.065118 -293.939214)
		(end 207.065118 -292.721538)
		(width 0.14605)
		(layer "In2.Cu")
		(net "DRAWER_CLOSED_N")
	)
	(segment
		(start 207.064864 -292.721284)
		(end 207.064864 -246.937022)
		(width 0.14605)
		(layer "In2.Cu")
		(net "DRAWER_CLOSED_N")
	)
	(segment
		(start 198.100696 -315.71819)
		(end 198.100696 -302.903636)
		(width 0.14605)
		(layer "In2.Cu")
		(net "DRAWER_CLOSED_N")
	)
	(segment
		(start 213.78672 -175.881538)
		(end 212.950298 -175.045116)
		(width 0.14605)
		(layer "In2.Cu")
		(net "DRAWER_CLOSED_N")
	)
	(segment
		(start 207.064864 -293.939468)
		(end 207.065118 -293.939214)
		(width 0.14605)
		(layer "In2.Cu")
		(net "DRAWER_CLOSED_N")
	)
	(segment
		(start 224.063306 -83.946492)
		(end 224.237042 -84.120228)
		(width 0.14605)
		(layer "In2.Cu")
		(net "DRAWER_CLOSED_N")
	)
	(segment
		(start 212.950298 -175.045116)
		(end 212.950298 -174.034958)
		(width 0.14605)
		(layer "In2.Cu")
		(net "DRAWER_CLOSED_N")
	)
	(segment
		(start 208.29016 -237.998762)
		(end 211.524342 -234.764326)
		(width 0.14605)
		(layer "In2.Cu")
		(net "DRAWER_CLOSED_N")
	)
	(segment
		(start 212.778086 -173.862746)
		(end 212.778086 -172.99813)
		(width 0.14605)
		(layer "In2.Cu")
		(net "DRAWER_CLOSED_N")
	)
	(segment
		(start 213.78672 -201.257154)
		(end 213.78672 -175.881538)
		(width 0.14605)
		(layer "In2.Cu")
		(net "DRAWER_CLOSED_N")
	)
	(segment
		(start 207.88376 -238.405162)
		(end 208.29016 -237.998762)
		(width 0.14605)
		(layer "In2.Cu")
		(net "DRAWER_CLOSED_N")
	)
	(segment
		(start 226.200208 -71.799958)
		(end 224.063306 -73.93686)
		(width 0.14605)
		(layer "In2.Cu")
		(net "DRAWER_CLOSED_N")
	)
	(segment
		(start 196.179694 -368.800888)
		(end 197.70344 -368.800888)
		(width 0.14605)
		(layer "In2.Cu")
		(net "DRAWER_CLOSED_N")
	)
	(segment
		(start 206.927196 -324.54469)
		(end 198.100696 -315.71819)
		(width 0.14605)
		(layer "In2.Cu")
		(net "DRAWER_CLOSED_N")
	)
	(segment
		(start 211.524342 -234.764326)
		(end 211.524342 -221.159832)
		(width 0.14605)
		(layer "In2.Cu")
		(net "DRAWER_CLOSED_N")
	)
	(segment
		(start 213.05266 -216.182448)
		(end 213.05266 -211.7725)
		(width 0.14605)
		(layer "In2.Cu")
		(net "DRAWER_CLOSED_N")
	)
	(segment
		(start 207.065118 -292.721538)
		(end 207.064864 -292.721284)
		(width 0.14605)
		(layer "In2.Cu")
		(net "DRAWER_CLOSED_N")
	)
	(segment
		(start 197.70344 -368.800888)
		(end 206.927196 -359.577132)
		(width 0.14605)
		(layer "In2.Cu")
		(net "DRAWER_CLOSED_N")
	)
	(segment
		(start 238.542576 -374.205754)
		(end 239.34801 -375.011188)
		(width 0.14605)
		(layer "In5.Cu")
		(net "DRAWER_CLOSED_N")
	)
	(segment
		(start 253.771908 -375.011188)
		(end 255.99517 -377.23445)
		(width 0.14605)
		(layer "In5.Cu")
		(net "DRAWER_CLOSED_N")
	)
	(segment
		(start 196.179694 -368.762788)
		(end 202.549252 -368.762788)
		(width 0.14605)
		(layer "In5.Cu")
		(net "DRAWER_CLOSED_N")
	)
	(segment
		(start 239.34801 -375.011188)
		(end 253.771908 -375.011188)
		(width 0.14605)
		(layer "In5.Cu")
		(net "DRAWER_CLOSED_N")
	)
	(segment
		(start 196.179694 -368.800888)
		(end 196.179694 -368.762788)
		(width 0.14605)
		(layer "In5.Cu")
		(net "DRAWER_CLOSED_N")
	)
	(segment
		(start 263.31926 -377.23445)
		(end 266.51204 -374.04167)
		(width 0.14605)
		(layer "In5.Cu")
		(net "DRAWER_CLOSED_N")
	)
	(segment
		(start 255.99517 -377.23445)
		(end 263.31926 -377.23445)
		(width 0.14605)
		(layer "In5.Cu")
		(net "DRAWER_CLOSED_N")
	)
	(segment
		(start 266.51204 -374.04167)
		(end 266.51204 -372.539514)
		(width 0.14605)
		(layer "In5.Cu")
		(net "DRAWER_CLOSED_N")
	)
	(segment
		(start 207.992218 -374.205754)
		(end 238.542576 -374.205754)
		(width 0.14605)
		(layer "In5.Cu")
		(net "DRAWER_CLOSED_N")
	)
	(segment
		(start 202.549252 -368.762788)
		(end 207.992218 -374.205754)
		(width 0.14605)
		(layer "In5.Cu")
		(net "DRAWER_CLOSED_N")
	)
	(via
		(at 212.13191 -119.485156)
		(size 0.5588)
		(drill 0.3048)
		(layers "F.Cu" "B.Cu")
		(net "COMP_B_EXP_B_SPARE_0")
	)
	(via
		(at 296.418 -148.971)
		(size 0.5588)
		(drill 0.3048)
		(layers "F.Cu" "B.Cu")
		(net "COMP_B_EXP_B_SPARE_0")
	)
	(via
		(at 300.863 -144.78)
		(size 0.6096)
		(drill 0.3048)
		(layers "F.Cu" "B.Cu")
		(net "COMP_B_EXP_B_SPARE_0")
	)
	(segment
		(start 283.23667 -139.294362)
		(end 283.23667 -139.73175)
		(width 0.17145)
		(layer "B.Cu")
		(net "COMP_B_EXP_B_SPARE_0")
	)
	(segment
		(start 298.196 -148.971)
		(end 296.418 -148.971)
		(width 0.17145)
		(layer "B.Cu")
		(net "COMP_B_EXP_B_SPARE_0")
	)
	(segment
		(start 300.863 -144.78)
		(end 300.863 -146.304)
		(width 0.17145)
		(layer "B.Cu")
		(net "COMP_B_EXP_B_SPARE_0")
	)
	(segment
		(start 283.23667 -139.73175)
		(end 283.50718 -140.00226)
		(width 0.17145)
		(layer "B.Cu")
		(net "COMP_B_EXP_B_SPARE_0")
	)
	(segment
		(start 283.50718 -140.00226)
		(end 296.08526 -140.00226)
		(width 0.17145)
		(layer "B.Cu")
		(net "COMP_B_EXP_B_SPARE_0")
	)
	(segment
		(start 296.08526 -140.00226)
		(end 300.863 -144.78)
		(width 0.17145)
		(layer "B.Cu")
		(net "COMP_B_EXP_B_SPARE_0")
	)
	(segment
		(start 300.863 -146.304)
		(end 298.196 -148.971)
		(width 0.17145)
		(layer "B.Cu")
		(net "COMP_B_EXP_B_SPARE_0")
	)
	(segment
		(start 215.852248 -79.843376)
		(end 215.852248 -82.724752)
		(width 0.14605)
		(layer "In2.Cu")
		(net "COMP_B_EXP_B_SPARE_0")
	)
	(segment
		(start 212.13445 -112.85855)
		(end 212.13445 -119.482616)
		(width 0.14605)
		(layer "In2.Cu")
		(net "COMP_B_EXP_B_SPARE_0")
	)
	(segment
		(start 212.852 -85.725)
		(end 212.852 -112.141)
		(width 0.14605)
		(layer "In2.Cu")
		(net "COMP_B_EXP_B_SPARE_0")
	)
	(segment
		(start 215.852248 -82.724752)
		(end 212.852 -85.725)
		(width 0.14605)
		(layer "In2.Cu")
		(net "COMP_B_EXP_B_SPARE_0")
	)
	(segment
		(start 212.13445 -119.482616)
		(end 212.13191 -119.485156)
		(width 0.14605)
		(layer "In2.Cu")
		(net "COMP_B_EXP_B_SPARE_0")
	)
	(segment
		(start 215.400128 -72.799956)
		(end 216.043002 -73.44283)
		(width 0.14605)
		(layer "In2.Cu")
		(net "COMP_B_EXP_B_SPARE_0")
	)
	(segment
		(start 212.852 -112.141)
		(end 212.13445 -112.85855)
		(width 0.14605)
		(layer "In2.Cu")
		(net "COMP_B_EXP_B_SPARE_0")
	)
	(segment
		(start 216.043002 -79.652622)
		(end 215.852248 -79.843376)
		(width 0.14605)
		(layer "In2.Cu")
		(net "COMP_B_EXP_B_SPARE_0")
	)
	(segment
		(start 216.043002 -73.44283)
		(end 216.043002 -79.652622)
		(width 0.14605)
		(layer "In2.Cu")
		(net "COMP_B_EXP_B_SPARE_0")
	)
	(segment
		(start 237.619794 -138.557)
		(end 238.889794 -139.827)
		(width 0.14605)
		(layer "In5.Cu")
		(net "COMP_B_EXP_B_SPARE_0")
	)
	(segment
		(start 235.712 -138.557)
		(end 237.619794 -138.557)
		(width 0.14605)
		(layer "In5.Cu")
		(net "COMP_B_EXP_B_SPARE_0")
	)
	(segment
		(start 216.651332 -119.496332)
		(end 235.712 -138.557)
		(width 0.14605)
		(layer "In5.Cu")
		(net "COMP_B_EXP_B_SPARE_0")
	)
	(segment
		(start 263.13765 -149.21865)
		(end 296.17035 -149.21865)
		(width 0.14605)
		(layer "In5.Cu")
		(net "COMP_B_EXP_B_SPARE_0")
	)
	(segment
		(start 296.17035 -149.21865)
		(end 296.418 -148.971)
		(width 0.14605)
		(layer "In5.Cu")
		(net "COMP_B_EXP_B_SPARE_0")
	)
	(segment
		(start 253.746 -139.827)
		(end 263.13765 -149.21865)
		(width 0.14605)
		(layer "In5.Cu")
		(net "COMP_B_EXP_B_SPARE_0")
	)
	(segment
		(start 212.143086 -119.496332)
		(end 216.651332 -119.496332)
		(width 0.14605)
		(layer "In5.Cu")
		(net "COMP_B_EXP_B_SPARE_0")
	)
	(segment
		(start 238.889794 -139.827)
		(end 253.746 -139.827)
		(width 0.14605)
		(layer "In5.Cu")
		(net "COMP_B_EXP_B_SPARE_0")
	)
	(segment
		(start 212.13191 -119.485156)
		(end 212.143086 -119.496332)
		(width 0.14605)
		(layer "In5.Cu")
		(net "COMP_B_EXP_B_SPARE_0")
	)
	(segment
		(start 271.7292 -110.0074)
		(end 277.242524 -110.0074)
		(width 0.17145)
		(layer "F.Cu")
		(net "BMC_B_HEARTBEAT")
	)
	(segment
		(start 267.5382 -105.8164)
		(end 271.7292 -110.0074)
		(width 0.17145)
		(layer "F.Cu")
		(net "BMC_B_HEARTBEAT")
	)
	(segment
		(start 231.599994 -68.09994)
		(end 231.859328 -68.09994)
		(width 0.17145)
		(layer "F.Cu")
		(net "BMC_B_HEARTBEAT")
	)
	(segment
		(start 263.1694 -104.267)
		(end 264.7188 -105.8164)
		(width 0.17145)
		(layer "F.Cu")
		(net "BMC_B_HEARTBEAT")
	)
	(segment
		(start 231.859328 -68.09994)
		(end 251.434346 -87.686388)
		(width 0.17145)
		(layer "F.Cu")
		(net "BMC_B_HEARTBEAT")
	)
	(segment
		(start 264.7188 -105.8164)
		(end 267.5382 -105.8164)
		(width 0.17145)
		(layer "F.Cu")
		(net "BMC_B_HEARTBEAT")
	)
	(segment
		(start 284.148276 -116.913152)
		(end 288.5694 -116.913152)
		(width 0.17145)
		(layer "F.Cu")
		(net "BMC_B_HEARTBEAT")
	)
	(segment
		(start 251.434346 -92.531946)
		(end 263.1694 -104.267)
		(width 0.17145)
		(layer "F.Cu")
		(net "BMC_B_HEARTBEAT")
	)
	(segment
		(start 251.434346 -87.686388)
		(end 251.434346 -92.531946)
		(width 0.17145)
		(layer "F.Cu")
		(net "BMC_B_HEARTBEAT")
	)
	(segment
		(start 277.242524 -110.0074)
		(end 284.148276 -116.913152)
		(width 0.17145)
		(layer "F.Cu")
		(net "BMC_B_HEARTBEAT")
	)
	(via
		(at 263.1694 -104.267)
		(size 0.6604)
		(drill 0.3302)
		(layers "F.Cu" "B.Cu")
		(net "BMC_B_HEARTBEAT")
	)
	(via
		(at 288.5694 -116.913152)
		(size 0.5588)
		(drill 0.3048)
		(layers "F.Cu" "B.Cu")
		(net "BMC_B_HEARTBEAT")
	)
	(segment
		(start 294.284146 -231.384348)
		(end 287.695894 -237.9726)
		(width 0.14605)
		(layer "In2.Cu")
		(net "BMC_B_HEARTBEAT")
	)
	(segment
		(start 288.5694 -116.913152)
		(end 294.145208 -116.913152)
		(width 0.14605)
		(layer "In2.Cu")
		(net "BMC_B_HEARTBEAT")
	)
	(segment
		(start 294.284146 -192.975484)
		(end 294.284146 -231.384348)
		(width 0.14605)
		(layer "In2.Cu")
		(net "BMC_B_HEARTBEAT")
	)
	(segment
		(start 283.558488 -237.9726)
		(end 282.83662 -238.694468)
		(width 0.14605)
		(layer "In2.Cu")
		(net "BMC_B_HEARTBEAT")
	)
	(segment
		(start 287.695894 -237.9726)
		(end 283.558488 -237.9726)
		(width 0.14605)
		(layer "In2.Cu")
		(net "BMC_B_HEARTBEAT")
	)
	(segment
		(start 300.50867 -123.276614)
		(end 300.50867 -186.75096)
		(width 0.14605)
		(layer "In2.Cu")
		(net "BMC_B_HEARTBEAT")
	)
	(segment
		(start 300.50867 -186.75096)
		(end 294.284146 -192.975484)
		(width 0.14605)
		(layer "In2.Cu")
		(net "BMC_B_HEARTBEAT")
	)
	(segment
		(start 294.145208 -116.913152)
		(end 300.50867 -123.276614)
		(width 0.14605)
		(layer "In2.Cu")
		(net "BMC_B_HEARTBEAT")
	)
	(segment
		(start 252.6284 -87.694008)
		(end 252.6284 -88.683084)
		(width 0.17145)
		(layer "F.Cu")
		(net "BMC_B_EXP_B_SPARE_1")
	)
	(segment
		(start 283.604716 -114.681)
		(end 277.737316 -108.8136)
		(width 0.17145)
		(layer "F.Cu")
		(net "BMC_B_EXP_B_SPARE_1")
	)
	(segment
		(start 294.169592 -119.061992)
		(end 289.7886 -114.681)
		(width 0.17145)
		(layer "F.Cu")
		(net "BMC_B_EXP_B_SPARE_1")
	)
	(segment
		(start 281.836622 -135.69442)
		(end 282.516326 -135.014716)
		(width 0.17145)
		(layer "F.Cu")
		(net "BMC_B_EXP_B_SPARE_1")
	)
	(segment
		(start 252.628146 -87.693754)
		(end 252.6284 -87.694008)
		(width 0.17145)
		(layer "F.Cu")
		(net "BMC_B_EXP_B_SPARE_1")
	)
	(segment
		(start 290.740084 -135.014716)
		(end 294.169592 -131.585208)
		(width 0.17145)
		(layer "F.Cu")
		(net "BMC_B_EXP_B_SPARE_1")
	)
	(segment
		(start 289.7886 -114.681)
		(end 283.604716 -114.681)
		(width 0.17145)
		(layer "F.Cu")
		(net "BMC_B_EXP_B_SPARE_1")
	)
	(segment
		(start 231.599994 -65.600072)
		(end 252.628146 -86.628224)
		(width 0.17145)
		(layer "F.Cu")
		(net "BMC_B_EXP_B_SPARE_1")
	)
	(segment
		(start 294.169592 -131.585208)
		(end 294.169592 -119.061992)
		(width 0.17145)
		(layer "F.Cu")
		(net "BMC_B_EXP_B_SPARE_1")
	)
	(segment
		(start 275.253704 -108.8136)
		(end 272.8976 -106.457496)
		(width 0.17145)
		(layer "F.Cu")
		(net "BMC_B_EXP_B_SPARE_1")
	)
	(segment
		(start 265.110722 -104.3178)
		(end 270.757904 -104.3178)
		(width 0.17145)
		(layer "F.Cu")
		(net "BMC_B_EXP_B_SPARE_1")
	)
	(segment
		(start 282.516326 -135.014716)
		(end 290.740084 -135.014716)
		(width 0.17145)
		(layer "F.Cu")
		(net "BMC_B_EXP_B_SPARE_1")
	)
	(segment
		(start 277.737316 -108.8136)
		(end 275.253704 -108.8136)
		(width 0.17145)
		(layer "F.Cu")
		(net "BMC_B_EXP_B_SPARE_1")
	)
	(segment
		(start 252.628146 -88.683338)
		(end 252.628146 -91.684094)
		(width 0.17145)
		(layer "F.Cu")
		(net "BMC_B_EXP_B_SPARE_1")
	)
	(segment
		(start 258.341114 -97.548192)
		(end 265.110722 -104.3178)
		(width 0.17145)
		(layer "F.Cu")
		(net "BMC_B_EXP_B_SPARE_1")
	)
	(segment
		(start 252.628146 -86.628224)
		(end 252.628146 -87.693754)
		(width 0.17145)
		(layer "F.Cu")
		(net "BMC_B_EXP_B_SPARE_1")
	)
	(segment
		(start 252.628146 -91.684094)
		(end 258.341114 -97.397062)
		(width 0.17145)
		(layer "F.Cu")
		(net "BMC_B_EXP_B_SPARE_1")
	)
	(segment
		(start 270.757904 -104.3178)
		(end 272.8976 -106.457496)
		(width 0.17145)
		(layer "F.Cu")
		(net "BMC_B_EXP_B_SPARE_1")
	)
	(segment
		(start 252.6284 -88.683084)
		(end 252.628146 -88.683338)
		(width 0.17145)
		(layer "F.Cu")
		(net "BMC_B_EXP_B_SPARE_1")
	)
	(segment
		(start 258.341114 -97.397062)
		(end 258.341114 -97.548192)
		(width 0.17145)
		(layer "F.Cu")
		(net "BMC_B_EXP_B_SPARE_1")
	)
	(via
		(at 272.8976 -106.457496)
		(size 0.6604)
		(drill 0.3302)
		(layers "F.Cu" "B.Cu")
		(net "BMC_B_EXP_B_SPARE_1")
	)
	(segment
		(start 301.9552 -126.0856)
		(end 294.8686 -118.999)
		(width 0.17145)
		(layer "F.Cu")
		(net "BMC_B_EXP_B_SPARE_0")
	)
	(segment
		(start 284.11043 -136.56818)
		(end 300.89602 -136.56818)
		(width 0.17145)
		(layer "F.Cu")
		(net "BMC_B_EXP_B_SPARE_0")
	)
	(segment
		(start 300.89602 -136.56818)
		(end 301.9552 -135.509)
		(width 0.17145)
		(layer "F.Cu")
		(net "BMC_B_EXP_B_SPARE_0")
	)
	(segment
		(start 301.9552 -135.509)
		(end 301.9552 -128.9304)
		(width 0.17145)
		(layer "F.Cu")
		(net "BMC_B_EXP_B_SPARE_0")
	)
	(segment
		(start 283.23667 -135.69442)
		(end 284.11043 -136.56818)
		(width 0.17145)
		(layer "F.Cu")
		(net "BMC_B_EXP_B_SPARE_0")
	)
	(segment
		(start 301.9552 -128.9304)
		(end 301.9552 -126.0856)
		(width 0.17145)
		(layer "F.Cu")
		(net "BMC_B_EXP_B_SPARE_0")
	)
	(via
		(at 301.9552 -128.9304)
		(size 0.6604)
		(drill 0.3302)
		(layers "F.Cu" "B.Cu")
		(net "BMC_B_EXP_B_SPARE_0")
	)
	(via
		(at 294.8686 -118.999)
		(size 0.5588)
		(drill 0.3048)
		(layers "F.Cu" "B.Cu")
		(net "BMC_B_EXP_B_SPARE_0")
	)
	(segment
		(start 263.856724 -100.453952)
		(end 275.343112 -111.94034)
		(width 0.14605)
		(layer "In5.Cu")
		(net "BMC_B_EXP_B_SPARE_0")
	)
	(segment
		(start 235.1532 -68.053204)
		(end 235.1532 -82.759042)
		(width 0.14605)
		(layer "In5.Cu")
		(net "BMC_B_EXP_B_SPARE_0")
	)
	(segment
		(start 252.84811 -100.453952)
		(end 263.856724 -100.453952)
		(width 0.14605)
		(layer "In5.Cu")
		(net "BMC_B_EXP_B_SPARE_0")
	)
	(segment
		(start 287.80994 -111.94034)
		(end 294.8686 -118.999)
		(width 0.14605)
		(layer "In5.Cu")
		(net "BMC_B_EXP_B_SPARE_0")
	)
	(segment
		(start 275.343112 -111.94034)
		(end 287.80994 -111.94034)
		(width 0.14605)
		(layer "In5.Cu")
		(net "BMC_B_EXP_B_SPARE_0")
	)
	(segment
		(start 235.1532 -82.759042)
		(end 252.84811 -100.453952)
		(width 0.14605)
		(layer "In5.Cu")
		(net "BMC_B_EXP_B_SPARE_0")
	)
	(segment
		(start 231.599994 -64.499998)
		(end 235.1532 -68.053204)
		(width 0.14605)
		(layer "In5.Cu")
		(net "BMC_B_EXP_B_SPARE_0")
	)
	(segment
		(start 293.0398 -130.3274)
		(end 293.0398 -122.1232)
		(width 0.17145)
		(layer "F.Cu")
		(net "BMC_A_HEARTBEAT")
	)
	(segment
		(start 289.4076 -115.443)
		(end 283.40558 -115.443)
		(width 0.17145)
		(layer "F.Cu")
		(net "BMC_A_HEARTBEAT")
	)
	(segment
		(start 273.386042 -109.49305)
		(end 271.239488 -107.346496)
		(width 0.17145)
		(layer "F.Cu")
		(net "BMC_A_HEARTBEAT")
	)
	(segment
		(start 251.948696 -92.055696)
		(end 257.661664 -97.768664)
		(width 0.17145)
		(layer "F.Cu")
		(net "BMC_A_HEARTBEAT")
	)
	(segment
		(start 257.661664 -97.768664)
		(end 257.661664 -97.829878)
		(width 0.17145)
		(layer "F.Cu")
		(net "BMC_A_HEARTBEAT")
	)
	(segment
		(start 277.45563 -109.49305)
		(end 273.386042 -109.49305)
		(width 0.17145)
		(layer "F.Cu")
		(net "BMC_A_HEARTBEAT")
	)
	(segment
		(start 292.0746 -118.11)
		(end 289.4076 -115.443)
		(width 0.17145)
		(layer "F.Cu")
		(net "BMC_A_HEARTBEAT")
	)
	(segment
		(start 283.40558 -115.443)
		(end 277.45563 -109.49305)
		(width 0.17145)
		(layer "F.Cu")
		(net "BMC_A_HEARTBEAT")
	)
	(segment
		(start 290.3474 -133.0198)
		(end 293.0398 -130.3274)
		(width 0.17145)
		(layer "F.Cu")
		(net "BMC_A_HEARTBEAT")
	)
	(segment
		(start 231.599994 -66.999866)
		(end 251.948696 -87.348568)
		(width 0.17145)
		(layer "F.Cu")
		(net "BMC_A_HEARTBEAT")
	)
	(segment
		(start 264.829036 -104.99725)
		(end 268.890242 -104.99725)
		(width 0.17145)
		(layer "F.Cu")
		(net "BMC_A_HEARTBEAT")
	)
	(segment
		(start 282.83662 -133.894322)
		(end 283.711142 -133.0198)
		(width 0.17145)
		(layer "F.Cu")
		(net "BMC_A_HEARTBEAT")
	)
	(segment
		(start 257.661664 -97.829878)
		(end 264.829036 -104.99725)
		(width 0.17145)
		(layer "F.Cu")
		(net "BMC_A_HEARTBEAT")
	)
	(segment
		(start 251.948696 -87.348568)
		(end 251.948696 -92.055696)
		(width 0.17145)
		(layer "F.Cu")
		(net "BMC_A_HEARTBEAT")
	)
	(segment
		(start 268.890242 -104.99725)
		(end 271.239488 -107.346496)
		(width 0.17145)
		(layer "F.Cu")
		(net "BMC_A_HEARTBEAT")
	)
	(segment
		(start 283.711142 -133.0198)
		(end 290.3474 -133.0198)
		(width 0.17145)
		(layer "F.Cu")
		(net "BMC_A_HEARTBEAT")
	)
	(segment
		(start 293.0398 -122.1232)
		(end 292.0746 -121.158)
		(width 0.17145)
		(layer "F.Cu")
		(net "BMC_A_HEARTBEAT")
	)
	(segment
		(start 292.0746 -121.158)
		(end 292.0746 -118.11)
		(width 0.17145)
		(layer "F.Cu")
		(net "BMC_A_HEARTBEAT")
	)
	(via
		(at 271.239488 -107.346496)
		(size 0.6604)
		(drill 0.3302)
		(layers "F.Cu" "B.Cu")
		(net "BMC_A_HEARTBEAT")
	)
	(via
		(at 436.920386 -120.854978)
		(size 0.6604)
		(drill 0.3302)
		(layers "F.Cu" "B.Cu")
		(net "AGND_P5V_B_4")
	)
	(via
		(at 437.869584 -120.543828)
		(size 0.5588)
		(drill 0.3048)
		(layers "F.Cu" "B.Cu")
		(net "AGND_P5V_B_4")
	)
	(via
		(at 456.7682 -230.8606)
		(size 0.5588)
		(drill 0.3048)
		(layers "F.Cu" "B.Cu")
		(net "AGND_P5V_B_3")
	)
	(via
		(at 455.819002 -231.17175)
		(size 0.6604)
		(drill 0.3302)
		(layers "F.Cu" "B.Cu")
		(net "AGND_P5V_B_3")
	)
	(via
		(at 46.006258 -119.675656)
		(size 0.5588)
		(drill 0.3048)
		(layers "F.Cu" "B.Cu")
		(net "AGND_P5V_B_2")
	)
	(via
		(at 45.05706 -119.986806)
		(size 0.6604)
		(drill 0.3302)
		(layers "F.Cu" "B.Cu")
		(net "AGND_P5V_B_2")
	)
	(via
		(at 21.1582 -230.8606)
		(size 0.5588)
		(drill 0.3048)
		(layers "F.Cu" "B.Cu")
		(net "AGND_P5V_B_1")
	)
	(via
		(at 20.209002 -231.17175)
		(size 0.6604)
		(drill 0.3302)
		(layers "F.Cu" "B.Cu")
		(net "AGND_P5V_B_1")
	)
	(segment
		(start 30.025086 -269.705074)
		(end 34.763964 -269.705074)
		(width 0.17145)
		(layer "F.Cu")
		(net "ACT_HDD_0")
	)
	(via
		(at 21.082 -267.462)
		(size 0.6604)
		(drill 0.3302)
		(layers "F.Cu" "B.Cu")
		(net "12V_PRE_0")
	)
	(segment
		(start 252.100588 -363.638846)
		(end 252.100588 -363.087412)
		(width 0.254)
		(layer "F.Cu")
		(net "MB3_VCAP_R")
	)
	(segment
		(start 251.128022 -360.146346)
		(end 251.128022 -361.035346)
		(width 0.254)
		(layer "F.Cu")
		(net "MB3_VCAP_R")
	)
	(segment
		(start 250.8504 -361.312968)
		(end 251.128022 -361.035346)
		(width 0.254)
		(layer "F.Cu")
		(net "MB3_VCAP_R")
	)
	(segment
		(start 252.100588 -363.087412)
		(end 251.440188 -362.427012)
		(width 0.254)
		(layer "F.Cu")
		(net "MB3_VCAP_R")
	)
	(segment
		(start 251.276612 -362.427012)
		(end 250.8504 -362.0008)
		(width 0.254)
		(layer "F.Cu")
		(net "MB3_VCAP_R")
	)
	(segment
		(start 251.128022 -360.146346)
		(end 250.680474 -360.146346)
		(width 0.254)
		(layer "F.Cu")
		(net "MB3_VCAP_R")
	)
	(segment
		(start 253.160022 -360.146346)
		(end 253.160022 -361.035346)
		(width 0.254)
		(layer "F.Cu")
		(net "MB3_VCAP_R")
	)
	(segment
		(start 249.921522 -360.019346)
		(end 249.045222 -360.019346)
		(width 0.254)
		(layer "F.Cu")
		(net "MB3_VCAP_R")
	)
	(segment
		(start 251.440188 -362.427012)
		(end 251.276612 -362.427012)
		(width 0.254)
		(layer "F.Cu")
		(net "MB3_VCAP_R")
	)
	(segment
		(start 249.045222 -360.019346)
		(end 248.715022 -360.349546)
		(width 0.254)
		(layer "F.Cu")
		(net "MB3_VCAP_R")
	)
	(segment
		(start 250.553474 -360.019346)
		(end 249.921522 -360.019346)
		(width 0.254)
		(layer "F.Cu")
		(net "MB3_VCAP_R")
	)
	(segment
		(start 250.8504 -362.0008)
		(end 250.8504 -361.312968)
		(width 0.254)
		(layer "F.Cu")
		(net "MB3_VCAP_R")
	)
	(segment
		(start 250.680474 -360.146346)
		(end 250.553474 -360.019346)
		(width 0.254)
		(layer "F.Cu")
		(net "MB3_VCAP_R")
	)
	(via
		(at 253.160022 -361.035346)
		(size 0.5588)
		(drill 0.3048)
		(layers "F.Cu" "B.Cu")
		(net "MB3_VCAP_R")
	)
	(via
		(at 251.128022 -361.035346)
		(size 0.5588)
		(drill 0.3048)
		(layers "F.Cu" "B.Cu")
		(net "MB3_VCAP_R")
	)
	(via
		(at 250.8504 -362.0008)
		(size 0.6604)
		(drill 0.3302)
		(layers "F.Cu" "B.Cu")
		(net "MB3_VCAP_R")
	)
	(segment
		(start 251.128022 -361.035346)
		(end 253.160022 -361.035346)
		(width 0.254)
		(layer "In5.Cu")
		(net "MB3_VCAP_R")
	)
	(segment
		(start 253.600458 -363.638846)
		(end 253.600458 -363.07141)
		(width 0.254)
		(layer "F.Cu")
		(net "MB3_TIME_R")
	)
	(segment
		(start 253.600458 -363.07141)
		(end 255.509522 -361.162346)
		(width 0.254)
		(layer "F.Cu")
		(net "MB3_TIME_R")
	)
	(segment
		(start 255.509522 -361.162346)
		(end 255.509522 -360.400346)
		(width 0.254)
		(layer "F.Cu")
		(net "MB3_TIME_R")
	)
	(segment
		(start 255.509522 -359.066846)
		(end 255.509522 -360.400346)
		(width 0.254)
		(layer "F.Cu")
		(net "MB3_TIME_R")
	)
	(via
		(at 255.509522 -360.400346)
		(size 0.6604)
		(drill 0.3302)
		(layers "F.Cu" "B.Cu")
		(net "MB3_TIME_R")
	)
	(segment
		(start 250.103894 -367.865406)
		(end 249.629168 -368.340132)
		(width 0.254)
		(layer "F.Cu")
		(net "MB3_TEMP")
	)
	(segment
		(start 248.711466 -368.340132)
		(end 247.761252 -368.340132)
		(width 0.254)
		(layer "F.Cu")
		(net "MB3_TEMP")
	)
	(segment
		(start 250.797822 -367.865406)
		(end 250.103894 -367.865406)
		(width 0.254)
		(layer "F.Cu")
		(net "MB3_TEMP")
	)
	(segment
		(start 249.629168 -368.340132)
		(end 248.711466 -368.340132)
		(width 0.254)
		(layer "F.Cu")
		(net "MB3_TEMP")
	)
	(via
		(at 248.711466 -368.340132)
		(size 0.6604)
		(drill 0.3302)
		(layers "F.Cu" "B.Cu")
		(net "MB3_TEMP")
	)
	(segment
		(start 255.903222 -364.365286)
		(end 257.231642 -364.365286)
		(width 0.254)
		(layer "F.Cu")
		(net "MB3_SPISS_PD")
	)
	(segment
		(start 258.494022 -363.575346)
		(end 258.021582 -363.575346)
		(width 0.254)
		(layer "F.Cu")
		(net "MB3_SPISS_PD")
	)
	(segment
		(start 258.021582 -363.575346)
		(end 257.386582 -364.210346)
		(width 0.254)
		(layer "F.Cu")
		(net "MB3_SPISS_PD")
	)
	(segment
		(start 257.231642 -364.365286)
		(end 257.386582 -364.210346)
		(width 0.254)
		(layer "F.Cu")
		(net "MB3_SPISS_PD")
	)
	(via
		(at 257.386582 -364.210346)
		(size 0.6604)
		(drill 0.3302)
		(layers "F.Cu" "B.Cu")
		(net "MB3_SPISS_PD")
	)
	(segment
		(start 259.490972 -370.84)
		(end 259.490972 -371.88521)
		(width 0.254)
		(layer "F.Cu")
		(net "MB3_RETRY_R")
	)
	(segment
		(start 255.663446 -368.668046)
		(end 256.857246 -369.861846)
		(width 0.254)
		(layer "F.Cu")
		(net "MB3_RETRY_R")
	)
	(segment
		(start 256.857246 -369.861846)
		(end 258.674108 -369.861846)
		(width 0.254)
		(layer "F.Cu")
		(net "MB3_RETRY_R")
	)
	(segment
		(start 259.490972 -370.67871)
		(end 259.490972 -370.84)
		(width 0.254)
		(layer "F.Cu")
		(net "MB3_RETRY_R")
	)
	(segment
		(start 255.100582 -368.668046)
		(end 255.663446 -368.668046)
		(width 0.254)
		(layer "F.Cu")
		(net "MB3_RETRY_R")
	)
	(segment
		(start 258.674108 -369.861846)
		(end 259.490972 -370.67871)
		(width 0.254)
		(layer "F.Cu")
		(net "MB3_RETRY_R")
	)
	(via
		(at 259.490972 -370.84)
		(size 0.6604)
		(drill 0.3302)
		(layers "F.Cu" "B.Cu")
		(net "MB3_RETRY_R")
	)
	(segment
		(start 247.826022 -360.349546)
		(end 247.826022 -361.338622)
		(width 0.254)
		(layer "F.Cu")
		(net "MB3_PSET_R")
	)
	(segment
		(start 250.185936 -362.465112)
		(end 248.952512 -362.465112)
		(width 0.254)
		(layer "F.Cu")
		(net "MB3_PSET_R")
	)
	(segment
		(start 248.952512 -362.465112)
		(end 248.8946 -362.4072)
		(width 0.254)
		(layer "F.Cu")
		(net "MB3_PSET_R")
	)
	(segment
		(start 251.600462 -363.562646)
		(end 251.28347 -363.562646)
		(width 0.254)
		(layer "F.Cu")
		(net "MB3_PSET_R")
	)
	(segment
		(start 247.762522 -359.320846)
		(end 247.762522 -360.286046)
		(width 0.254)
		(layer "F.Cu")
		(net "MB3_PSET_R")
	)
	(segment
		(start 247.826022 -361.338622)
		(end 248.8946 -362.4072)
		(width 0.254)
		(layer "F.Cu")
		(net "MB3_PSET_R")
	)
	(segment
		(start 247.762522 -359.320846)
		(end 248.778522 -359.320846)
		(width 0.254)
		(layer "F.Cu")
		(net "MB3_PSET_R")
	)
	(segment
		(start 247.762522 -360.286046)
		(end 247.826022 -360.349546)
		(width 0.254)
		(layer "F.Cu")
		(net "MB3_PSET_R")
	)
	(segment
		(start 251.28347 -363.562646)
		(end 250.185936 -362.465112)
		(width 0.254)
		(layer "F.Cu")
		(net "MB3_PSET_R")
	)
	(via
		(at 248.8946 -362.4072)
		(size 0.6604)
		(drill 0.3302)
		(layers "F.Cu" "B.Cu")
		(net "MB3_PSET_R")
	)
	(segment
		(start 252.544834 -371.898418)
		(end 253.570232 -371.898418)
		(width 0.254)
		(layer "F.Cu")
		(net "MB3_P12V_PWGIN_R")
	)
	(segment
		(start 252.886718 -370.717064)
		(end 252.544834 -371.058948)
		(width 0.254)
		(layer "F.Cu")
		(net "MB3_P12V_PWGIN_R")
	)
	(segment
		(start 253.100586 -370.503196)
		(end 252.886718 -370.717064)
		(width 0.254)
		(layer "F.Cu")
		(net "MB3_P12V_PWGIN_R")
	)
	(segment
		(start 252.544834 -371.058948)
		(end 252.544834 -371.898418)
		(width 0.254)
		(layer "F.Cu")
		(net "MB3_P12V_PWGIN_R")
	)
	(segment
		(start 253.570232 -371.898418)
		(end 253.57455 -371.902736)
		(width 0.254)
		(layer "F.Cu")
		(net "MB3_P12V_PWGIN_R")
	)
	(segment
		(start 253.100586 -368.591846)
		(end 253.100586 -370.503196)
		(width 0.254)
		(layer "F.Cu")
		(net "MB3_P12V_PWGIN_R")
	)
	(via
		(at 252.886718 -370.717064)
		(size 0.6604)
		(drill 0.3302)
		(layers "F.Cu" "B.Cu")
		(net "MB3_P12V_PWGIN_R")
	)
	(segment
		(start 250.874022 -365.365284)
		(end 250.206002 -365.365284)
		(width 0.254)
		(layer "F.Cu")
		(net "MB3_P12V_HS")
	)
	(segment
		(start 248.818146 -364.845346)
		(end 247.762522 -364.845346)
		(width 0.508)
		(layer "F.Cu")
		(net "MB3_P12V_HS")
	)
	(segment
		(start 247.762522 -364.400846)
		(end 247.762522 -364.845346)
		(width 0.508)
		(layer "F.Cu")
		(net "MB3_P12V_HS")
	)
	(segment
		(start 247.064022 -363.702346)
		(end 247.762522 -364.400846)
		(width 0.508)
		(layer "F.Cu")
		(net "MB3_P12V_HS")
	)
	(segment
		(start 250.206002 -365.365284)
		(end 249.686064 -364.845346)
		(width 0.254)
		(layer "F.Cu")
		(net "MB3_P12V_HS")
	)
	(segment
		(start 249.441208 -364.845346)
		(end 248.818146 -364.845346)
		(width 0.508)
		(layer "F.Cu")
		(net "MB3_P12V_HS")
	)
	(segment
		(start 249.686064 -364.845346)
		(end 249.441208 -364.845346)
		(width 0.254)
		(layer "F.Cu")
		(net "MB3_P12V_HS")
	)
	(via
		(at 248.818146 -364.845346)
		(size 0.6604)
		(drill 0.3302)
		(layers "F.Cu" "B.Cu")
		(net "MB3_P12V_HS")
	)
	(segment
		(start 254.049022 -360.146346)
		(end 254.049022 -359.130346)
		(width 0.254)
		(layer "F.Cu")
		(net "MB3_ISTART_R")
	)
	(segment
		(start 254.112522 -359.066846)
		(end 253.096522 -359.066846)
		(width 0.254)
		(layer "F.Cu")
		(net "MB3_ISTART_R")
	)
	(segment
		(start 254.049022 -361.543346)
		(end 254.049022 -360.146346)
		(width 0.254)
		(layer "F.Cu")
		(net "MB3_ISTART_R")
	)
	(segment
		(start 253.100586 -362.491782)
		(end 254.049022 -361.543346)
		(width 0.254)
		(layer "F.Cu")
		(net "MB3_ISTART_R")
	)
	(segment
		(start 254.049022 -359.130346)
		(end 254.112522 -359.066846)
		(width 0.254)
		(layer "F.Cu")
		(net "MB3_ISTART_R")
	)
	(segment
		(start 253.100586 -363.638846)
		(end 253.100586 -362.491782)
		(width 0.254)
		(layer "F.Cu")
		(net "MB3_ISTART_R")
	)
	(via
		(at 254.049022 -361.543346)
		(size 0.6604)
		(drill 0.3302)
		(layers "F.Cu" "B.Cu")
		(net "MB3_ISTART_R")
	)
	(segment
		(start 252.017022 -361.110022)
		(end 252.017022 -360.146346)
		(width 0.254)
		(layer "F.Cu")
		(net "MB3_ISET_R")
	)
	(segment
		(start 252.080522 -359.066846)
		(end 251.064522 -359.066846)
		(width 0.254)
		(layer "F.Cu")
		(net "MB3_ISET_R")
	)
	(segment
		(start 252.60046 -363.638846)
		(end 252.60046 -362.65866)
		(width 0.254)
		(layer "F.Cu")
		(net "MB3_ISET_R")
	)
	(segment
		(start 252.60046 -362.65866)
		(end 252.2982 -362.3564)
		(width 0.254)
		(layer "F.Cu")
		(net "MB3_ISET_R")
	)
	(segment
		(start 252.017022 -360.146346)
		(end 252.017022 -359.130346)
		(width 0.254)
		(layer "F.Cu")
		(net "MB3_ISET_R")
	)
	(segment
		(start 252.017022 -359.130346)
		(end 252.080522 -359.066846)
		(width 0.254)
		(layer "F.Cu")
		(net "MB3_ISET_R")
	)
	(segment
		(start 252.1712 -361.2642)
		(end 252.1712 -362.2294)
		(width 0.254)
		(layer "F.Cu")
		(net "MB3_ISET_R")
	)
	(segment
		(start 252.1712 -362.2294)
		(end 252.2982 -362.3564)
		(width 0.254)
		(layer "F.Cu")
		(net "MB3_ISET_R")
	)
	(segment
		(start 252.1712 -361.2642)
		(end 252.017022 -361.110022)
		(width 0.254)
		(layer "F.Cu")
		(net "MB3_ISET_R")
	)
	(via
		(at 252.1712 -361.2642)
		(size 0.6604)
		(drill 0.3302)
		(layers "F.Cu" "B.Cu")
		(net "MB3_ISET_R")
	)
	(segment
		(start 258.426458 -365.86541)
		(end 258.811522 -365.480346)
		(width 0.254)
		(layer "F.Cu")
		(net "MB3_HS_ENABLE")
	)
	(segment
		(start 260.320282 -365.289846)
		(end 259.002022 -365.289846)
		(width 0.254)
		(layer "F.Cu")
		(net "MB3_HS_ENABLE")
	)
	(segment
		(start 259.002022 -365.289846)
		(end 258.811522 -365.480346)
		(width 0.254)
		(layer "F.Cu")
		(net "MB3_HS_ENABLE")
	)
	(segment
		(start 255.827022 -365.86541)
		(end 258.426458 -365.86541)
		(width 0.254)
		(layer "F.Cu")
		(net "MB3_HS_ENABLE")
	)
	(via
		(at 258.811522 -365.480346)
		(size 0.6604)
		(drill 0.3302)
		(layers "F.Cu" "B.Cu")
		(net "MB3_HS_ENABLE")
	)
	(segment
		(start 253.858522 -371.20576)
		(end 253.858522 -370.333524)
		(width 0.254)
		(layer "F.Cu")
		(net "MB3_CM_VOUT_R")
	)
	(segment
		(start 270.23568 -351.794826)
		(end 271.134586 -351.794826)
		(width 0.254)
		(layer "F.Cu")
		(net "MB3_CM_VOUT_R")
	)
	(segment
		(start 254.537972 -371.88521)
		(end 253.858522 -371.20576)
		(width 0.254)
		(layer "F.Cu")
		(net "MB3_CM_VOUT_R")
	)
	(segment
		(start 253.858522 -369.417346)
		(end 253.858522 -370.333524)
		(width 0.254)
		(layer "F.Cu")
		(net "MB3_CM_VOUT_R")
	)
	(segment
		(start 269.269972 -351.749106)
		(end 269.311882 -351.791016)
		(width 0.254)
		(layer "F.Cu")
		(net "MB3_CM_VOUT_R")
	)
	(segment
		(start 253.600458 -369.159282)
		(end 253.858522 -369.417346)
		(width 0.254)
		(layer "F.Cu")
		(net "MB3_CM_VOUT_R")
	)
	(segment
		(start 253.600458 -368.591846)
		(end 253.600458 -369.159282)
		(width 0.254)
		(layer "F.Cu")
		(net "MB3_CM_VOUT_R")
	)
	(segment
		(start 269.311882 -351.791016)
		(end 270.23949 -351.791016)
		(width 0.254)
		(layer "F.Cu")
		(net "MB3_CM_VOUT_R")
	)
	(segment
		(start 271.134586 -351.794826)
		(end 271.198848 -351.730564)
		(width 0.254)
		(layer "F.Cu")
		(net "MB3_CM_VOUT_R")
	)
	(segment
		(start 270.23949 -351.791016)
		(end 270.23568 -351.794826)
		(width 0.254)
		(layer "F.Cu")
		(net "MB3_CM_VOUT_R")
	)
	(via
		(at 271.198848 -351.730564)
		(size 0.5588)
		(drill 0.3048)
		(layers "F.Cu" "B.Cu")
		(net "MB3_CM_VOUT_R")
	)
	(via
		(at 270.23568 -351.794826)
		(size 0.6604)
		(drill 0.3302)
		(layers "F.Cu" "B.Cu")
		(net "MB3_CM_VOUT_R")
	)
	(via
		(at 253.858522 -370.333524)
		(size 0.5588)
		(drill 0.3048)
		(layers "F.Cu" "B.Cu")
		(net "MB3_CM_VOUT_R")
	)
	(segment
		(start 257.874008 -370.333524)
		(end 253.858522 -370.333524)
		(width 0.254)
		(layer "B.Cu")
		(net "MB3_CM_VOUT_R")
	)
	(segment
		(start 271.198848 -351.730564)
		(end 269.942564 -351.730564)
		(width 0.254)
		(layer "B.Cu")
		(net "MB3_CM_VOUT_R")
	)
	(segment
		(start 261.37235 -366.835182)
		(end 257.874008 -370.333524)
		(width 0.254)
		(layer "B.Cu")
		(net "MB3_CM_VOUT_R")
	)
	(segment
		(start 261.37235 -360.300778)
		(end 261.37235 -366.835182)
		(width 0.254)
		(layer "B.Cu")
		(net "MB3_CM_VOUT_R")
	)
	(segment
		(start 269.942564 -351.730564)
		(end 261.37235 -360.300778)
		(width 0.254)
		(layer "B.Cu")
		(net "MB3_CM_VOUT_R")
	)
	(segment
		(start 250.874022 -364.865412)
		(end 250.311412 -364.865412)
		(width 0.254)
		(layer "F.Cu")
		(net "MB3_CM_UV_R")
	)
	(segment
		(start 243.519452 -363.046772)
		(end 244.344952 -363.046772)
		(width 0.254)
		(layer "F.Cu")
		(net "MB3_CM_UV_R")
	)
	(segment
		(start 249.46229 -364.01629)
		(end 248.707402 -364.01629)
		(width 0.254)
		(layer "F.Cu")
		(net "MB3_CM_UV_R")
	)
	(segment
		(start 248.707402 -364.01629)
		(end 247.10644 -362.415328)
		(width 0.254)
		(layer "F.Cu")
		(net "MB3_CM_UV_R")
	)
	(segment
		(start 250.311412 -364.865412)
		(end 249.46229 -364.01629)
		(width 0.254)
		(layer "F.Cu")
		(net "MB3_CM_UV_R")
	)
	(segment
		(start 245.862094 -362.729272)
		(end 246.176038 -362.415328)
		(width 0.254)
		(layer "F.Cu")
		(net "MB3_CM_UV_R")
	)
	(segment
		(start 244.662452 -362.729272)
		(end 245.862094 -362.729272)
		(width 0.254)
		(layer "F.Cu")
		(net "MB3_CM_UV_R")
	)
	(segment
		(start 247.10644 -362.415328)
		(end 246.676926 -362.415328)
		(width 0.254)
		(layer "F.Cu")
		(net "MB3_CM_UV_R")
	)
	(segment
		(start 242.439952 -363.046772)
		(end 243.519452 -363.046772)
		(width 0.254)
		(layer "F.Cu")
		(net "MB3_CM_UV_R")
	)
	(segment
		(start 246.176038 -362.415328)
		(end 246.676926 -362.415328)
		(width 0.254)
		(layer "F.Cu")
		(net "MB3_CM_UV_R")
	)
	(segment
		(start 244.344952 -363.046772)
		(end 244.662452 -362.729272)
		(width 0.254)
		(layer "F.Cu")
		(net "MB3_CM_UV_R")
	)
	(via
		(at 246.676926 -362.415328)
		(size 0.6604)
		(drill 0.3302)
		(layers "F.Cu" "B.Cu")
		(net "MB3_CM_UV_R")
	)
	(segment
		(start 243.7384 -355.6508)
		(end 244.4496 -355.6508)
		(width 0.254)
		(layer "F.Cu")
		(net "MB3_CM_SENSE_R1_P")
	)
	(segment
		(start 240.817146 -344.671904)
		(end 243.624862 -344.671904)
		(width 0.254)
		(layer "F.Cu")
		(net "MB3_CM_SENSE_R1_P")
	)
	(segment
		(start 244.4496 -355.6508)
		(end 244.708934 -355.391466)
		(width 0.254)
		(layer "F.Cu")
		(net "MB3_CM_SENSE_R1_P")
	)
	(segment
		(start 244.708934 -355.391466)
		(end 244.708934 -354.447856)
		(width 0.254)
		(layer "F.Cu")
		(net "MB3_CM_SENSE_R1_P")
	)
	(segment
		(start 244.708934 -353.653344)
		(end 244.311678 -354.0506)
		(width 0.254)
		(layer "F.Cu")
		(net "MB3_CM_SENSE_R1_P")
	)
	(segment
		(start 243.624862 -344.671904)
		(end 244.708934 -345.755976)
		(width 0.254)
		(layer "F.Cu")
		(net "MB3_CM_SENSE_R1_P")
	)
	(segment
		(start 244.879368 -366.3696)
		(end 245.133622 -366.115346)
		(width 0.254)
		(layer "F.Cu")
		(net "MB3_CM_SENSE_R1_P")
	)
	(segment
		(start 244.708934 -354.447856)
		(end 244.311678 -354.0506)
		(width 0.254)
		(layer "F.Cu")
		(net "MB3_CM_SENSE_R1_P")
	)
	(segment
		(start 244.708934 -345.755976)
		(end 244.708934 -353.653344)
		(width 0.254)
		(layer "F.Cu")
		(net "MB3_CM_SENSE_R1_P")
	)
	(segment
		(start 243.5352 -355.4476)
		(end 243.7384 -355.6508)
		(width 0.254)
		(layer "F.Cu")
		(net "MB3_CM_SENSE_R1_P")
	)
	(segment
		(start 244.316758 -366.128554)
		(end 244.557804 -366.3696)
		(width 0.254)
		(layer "F.Cu")
		(net "MB3_CM_SENSE_R1_P")
	)
	(segment
		(start 244.557804 -366.3696)
		(end 244.879368 -366.3696)
		(width 0.254)
		(layer "F.Cu")
		(net "MB3_CM_SENSE_R1_P")
	)
	(via
		(at 244.316758 -366.128554)
		(size 0.5588)
		(drill 0.3048)
		(layers "F.Cu" "B.Cu")
		(net "MB3_CM_SENSE_R1_P")
	)
	(via
		(at 244.311678 -354.0506)
		(size 0.5588)
		(drill 0.3048)
		(layers "F.Cu" "B.Cu")
		(net "MB3_CM_SENSE_R1_P")
	)
	(segment
		(start 244.55755 -366.369346)
		(end 245.761256 -366.369346)
		(width 0.254)
		(layer "B.Cu")
		(net "MB3_CM_SENSE_R1_P")
	)
	(segment
		(start 246.141494 -357.418894)
		(end 244.7036 -355.981)
		(width 0.254)
		(layer "B.Cu")
		(net "MB3_CM_SENSE_R1_P")
	)
	(segment
		(start 245.761256 -366.369346)
		(end 246.141494 -365.989108)
		(width 0.254)
		(layer "B.Cu")
		(net "MB3_CM_SENSE_R1_P")
	)
	(segment
		(start 246.141494 -365.989108)
		(end 246.141494 -357.418894)
		(width 0.254)
		(layer "B.Cu")
		(net "MB3_CM_SENSE_R1_P")
	)
	(segment
		(start 244.316758 -366.128554)
		(end 244.55755 -366.369346)
		(width 0.254)
		(layer "B.Cu")
		(net "MB3_CM_SENSE_R1_P")
	)
	(segment
		(start 244.7036 -354.442522)
		(end 244.311678 -354.0506)
		(width 0.254)
		(layer "B.Cu")
		(net "MB3_CM_SENSE_R1_P")
	)
	(segment
		(start 244.7036 -355.981)
		(end 244.7036 -354.442522)
		(width 0.254)
		(layer "B.Cu")
		(net "MB3_CM_SENSE_R1_P")
	)
	(segment
		(start 245.216934 -355.602032)
		(end 245.216934 -354.447856)
		(width 0.254)
		(layer "F.Cu")
		(net "MB3_CM_SENSE_R1_N")
	)
	(segment
		(start 243.84 -356.1588)
		(end 244.660166 -356.1588)
		(width 0.254)
		(layer "F.Cu")
		(net "MB3_CM_SENSE_R1_N")
	)
	(segment
		(start 249.047254 -344.671904)
		(end 246.233696 -344.671904)
		(width 0.254)
		(layer "F.Cu")
		(net "MB3_CM_SENSE_R1_N")
	)
	(segment
		(start 244.316758 -367.118138)
		(end 244.557296 -366.8776)
		(width 0.254)
		(layer "F.Cu")
		(net "MB3_CM_SENSE_R1_N")
	)
	(segment
		(start 244.879876 -366.8776)
		(end 245.133622 -367.131346)
		(width 0.254)
		(layer "F.Cu")
		(net "MB3_CM_SENSE_R1_N")
	)
	(segment
		(start 246.233696 -344.671904)
		(end 245.216934 -345.688666)
		(width 0.254)
		(layer "F.Cu")
		(net "MB3_CM_SENSE_R1_N")
	)
	(segment
		(start 245.216934 -353.653344)
		(end 245.61419 -354.0506)
		(width 0.254)
		(layer "F.Cu")
		(net "MB3_CM_SENSE_R1_N")
	)
	(segment
		(start 244.660166 -356.1588)
		(end 245.216934 -355.602032)
		(width 0.254)
		(layer "F.Cu")
		(net "MB3_CM_SENSE_R1_N")
	)
	(segment
		(start 245.216934 -345.688666)
		(end 245.216934 -353.653344)
		(width 0.254)
		(layer "F.Cu")
		(net "MB3_CM_SENSE_R1_N")
	)
	(segment
		(start 243.5352 -356.4636)
		(end 243.84 -356.1588)
		(width 0.254)
		(layer "F.Cu")
		(net "MB3_CM_SENSE_R1_N")
	)
	(segment
		(start 245.216934 -354.447856)
		(end 245.61419 -354.0506)
		(width 0.254)
		(layer "F.Cu")
		(net "MB3_CM_SENSE_R1_N")
	)
	(segment
		(start 244.557296 -366.8776)
		(end 244.879876 -366.8776)
		(width 0.254)
		(layer "F.Cu")
		(net "MB3_CM_SENSE_R1_N")
	)
	(via
		(at 245.61419 -354.0506)
		(size 0.5588)
		(drill 0.3048)
		(layers "F.Cu" "B.Cu")
		(net "MB3_CM_SENSE_R1_N")
	)
	(via
		(at 244.316758 -367.118138)
		(size 0.5588)
		(drill 0.3048)
		(layers "F.Cu" "B.Cu")
		(net "MB3_CM_SENSE_R1_N")
	)
	(segment
		(start 246.649494 -357.208328)
		(end 245.2116 -355.770434)
		(width 0.254)
		(layer "B.Cu")
		(net "MB3_CM_SENSE_R1_N")
	)
	(segment
		(start 245.971822 -366.877346)
		(end 246.649494 -366.199674)
		(width 0.254)
		(layer "B.Cu")
		(net "MB3_CM_SENSE_R1_N")
	)
	(segment
		(start 245.2116 -355.770434)
		(end 245.2116 -354.45319)
		(width 0.254)
		(layer "B.Cu")
		(net "MB3_CM_SENSE_R1_N")
	)
	(segment
		(start 246.649494 -366.199674)
		(end 246.649494 -357.208328)
		(width 0.254)
		(layer "B.Cu")
		(net "MB3_CM_SENSE_R1_N")
	)
	(segment
		(start 244.316758 -367.118138)
		(end 244.55755 -366.877346)
		(width 0.254)
		(layer "B.Cu")
		(net "MB3_CM_SENSE_R1_N")
	)
	(segment
		(start 245.2116 -354.45319)
		(end 245.61419 -354.0506)
		(width 0.254)
		(layer "B.Cu")
		(net "MB3_CM_SENSE_R1_N")
	)
	(segment
		(start 244.55755 -366.877346)
		(end 245.971822 -366.877346)
		(width 0.254)
		(layer "B.Cu")
		(net "MB3_CM_SENSE_R1_N")
	)
	(segment
		(start 241.088672 -355.709728)
		(end 241.469672 -355.709728)
		(width 0.254)
		(layer "F.Cu")
		(net "MB3_CM_SENSE_P")
	)
	(segment
		(start 239.513872 -356.770178)
		(end 240.028222 -356.770178)
		(width 0.254)
		(layer "F.Cu")
		(net "MB3_CM_SENSE_P")
	)
	(segment
		(start 242.094766 -355.519228)
		(end 241.698526 -355.519228)
		(width 0.254)
		(layer "F.Cu")
		(net "MB3_CM_SENSE_P")
	)
	(segment
		(start 239.155986 -356.412292)
		(end 239.513872 -356.770178)
		(width 0.254)
		(layer "F.Cu")
		(net "MB3_CM_SENSE_P")
	)
	(segment
		(start 242.6462 -355.4476)
		(end 242.166394 -355.4476)
		(width 0.254)
		(layer "F.Cu")
		(net "MB3_CM_SENSE_P")
	)
	(segment
		(start 241.469672 -355.709728)
		(end 241.660172 -355.519228)
		(width 0.254)
		(layer "F.Cu")
		(net "MB3_CM_SENSE_P")
	)
	(segment
		(start 240.028222 -356.770178)
		(end 241.088672 -355.709728)
		(width 0.254)
		(layer "F.Cu")
		(net "MB3_CM_SENSE_P")
	)
	(segment
		(start 241.660172 -355.519228)
		(end 241.698526 -355.519228)
		(width 0.254)
		(layer "F.Cu")
		(net "MB3_CM_SENSE_P")
	)
	(segment
		(start 242.166394 -355.4476)
		(end 242.094766 -355.519228)
		(width 0.254)
		(layer "F.Cu")
		(net "MB3_CM_SENSE_P")
	)
	(segment
		(start 249.591322 -365.86541)
		(end 249.515122 -365.78921)
		(width 0.254)
		(layer "F.Cu")
		(net "MB3_CM_SENSE_P")
	)
	(segment
		(start 250.874022 -365.86541)
		(end 249.591322 -365.86541)
		(width 0.254)
		(layer "F.Cu")
		(net "MB3_CM_SENSE_P")
	)
	(via
		(at 239.155986 -356.412292)
		(size 0.5588)
		(drill 0.3048)
		(layers "F.Cu" "B.Cu")
		(net "MB3_CM_SENSE_P")
	)
	(via
		(at 249.515122 -365.78921)
		(size 0.5588)
		(drill 0.3048)
		(layers "F.Cu" "B.Cu")
		(net "MB3_CM_SENSE_P")
	)
	(segment
		(start 248.962926 -366.341406)
		(end 249.515122 -365.78921)
		(width 0.254)
		(layer "B.Cu")
		(net "MB3_CM_SENSE_P")
	)
	(segment
		(start 246.090694 -368.283998)
		(end 248.033286 -366.341406)
		(width 0.254)
		(layer "B.Cu")
		(net "MB3_CM_SENSE_P")
	)
	(segment
		(start 248.033286 -366.341406)
		(end 248.962926 -366.341406)
		(width 0.254)
		(layer "B.Cu")
		(net "MB3_CM_SENSE_P")
	)
	(segment
		(start 243.3574 -361.43057)
		(end 243.3574 -367.5634)
		(width 0.254)
		(layer "B.Cu")
		(net "MB3_CM_SENSE_P")
	)
	(segment
		(start 244.077998 -368.283998)
		(end 246.090694 -368.283998)
		(width 0.254)
		(layer "B.Cu")
		(net "MB3_CM_SENSE_P")
	)
	(segment
		(start 244.393212 -360.394758)
		(end 243.3574 -361.43057)
		(width 0.254)
		(layer "B.Cu")
		(net "MB3_CM_SENSE_P")
	)
	(segment
		(start 239.511586 -356.767892)
		(end 243.636292 -356.767892)
		(width 0.254)
		(layer "B.Cu")
		(net "MB3_CM_SENSE_P")
	)
	(segment
		(start 239.155986 -356.412292)
		(end 239.511586 -356.767892)
		(width 0.254)
		(layer "B.Cu")
		(net "MB3_CM_SENSE_P")
	)
	(segment
		(start 244.393212 -357.524812)
		(end 244.393212 -360.394758)
		(width 0.254)
		(layer "B.Cu")
		(net "MB3_CM_SENSE_P")
	)
	(segment
		(start 243.3574 -367.5634)
		(end 244.077998 -368.283998)
		(width 0.254)
		(layer "B.Cu")
		(net "MB3_CM_SENSE_P")
	)
	(segment
		(start 243.636292 -356.767892)
		(end 244.393212 -357.524812)
		(width 0.254)
		(layer "B.Cu")
		(net "MB3_CM_SENSE_P")
	)
	(segment
		(start 240.238788 -357.278178)
		(end 241.299238 -356.217728)
		(width 0.254)
		(layer "F.Cu")
		(net "MB3_CM_SENSE_N")
	)
	(segment
		(start 241.299238 -356.217728)
		(end 241.508026 -356.217728)
		(width 0.254)
		(layer "F.Cu")
		(net "MB3_CM_SENSE_N")
	)
	(segment
		(start 242.6462 -356.4636)
		(end 242.199668 -356.4636)
		(width 0.254)
		(layer "F.Cu")
		(net "MB3_CM_SENSE_N")
	)
	(segment
		(start 242.199668 -356.4636)
		(end 242.144296 -356.408228)
		(width 0.254)
		(layer "F.Cu")
		(net "MB3_CM_SENSE_N")
	)
	(segment
		(start 250.874022 -367.36528)
		(end 249.591322 -367.36528)
		(width 0.254)
		(layer "F.Cu")
		(net "MB3_CM_SENSE_N")
	)
	(segment
		(start 241.508026 -356.217728)
		(end 241.698526 -356.408228)
		(width 0.254)
		(layer "F.Cu")
		(net "MB3_CM_SENSE_N")
	)
	(segment
		(start 242.144296 -356.408228)
		(end 241.698526 -356.408228)
		(width 0.254)
		(layer "F.Cu")
		(net "MB3_CM_SENSE_N")
	)
	(segment
		(start 239.5601 -357.278178)
		(end 240.238788 -357.278178)
		(width 0.254)
		(layer "F.Cu")
		(net "MB3_CM_SENSE_N")
	)
	(segment
		(start 249.591322 -367.36528)
		(end 249.515122 -367.44148)
		(width 0.254)
		(layer "F.Cu")
		(net "MB3_CM_SENSE_N")
	)
	(segment
		(start 239.155986 -357.682292)
		(end 239.5601 -357.278178)
		(width 0.254)
		(layer "F.Cu")
		(net "MB3_CM_SENSE_N")
	)
	(via
		(at 249.515122 -367.44148)
		(size 0.5588)
		(drill 0.3048)
		(layers "F.Cu" "B.Cu")
		(net "MB3_CM_SENSE_N")
	)
	(via
		(at 239.155986 -357.682292)
		(size 0.5588)
		(drill 0.3048)
		(layers "F.Cu" "B.Cu")
		(net "MB3_CM_SENSE_N")
	)
	(segment
		(start 243.867432 -368.791998)
		(end 246.30126 -368.791998)
		(width 0.254)
		(layer "B.Cu")
		(net "MB3_CM_SENSE_N")
	)
	(segment
		(start 242.8494 -361.220004)
		(end 242.8494 -367.773966)
		(width 0.254)
		(layer "B.Cu")
		(net "MB3_CM_SENSE_N")
	)
	(segment
		(start 248.923048 -366.849406)
		(end 249.515122 -367.44148)
		(width 0.254)
		(layer "B.Cu")
		(net "MB3_CM_SENSE_N")
	)
	(segment
		(start 248.243852 -366.849406)
		(end 248.923048 -366.849406)
		(width 0.254)
		(layer "B.Cu")
		(net "MB3_CM_SENSE_N")
	)
	(segment
		(start 246.30126 -368.791998)
		(end 248.243852 -366.849406)
		(width 0.254)
		(layer "B.Cu")
		(net "MB3_CM_SENSE_N")
	)
	(segment
		(start 243.885212 -360.184192)
		(end 242.8494 -361.220004)
		(width 0.254)
		(layer "B.Cu")
		(net "MB3_CM_SENSE_N")
	)
	(segment
		(start 243.425726 -357.275892)
		(end 243.885212 -357.735378)
		(width 0.254)
		(layer "B.Cu")
		(net "MB3_CM_SENSE_N")
	)
	(segment
		(start 239.562386 -357.275892)
		(end 243.425726 -357.275892)
		(width 0.254)
		(layer "B.Cu")
		(net "MB3_CM_SENSE_N")
	)
	(segment
		(start 243.885212 -357.735378)
		(end 243.885212 -360.184192)
		(width 0.254)
		(layer "B.Cu")
		(net "MB3_CM_SENSE_N")
	)
	(segment
		(start 239.155986 -357.682292)
		(end 239.562386 -357.275892)
		(width 0.254)
		(layer "B.Cu")
		(net "MB3_CM_SENSE_N")
	)
	(segment
		(start 242.8494 -367.773966)
		(end 243.867432 -368.791998)
		(width 0.254)
		(layer "B.Cu")
		(net "MB3_CM_SENSE_N")
	)
	(segment
		(start 250.797822 -363.923072)
		(end 250.014994 -363.140244)
		(width 0.254)
		(layer "F.Cu")
		(net "MB3_CM_OV_R")
	)
	(segment
		(start 248.61266 -363.140244)
		(end 246.520208 -361.047792)
		(width 0.254)
		(layer "F.Cu")
		(net "MB3_CM_OV_R")
	)
	(segment
		(start 245.159784 -359.173272)
		(end 245.826534 -359.840022)
		(width 0.254)
		(layer "F.Cu")
		(net "MB3_CM_OV_R")
	)
	(segment
		(start 245.826534 -360.354118)
		(end 246.520208 -361.047792)
		(width 0.254)
		(layer "F.Cu")
		(net "MB3_CM_OV_R")
	)
	(segment
		(start 244.662452 -359.173272)
		(end 245.159784 -359.173272)
		(width 0.254)
		(layer "F.Cu")
		(net "MB3_CM_OV_R")
	)
	(segment
		(start 243.836952 -359.173272)
		(end 244.662452 -359.173272)
		(width 0.254)
		(layer "F.Cu")
		(net "MB3_CM_OV_R")
	)
	(segment
		(start 245.826534 -359.840022)
		(end 245.826534 -360.354118)
		(width 0.254)
		(layer "F.Cu")
		(net "MB3_CM_OV_R")
	)
	(segment
		(start 243.519452 -358.855772)
		(end 243.836952 -359.173272)
		(width 0.254)
		(layer "F.Cu")
		(net "MB3_CM_OV_R")
	)
	(segment
		(start 250.014994 -363.140244)
		(end 248.61266 -363.140244)
		(width 0.254)
		(layer "F.Cu")
		(net "MB3_CM_OV_R")
	)
	(segment
		(start 250.797822 -364.365286)
		(end 250.797822 -363.923072)
		(width 0.254)
		(layer "F.Cu")
		(net "MB3_CM_OV_R")
	)
	(segment
		(start 242.439952 -358.855772)
		(end 243.519452 -358.855772)
		(width 0.254)
		(layer "F.Cu")
		(net "MB3_CM_OV_R")
	)
	(via
		(at 246.520208 -361.047792)
		(size 0.6604)
		(drill 0.3302)
		(layers "F.Cu" "B.Cu")
		(net "MB3_CM_OV_R")
	)
	(via
		(at 268.106144 -354.007674)
		(size 0.6604)
		(drill 0.3302)
		(layers "F.Cu" "B.Cu")
		(net "MB3_CM_GATE_R")
	)
	(via
		(at 267.949172 -350.860106)
		(size 0.5588)
		(drill 0.3048)
		(layers "F.Cu" "B.Cu")
		(net "MB3_CM_GATE_R")
	)
	(via
		(at 267.949172 -337.931506)
		(size 0.5588)
		(drill 0.3048)
		(layers "F.Cu" "B.Cu")
		(net "MB3_CM_GATE_R")
	)
	(via
		(at 267.949172 -343.798906)
		(size 0.5588)
		(drill 0.3048)
		(layers "F.Cu" "B.Cu")
		(net "MB3_CM_GATE_R")
	)
	(via
		(at 267.949172 -352.053906)
		(size 0.5588)
		(drill 0.3048)
		(layers "F.Cu" "B.Cu")
		(net "MB3_CM_GATE_R")
	)
	(via
		(at 267.949172 -336.737706)
		(size 0.5588)
		(drill 0.3048)
		(layers "F.Cu" "B.Cu")
		(net "MB3_CM_GATE_R")
	)
	(via
		(at 267.949172 -344.992706)
		(size 0.5588)
		(drill 0.3048)
		(layers "F.Cu" "B.Cu")
		(net "MB3_CM_GATE_R")
	)
	(segment
		(start 267.949172 -337.931506)
		(end 267.949172 -336.737706)
		(width 1.524)
		(layer "In2.Cu")
		(net "MB3_CM_GATE_R")
	)
	(segment
		(start 267.949172 -343.798906)
		(end 267.949172 -337.931506)
		(width 1.524)
		(layer "In2.Cu")
		(net "MB3_CM_GATE_R")
	)
	(segment
		(start 267.949172 -350.860106)
		(end 267.949172 -344.992706)
		(width 1.524)
		(layer "In2.Cu")
		(net "MB3_CM_GATE_R")
	)
	(segment
		(start 267.949172 -344.992706)
		(end 267.949172 -343.798906)
		(width 1.524)
		(layer "In2.Cu")
		(net "MB3_CM_GATE_R")
	)
	(segment
		(start 267.949172 -350.860106)
		(end 267.949172 -352.053906)
		(width 1.524)
		(layer "In2.Cu")
		(net "MB3_CM_GATE_R")
	)
	(via
		(at 250.844304 -368.669316)
		(size 0.5588)
		(drill 0.3048)
		(layers "F.Cu" "B.Cu")
		(net "MB3_CM_GATE")
	)
	(via
		(at 261.9756 -355.3968)
		(size 0.5588)
		(drill 0.3048)
		(layers "F.Cu" "B.Cu")
		(net "MB3_CM_GATE")
	)
	(via
		(at 263.4996 -355.7524)
		(size 0.5588)
		(drill 0.3048)
		(layers "F.Cu" "B.Cu")
		(net "MB3_CM_GATE")
	)
	(via
		(at 250.844304 -369.583716)
		(size 0.5588)
		(drill 0.3048)
		(layers "F.Cu" "B.Cu")
		(net "MB3_CM_GATE")
	)
	(via
		(at 262.9154 -354.9142)
		(size 0.6604)
		(drill 0.3302)
		(layers "F.Cu" "B.Cu")
		(net "MB3_CM_GATE")
	)
	(segment
		(start 258.6228 -365.9378)
		(end 255.9304 -368.6302)
		(width 1.524)
		(layer "B.Cu")
		(net "MB3_CM_GATE")
	)
	(segment
		(start 255.9304 -368.6302)
		(end 252.2728 -368.6302)
		(width 1.524)
		(layer "B.Cu")
		(net "MB3_CM_GATE")
	)
	(segment
		(start 261.0104 -356.9716)
		(end 258.6228 -359.3592)
		(width 1.524)
		(layer "B.Cu")
		(net "MB3_CM_GATE")
	)
	(segment
		(start 258.6228 -359.3592)
		(end 258.6228 -365.9378)
		(width 1.524)
		(layer "B.Cu")
		(net "MB3_CM_GATE")
	)
	(segment
		(start 259.256022 -362.305346)
		(end 258.049522 -362.305346)
		(width 0.254)
		(layer "F.Cu")
		(net "MB3_CM_ADR2_R")
	)
	(segment
		(start 257.033522 -362.305346)
		(end 258.049522 -362.305346)
		(width 0.254)
		(layer "F.Cu")
		(net "MB3_CM_ADR2_R")
	)
	(segment
		(start 255.776222 -363.562646)
		(end 257.033522 -362.305346)
		(width 0.254)
		(layer "F.Cu")
		(net "MB3_CM_ADR2_R")
	)
	(segment
		(start 255.100582 -363.562646)
		(end 255.776222 -363.562646)
		(width 0.254)
		(layer "F.Cu")
		(net "MB3_CM_ADR2_R")
	)
	(via
		(at 258.049522 -362.305346)
		(size 0.6604)
		(drill 0.3302)
		(layers "F.Cu" "B.Cu")
		(net "MB3_CM_ADR2_R")
	)
	(segment
		(start 256.779522 -360.844846)
		(end 256.779522 -361.543346)
		(width 0.254)
		(layer "F.Cu")
		(net "MB3_CM_ADR1_R")
	)
	(segment
		(start 255.509522 -362.178346)
		(end 256.144522 -362.178346)
		(width 0.254)
		(layer "F.Cu")
		(net "MB3_CM_ADR1_R")
	)
	(segment
		(start 256.779522 -361.543346)
		(end 256.144522 -362.178346)
		(width 0.254)
		(layer "F.Cu")
		(net "MB3_CM_ADR1_R")
	)
	(segment
		(start 254.600456 -363.087412)
		(end 255.509522 -362.178346)
		(width 0.254)
		(layer "F.Cu")
		(net "MB3_CM_ADR1_R")
	)
	(segment
		(start 254.600456 -363.638846)
		(end 254.600456 -363.087412)
		(width 0.254)
		(layer "F.Cu")
		(net "MB3_CM_ADR1_R")
	)
	(via
		(at 256.144522 -362.178346)
		(size 0.6604)
		(drill 0.3302)
		(layers "F.Cu" "B.Cu")
		(net "MB3_CM_ADR1_R")
	)
	(via
		(at 263.114028 -337.079336)
		(size 0.6604)
		(drill 0.3302)
		(layers "F.Cu" "B.Cu")
		(net "MB3_12V_CTRL_GATE3")
	)
	(via
		(at 263.366758 -344.45321)
		(size 0.6604)
		(drill 0.3302)
		(layers "F.Cu" "B.Cu")
		(net "MB3_12V_CTRL_GATE2")
	)
	(via
		(at 263.061704 -351.354644)
		(size 0.6604)
		(drill 0.3302)
		(layers "F.Cu" "B.Cu")
		(net "MB3_12V_CTRL_GATE1")
	)
	(segment
		(start 259.383022 -363.575346)
		(end 260.462522 -363.575346)
		(width 0.254)
		(layer "F.Cu")
		(net "AGND_CURRENT_DPB")
	)
	(segment
		(start 248.778522 -358.431846)
		(end 248.778522 -357.377746)
		(width 0.254)
		(layer "F.Cu")
		(net "AGND_CURRENT_DPB")
	)
	(segment
		(start 260.462522 -363.575346)
		(end 260.462522 -362.622846)
		(width 0.254)
		(layer "F.Cu")
		(net "AGND_CURRENT_DPB")
	)
	(segment
		(start 252.60046 -368.591846)
		(end 252.60046 -366.865408)
		(width 0.254)
		(layer "F.Cu")
		(net "AGND_CURRENT_DPB")
	)
	(segment
		(start 247.762522 -358.431846)
		(end 247.762522 -357.5558)
		(width 0.254)
		(layer "F.Cu")
		(net "AGND_CURRENT_DPB")
	)
	(segment
		(start 260.462522 -362.622846)
		(end 260.145022 -362.305346)
		(width 0.254)
		(layer "F.Cu")
		(net "AGND_CURRENT_DPB")
	)
	(segment
		(start 254.112522 -358.177846)
		(end 254.112522 -357.3018)
		(width 0.254)
		(layer "F.Cu")
		(net "AGND_CURRENT_DPB")
	)
	(segment
		(start 251.064522 -358.177846)
		(end 251.064522 -357.3018)
		(width 0.254)
		(layer "F.Cu")
		(net "AGND_CURRENT_DPB")
	)
	(segment
		(start 255.509522 -358.177846)
		(end 255.509522 -357.3018)
		(width 0.254)
		(layer "F.Cu")
		(net "AGND_CURRENT_DPB")
	)
	(segment
		(start 246.238522 -364.845346)
		(end 245.222522 -364.845346)
		(width 0.254)
		(layer "F.Cu")
		(net "AGND_CURRENT_DPB")
	)
	(segment
		(start 260.145022 -362.305346)
		(end 260.145022 -361.416346)
		(width 0.254)
		(layer "F.Cu")
		(net "AGND_CURRENT_DPB")
	)
	(segment
		(start 253.57455 -372.791736)
		(end 253.57455 -373.744236)
		(width 0.254)
		(layer "F.Cu")
		(net "AGND_CURRENT_DPB")
	)
	(segment
		(start 249.921522 -358.495346)
		(end 249.921522 -357.479346)
		(width 0.254)
		(layer "F.Cu")
		(net "AGND_CURRENT_DPB")
	)
	(segment
		(start 252.080522 -358.177846)
		(end 252.080522 -357.3018)
		(width 0.254)
		(layer "F.Cu")
		(net "AGND_CURRENT_DPB")
	)
	(segment
		(start 252.60046 -366.865408)
		(end 253.350522 -366.115346)
		(width 0.254)
		(layer "F.Cu")
		(net "AGND_CURRENT_DPB")
	)
	(segment
		(start 254.537972 -372.77421)
		(end 254.537972 -373.72671)
		(width 0.254)
		(layer "F.Cu")
		(net "AGND_CURRENT_DPB")
	)
	(segment
		(start 256.779522 -359.955846)
		(end 256.779522 -359.130346)
		(width 0.254)
		(layer "F.Cu")
		(net "AGND_CURRENT_DPB")
	)
	(segment
		(start 253.096522 -358.177846)
		(end 253.096522 -357.3272)
		(width 0.254)
		(layer "F.Cu")
		(net "AGND_CURRENT_DPB")
	)
	(via
		(at 260.145022 -361.416346)
		(size 0.5588)
		(drill 0.3048)
		(layers "F.Cu" "B.Cu")
		(net "AGND_CURRENT_DPB")
	)
	(via
		(at 249.921522 -357.479346)
		(size 0.5588)
		(drill 0.3048)
		(layers "F.Cu" "B.Cu")
		(net "AGND_CURRENT_DPB")
	)
	(via
		(at 253.096522 -357.3272)
		(size 0.5588)
		(drill 0.3048)
		(layers "F.Cu" "B.Cu")
		(net "AGND_CURRENT_DPB")
	)
	(via
		(at 254.112522 -357.3018)
		(size 0.5588)
		(drill 0.3048)
		(layers "F.Cu" "B.Cu")
		(net "AGND_CURRENT_DPB")
	)
	(via
		(at 242.227608 -360.869992)
		(size 0.6604)
		(drill 0.3302)
		(layers "F.Cu" "B.Cu")
		(net "AGND_CURRENT_DPB")
	)
	(via
		(at 255.509522 -357.3018)
		(size 0.5588)
		(drill 0.3048)
		(layers "F.Cu" "B.Cu")
		(net "AGND_CURRENT_DPB")
	)
	(via
		(at 253.57455 -373.744236)
		(size 0.5588)
		(drill 0.3048)
		(layers "F.Cu" "B.Cu")
		(net "AGND_CURRENT_DPB")
	)
	(via
		(at 252.080522 -366.115346)
		(size 0.5588)
		(drill 0.3048)
		(layers "F.Cu" "B.Cu")
		(net "AGND_CURRENT_DPB")
	)
	(via
		(at 253.350522 -366.115346)
		(size 0.5588)
		(drill 0.3048)
		(layers "F.Cu" "B.Cu")
		(net "AGND_CURRENT_DPB")
	)
	(via
		(at 253.350522 -364.845346)
		(size 0.5588)
		(drill 0.3048)
		(layers "F.Cu" "B.Cu")
		(net "AGND_CURRENT_DPB")
	)
	(via
		(at 245.222522 -364.845346)
		(size 0.5588)
		(drill 0.3048)
		(layers "F.Cu" "B.Cu")
		(net "AGND_CURRENT_DPB")
	)
	(via
		(at 248.778522 -357.377746)
		(size 0.5588)
		(drill 0.3048)
		(layers "F.Cu" "B.Cu")
		(net "AGND_CURRENT_DPB")
	)
	(via
		(at 245.06174 -360.977688)
		(size 0.5588)
		(drill 0.3048)
		(layers "F.Cu" "B.Cu")
		(net "AGND_CURRENT_DPB")
	)
	(via
		(at 254.537972 -373.72671)
		(size 0.5588)
		(drill 0.3048)
		(layers "F.Cu" "B.Cu")
		(net "AGND_CURRENT_DPB")
	)
	(via
		(at 252.080522 -357.3018)
		(size 0.5588)
		(drill 0.3048)
		(layers "F.Cu" "B.Cu")
		(net "AGND_CURRENT_DPB")
	)
	(via
		(at 254.620522 -366.115346)
		(size 0.5588)
		(drill 0.3048)
		(layers "F.Cu" "B.Cu")
		(net "AGND_CURRENT_DPB")
	)
	(via
		(at 247.762522 -357.5558)
		(size 0.5588)
		(drill 0.3048)
		(layers "F.Cu" "B.Cu")
		(net "AGND_CURRENT_DPB")
	)
	(via
		(at 256.779522 -359.130346)
		(size 0.5588)
		(drill 0.3048)
		(layers "F.Cu" "B.Cu")
		(net "AGND_CURRENT_DPB")
	)
	(via
		(at 251.064522 -357.3018)
		(size 0.5588)
		(drill 0.3048)
		(layers "F.Cu" "B.Cu")
		(net "AGND_CURRENT_DPB")
	)
	(via
		(at 253.350522 -367.385346)
		(size 0.5588)
		(drill 0.3048)
		(layers "F.Cu" "B.Cu")
		(net "AGND_CURRENT_DPB")
	)
	(segment
		(start 306.932076 -340.368382)
		(end 305.662076 -340.368382)
		(width 0.17145)
		(layer "F.Cu")
		(net "PWM_CAMP_SEL1")
	)
	(segment
		(start 305.662076 -340.368382)
		(end 305.408076 -340.114382)
		(width 0.17145)
		(layer "F.Cu")
		(net "PWM_CAMP_SEL1")
	)
	(segment
		(start 305.408076 -339.128354)
		(end 305.408076 -337.015582)
		(width 0.17145)
		(layer "F.Cu")
		(net "PWM_CAMP_SEL1")
	)
	(segment
		(start 305.408076 -340.114382)
		(end 305.408076 -339.128354)
		(width 0.17145)
		(layer "F.Cu")
		(net "PWM_CAMP_SEL1")
	)
	(via
		(at 305.408076 -339.128354)
		(size 0.6604)
		(drill 0.3302)
		(layers "F.Cu" "B.Cu")
		(net "PWM_CAMP_SEL1")
	)
	(segment
		(start 218.35872 -195.71208)
		(end 218.6178 -195.453)
		(width 0.17145)
		(layer "F.Cu")
		(net "IO_EXP2_LED_SDA")
	)
	(segment
		(start 220.1037 -195.453)
		(end 219.1004 -195.453)
		(width 0.17145)
		(layer "F.Cu")
		(net "IO_EXP2_LED_SDA")
	)
	(segment
		(start 220.2307 -195.58)
		(end 220.1037 -195.453)
		(width 0.17145)
		(layer "F.Cu")
		(net "IO_EXP2_LED_SDA")
	)
	(segment
		(start 218.6178 -195.453)
		(end 219.1004 -195.453)
		(width 0.17145)
		(layer "F.Cu")
		(net "IO_EXP2_LED_SDA")
	)
	(segment
		(start 217.2716 -195.71208)
		(end 218.35872 -195.71208)
		(width 0.17145)
		(layer "F.Cu")
		(net "IO_EXP2_LED_SDA")
	)
	(via
		(at 219.1004 -195.453)
		(size 0.6604)
		(drill 0.3302)
		(layers "F.Cu" "B.Cu")
		(net "IO_EXP2_LED_SDA")
	)
	(segment
		(start 217.2716 -195.06184)
		(end 218.11996 -195.06184)
		(width 0.17145)
		(layer "F.Cu")
		(net "IO_EXP2_LED_SCL")
	)
	(segment
		(start 220.2307 -194.437)
		(end 220.1545 -194.3608)
		(width 0.17145)
		(layer "F.Cu")
		(net "IO_EXP2_LED_SCL")
	)
	(segment
		(start 218.11996 -195.06184)
		(end 218.4908 -194.691)
		(width 0.17145)
		(layer "F.Cu")
		(net "IO_EXP2_LED_SCL")
	)
	(segment
		(start 220.1545 -194.3608)
		(end 219.2274 -194.3608)
		(width 0.17145)
		(layer "F.Cu")
		(net "IO_EXP2_LED_SCL")
	)
	(segment
		(start 218.4908 -194.691)
		(end 218.8972 -194.691)
		(width 0.17145)
		(layer "F.Cu")
		(net "IO_EXP2_LED_SCL")
	)
	(segment
		(start 218.8972 -194.691)
		(end 219.2274 -194.3608)
		(width 0.17145)
		(layer "F.Cu")
		(net "IO_EXP2_LED_SCL")
	)
	(via
		(at 219.2274 -194.3608)
		(size 0.6604)
		(drill 0.3302)
		(layers "F.Cu" "B.Cu")
		(net "IO_EXP2_LED_SCL")
	)
	(segment
		(start 208.915 -195.326)
		(end 208.534 -194.945)
		(width 0.17145)
		(layer "F.Cu")
		(net "IO_EXP2_HDD_FAULT_A2")
	)
	(segment
		(start 208.534 -194.945)
		(end 207.7847 -194.945)
		(width 0.17145)
		(layer "F.Cu")
		(net "IO_EXP2_HDD_FAULT_A2")
	)
	(segment
		(start 210.22056 -195.06184)
		(end 209.9564 -195.326)
		(width 0.17145)
		(layer "F.Cu")
		(net "IO_EXP2_HDD_FAULT_A2")
	)
	(segment
		(start 211.6328 -195.06184)
		(end 210.22056 -195.06184)
		(width 0.17145)
		(layer "F.Cu")
		(net "IO_EXP2_HDD_FAULT_A2")
	)
	(segment
		(start 207.7847 -194.945)
		(end 207.7847 -196.088)
		(width 0.17145)
		(layer "F.Cu")
		(net "IO_EXP2_HDD_FAULT_A2")
	)
	(segment
		(start 209.296 -195.326)
		(end 208.915 -195.326)
		(width 0.17145)
		(layer "F.Cu")
		(net "IO_EXP2_HDD_FAULT_A2")
	)
	(segment
		(start 209.9564 -195.326)
		(end 209.296 -195.326)
		(width 0.17145)
		(layer "F.Cu")
		(net "IO_EXP2_HDD_FAULT_A2")
	)
	(via
		(at 209.296 -195.326)
		(size 0.6604)
		(drill 0.3302)
		(layers "F.Cu" "B.Cu")
		(net "IO_EXP2_HDD_FAULT_A2")
	)
	(segment
		(start 211.6328 -195.71208)
		(end 210.56092 -195.71208)
		(width 0.17145)
		(layer "F.Cu")
		(net "IO_EXP2_HDD_FAULT_A1")
	)
	(segment
		(start 209.423 -196.85)
		(end 209.042 -197.231)
		(width 0.17145)
		(layer "F.Cu")
		(net "IO_EXP2_HDD_FAULT_A1")
	)
	(segment
		(start 209.042 -197.231)
		(end 207.7847 -197.231)
		(width 0.17145)
		(layer "F.Cu")
		(net "IO_EXP2_HDD_FAULT_A1")
	)
	(segment
		(start 207.7847 -197.231)
		(end 207.7847 -198.374)
		(width 0.17145)
		(layer "F.Cu")
		(net "IO_EXP2_HDD_FAULT_A1")
	)
	(segment
		(start 210.56092 -195.71208)
		(end 209.423 -196.85)
		(width 0.17145)
		(layer "F.Cu")
		(net "IO_EXP2_HDD_FAULT_A1")
	)
	(via
		(at 209.423 -196.85)
		(size 0.6604)
		(drill 0.3302)
		(layers "F.Cu" "B.Cu")
		(net "IO_EXP2_HDD_FAULT_A1")
	)
	(segment
		(start 219.9767 -193.04)
		(end 220.2307 -193.294)
		(width 0.17145)
		(layer "F.Cu")
		(net "IO_EXP2_HDD_FAULT_A0")
	)
	(segment
		(start 219.075 -193.04)
		(end 219.9767 -193.04)
		(width 0.17145)
		(layer "F.Cu")
		(net "IO_EXP2_HDD_FAULT_A0")
	)
	(segment
		(start 218.313 -194.0052)
		(end 218.313 -193.675)
		(width 0.17145)
		(layer "F.Cu")
		(net "IO_EXP2_HDD_FAULT_A0")
	)
	(segment
		(start 217.2716 -194.4116)
		(end 217.9066 -194.4116)
		(width 0.17145)
		(layer "F.Cu")
		(net "IO_EXP2_HDD_FAULT_A0")
	)
	(segment
		(start 217.9066 -194.4116)
		(end 218.313 -194.0052)
		(width 0.17145)
		(layer "F.Cu")
		(net "IO_EXP2_HDD_FAULT_A0")
	)
	(segment
		(start 220.2307 -193.294)
		(end 220.2307 -192.151)
		(width 0.17145)
		(layer "F.Cu")
		(net "IO_EXP2_HDD_FAULT_A0")
	)
	(segment
		(start 218.948 -193.04)
		(end 219.075 -193.04)
		(width 0.17145)
		(layer "F.Cu")
		(net "IO_EXP2_HDD_FAULT_A0")
	)
	(segment
		(start 218.313 -193.675)
		(end 218.948 -193.04)
		(width 0.17145)
		(layer "F.Cu")
		(net "IO_EXP2_HDD_FAULT_A0")
	)
	(via
		(at 219.075 -193.04)
		(size 0.6604)
		(drill 0.3302)
		(layers "F.Cu" "B.Cu")
		(net "IO_EXP2_HDD_FAULT_A0")
	)
	(segment
		(start 221.5515 -224.282)
		(end 220.3069 -224.282)
		(width 0.17145)
		(layer "F.Cu")
		(net "IO_EXP1_LED_SDA")
	)
	(segment
		(start 219.4052 -224.282)
		(end 220.3069 -224.282)
		(width 0.17145)
		(layer "F.Cu")
		(net "IO_EXP1_LED_SDA")
	)
	(segment
		(start 218.5924 -224.16008)
		(end 219.28328 -224.16008)
		(width 0.17145)
		(layer "F.Cu")
		(net "IO_EXP1_LED_SDA")
	)
	(segment
		(start 219.28328 -224.16008)
		(end 219.4052 -224.282)
		(width 0.17145)
		(layer "F.Cu")
		(net "IO_EXP1_LED_SDA")
	)
	(via
		(at 220.3069 -224.282)
		(size 0.6604)
		(drill 0.3302)
		(layers "F.Cu" "B.Cu")
		(net "IO_EXP1_LED_SDA")
	)
	(segment
		(start 219.633292 -223.50984)
		(end 220.080332 -223.0628)
		(width 0.17145)
		(layer "F.Cu")
		(net "IO_EXP1_LED_SCL")
	)
	(segment
		(start 220.080332 -223.0628)
		(end 220.3958 -223.0628)
		(width 0.17145)
		(layer "F.Cu")
		(net "IO_EXP1_LED_SCL")
	)
	(segment
		(start 218.5924 -223.50984)
		(end 219.633292 -223.50984)
		(width 0.17145)
		(layer "F.Cu")
		(net "IO_EXP1_LED_SCL")
	)
	(segment
		(start 220.94825 -223.139)
		(end 220.87205 -223.0628)
		(width 0.17145)
		(layer "F.Cu")
		(net "IO_EXP1_LED_SCL")
	)
	(segment
		(start 221.5515 -223.139)
		(end 220.94825 -223.139)
		(width 0.17145)
		(layer "F.Cu")
		(net "IO_EXP1_LED_SCL")
	)
	(segment
		(start 220.87205 -223.0628)
		(end 220.3958 -223.0628)
		(width 0.17145)
		(layer "F.Cu")
		(net "IO_EXP1_LED_SCL")
	)
	(via
		(at 220.3958 -223.0628)
		(size 0.6604)
		(drill 0.3302)
		(layers "F.Cu" "B.Cu")
		(net "IO_EXP1_LED_SCL")
	)
	(segment
		(start 210.791806 -223.71939)
		(end 210.354164 -223.71939)
		(width 0.17145)
		(layer "F.Cu")
		(net "IO_EXP1_HDD_FAULT_A2")
	)
	(segment
		(start 210.973416 -223.901)
		(end 210.791806 -223.71939)
		(width 0.17145)
		(layer "F.Cu")
		(net "IO_EXP1_HDD_FAULT_A2")
	)
	(segment
		(start 210.354164 -223.71939)
		(end 210.219798 -223.585024)
		(width 0.17145)
		(layer "F.Cu")
		(net "IO_EXP1_HDD_FAULT_A2")
	)
	(segment
		(start 211.328 -223.901)
		(end 210.973416 -223.901)
		(width 0.17145)
		(layer "F.Cu")
		(net "IO_EXP1_HDD_FAULT_A2")
	)
	(segment
		(start 210.219798 -223.585024)
		(end 210.219798 -224.651062)
		(width 0.17145)
		(layer "F.Cu")
		(net "IO_EXP1_HDD_FAULT_A2")
	)
	(segment
		(start 211.71916 -223.50984)
		(end 211.328 -223.901)
		(width 0.17145)
		(layer "F.Cu")
		(net "IO_EXP1_HDD_FAULT_A2")
	)
	(segment
		(start 212.9536 -223.50984)
		(end 211.71916 -223.50984)
		(width 0.17145)
		(layer "F.Cu")
		(net "IO_EXP1_HDD_FAULT_A2")
	)
	(via
		(at 211.328 -223.901)
		(size 0.6604)
		(drill 0.3302)
		(layers "F.Cu" "B.Cu")
		(net "IO_EXP1_HDD_FAULT_A2")
	)
	(segment
		(start 212.9536 -224.16008)
		(end 212.36305 -224.16008)
		(width 0.17145)
		(layer "F.Cu")
		(net "IO_EXP1_HDD_FAULT_A1")
	)
	(segment
		(start 211.328 -225.298)
		(end 210.947 -225.679)
		(width 0.17145)
		(layer "F.Cu")
		(net "IO_EXP1_HDD_FAULT_A1")
	)
	(segment
		(start 211.328 -225.19513)
		(end 211.328 -225.298)
		(width 0.17145)
		(layer "F.Cu")
		(net "IO_EXP1_HDD_FAULT_A1")
	)
	(segment
		(start 212.36305 -224.16008)
		(end 211.328 -225.19513)
		(width 0.17145)
		(layer "F.Cu")
		(net "IO_EXP1_HDD_FAULT_A1")
	)
	(segment
		(start 210.947 -225.679)
		(end 210.2485 -225.679)
		(width 0.17145)
		(layer "F.Cu")
		(net "IO_EXP1_HDD_FAULT_A1")
	)
	(segment
		(start 210.2485 -225.679)
		(end 210.2485 -226.822)
		(width 0.17145)
		(layer "F.Cu")
		(net "IO_EXP1_HDD_FAULT_A1")
	)
	(via
		(at 211.328 -225.298)
		(size 0.6604)
		(drill 0.3302)
		(layers "F.Cu" "B.Cu")
		(net "IO_EXP1_HDD_FAULT_A1")
	)
	(segment
		(start 220.98 -221.869)
		(end 221.107 -221.996)
		(width 0.17145)
		(layer "F.Cu")
		(net "IO_EXP1_HDD_FAULT_A0")
	)
	(segment
		(start 219.2528 -222.8596)
		(end 220.2434 -221.869)
		(width 0.17145)
		(layer "F.Cu")
		(net "IO_EXP1_HDD_FAULT_A0")
	)
	(segment
		(start 218.5924 -222.8596)
		(end 219.2528 -222.8596)
		(width 0.17145)
		(layer "F.Cu")
		(net "IO_EXP1_HDD_FAULT_A0")
	)
	(segment
		(start 221.5515 -221.996)
		(end 221.5515 -220.853)
		(width 0.17145)
		(layer "F.Cu")
		(net "IO_EXP1_HDD_FAULT_A0")
	)
	(segment
		(start 220.3958 -221.869)
		(end 220.98 -221.869)
		(width 0.17145)
		(layer "F.Cu")
		(net "IO_EXP1_HDD_FAULT_A0")
	)
	(segment
		(start 221.107 -221.996)
		(end 221.5515 -221.996)
		(width 0.17145)
		(layer "F.Cu")
		(net "IO_EXP1_HDD_FAULT_A0")
	)
	(segment
		(start 220.2434 -221.869)
		(end 220.3958 -221.869)
		(width 0.17145)
		(layer "F.Cu")
		(net "IO_EXP1_HDD_FAULT_A0")
	)
	(via
		(at 220.3958 -221.869)
		(size 0.6604)
		(drill 0.3302)
		(layers "F.Cu" "B.Cu")
		(net "IO_EXP1_HDD_FAULT_A0")
	)
	(segment
		(start 472.388184 -75.913996)
		(end 472.388184 -82.642964)
		(width 0.254)
		(layer "F.Cu")
		(net "FLT_HDD23")
	)
	(segment
		(start 472.388184 -82.642964)
		(end 467.125558 -87.90559)
		(width 0.254)
		(layer "F.Cu")
		(net "FLT_HDD23")
	)
	(segment
		(start 472.399614 -66.13017)
		(end 472.399614 -75.902566)
		(width 0.254)
		(layer "F.Cu")
		(net "FLT_HDD23")
	)
	(segment
		(start 464.0834 -90.947748)
		(end 467.125558 -87.90559)
		(width 0.254)
		(layer "F.Cu")
		(net "FLT_HDD23")
	)
	(segment
		(start 472.399614 -75.902566)
		(end 472.388184 -75.913996)
		(width 0.254)
		(layer "F.Cu")
		(net "FLT_HDD23")
	)
	(segment
		(start 464.0834 -98.6282)
		(end 464.0834 -90.947748)
		(width 0.254)
		(layer "F.Cu")
		(net "FLT_HDD23")
	)
	(via
		(at 467.125558 -87.90559)
		(size 0.6604)
		(drill 0.3302)
		(layers "F.Cu" "B.Cu")
		(net "FLT_HDD23")
	)
	(segment
		(start 440.69 -98.425)
		(end 440.69 -95.095822)
		(width 0.254)
		(layer "F.Cu")
		(net "FLT_HDD22")
	)
	(segment
		(start 440.849512 -94.93631)
		(end 440.849512 -86.207092)
		(width 0.254)
		(layer "F.Cu")
		(net "FLT_HDD22")
	)
	(segment
		(start 440.69 -95.095822)
		(end 440.849512 -94.93631)
		(width 0.254)
		(layer "F.Cu")
		(net "FLT_HDD22")
	)
	(segment
		(start 440.849512 -66.13017)
		(end 440.849512 -86.207092)
		(width 0.254)
		(layer "F.Cu")
		(net "FLT_HDD22")
	)
	(via
		(at 440.849512 -86.207092)
		(size 0.6604)
		(drill 0.3302)
		(layers "F.Cu" "B.Cu")
		(net "FLT_HDD22")
	)
	(segment
		(start 409.299664 -94.792038)
		(end 409.299664 -86.529164)
		(width 0.254)
		(layer "F.Cu")
		(net "FLT_HDD21")
	)
	(segment
		(start 409.299664 -66.13017)
		(end 409.299664 -86.529164)
		(width 0.254)
		(layer "F.Cu")
		(net "FLT_HDD21")
	)
	(segment
		(start 409.194 -98.425)
		(end 409.194 -94.897702)
		(width 0.254)
		(layer "F.Cu")
		(net "FLT_HDD21")
	)
	(segment
		(start 409.194 -94.897702)
		(end 409.299664 -94.792038)
		(width 0.254)
		(layer "F.Cu")
		(net "FLT_HDD21")
	)
	(via
		(at 409.299664 -86.529164)
		(size 0.6604)
		(drill 0.3302)
		(layers "F.Cu" "B.Cu")
		(net "FLT_HDD21")
	)
	(segment
		(start 377.749562 -95.162878)
		(end 377.749562 -86.97976)
		(width 0.254)
		(layer "F.Cu")
		(net "FLT_HDD20")
	)
	(segment
		(start 377.698 -95.21444)
		(end 377.749562 -95.162878)
		(width 0.254)
		(layer "F.Cu")
		(net "FLT_HDD20")
	)
	(segment
		(start 377.698 -98.425)
		(end 377.698 -95.21444)
		(width 0.254)
		(layer "F.Cu")
		(net "FLT_HDD20")
	)
	(segment
		(start 377.749562 -66.13017)
		(end 377.749562 -86.97976)
		(width 0.254)
		(layer "F.Cu")
		(net "FLT_HDD20")
	)
	(via
		(at 377.749562 -86.97976)
		(size 0.6604)
		(drill 0.3302)
		(layers "F.Cu" "B.Cu")
		(net "FLT_HDD20")
	)
	(segment
		(start 346.199714 -66.13017)
		(end 346.199714 -85.581998)
		(width 0.254)
		(layer "F.Cu")
		(net "FLT_HDD19")
	)
	(segment
		(start 346.075 -98.425)
		(end 346.075 -95.303848)
		(width 0.254)
		(layer "F.Cu")
		(net "FLT_HDD19")
	)
	(segment
		(start 346.075 -95.303848)
		(end 346.199714 -95.179134)
		(width 0.254)
		(layer "F.Cu")
		(net "FLT_HDD19")
	)
	(segment
		(start 346.199714 -95.179134)
		(end 346.199714 -85.581998)
		(width 0.254)
		(layer "F.Cu")
		(net "FLT_HDD19")
	)
	(via
		(at 346.199714 -85.581998)
		(size 0.6604)
		(drill 0.3302)
		(layers "F.Cu" "B.Cu")
		(net "FLT_HDD19")
	)
	(segment
		(start 315.849 -97.409)
		(end 315.849 -92.202)
		(width 0.254)
		(layer "F.Cu")
		(net "FLT_HDD18")
	)
	(segment
		(start 314.649612 -91.002612)
		(end 314.649612 -79.398622)
		(width 0.254)
		(layer "F.Cu")
		(net "FLT_HDD18")
	)
	(segment
		(start 315.849 -92.202)
		(end 314.649612 -91.002612)
		(width 0.254)
		(layer "F.Cu")
		(net "FLT_HDD18")
	)
	(segment
		(start 314.649612 -79.398622)
		(end 314.649612 -66.13017)
		(width 0.254)
		(layer "F.Cu")
		(net "FLT_HDD18")
	)
	(via
		(at 314.649612 -79.398622)
		(size 0.6604)
		(drill 0.3302)
		(layers "F.Cu" "B.Cu")
		(net "FLT_HDD18")
	)
	(segment
		(start 172.847 -98.552)
		(end 172.847 -89.770458)
		(width 0.254)
		(layer "F.Cu")
		(net "FLT_HDD17")
	)
	(segment
		(start 175.049688 -87.56777)
		(end 175.049688 -81.26603)
		(width 0.254)
		(layer "F.Cu")
		(net "FLT_HDD17")
	)
	(segment
		(start 175.049688 -81.26603)
		(end 175.049688 -66.13017)
		(width 0.254)
		(layer "F.Cu")
		(net "FLT_HDD17")
	)
	(segment
		(start 172.847 -89.770458)
		(end 175.049688 -87.56777)
		(width 0.254)
		(layer "F.Cu")
		(net "FLT_HDD17")
	)
	(via
		(at 175.049688 -81.26603)
		(size 0.6604)
		(drill 0.3302)
		(layers "F.Cu" "B.Cu")
		(net "FLT_HDD17")
	)
	(segment
		(start 143.499586 -66.13017)
		(end 143.499586 -84.646516)
		(width 0.254)
		(layer "F.Cu")
		(net "FLT_HDD16")
	)
	(segment
		(start 143.256 -96.206056)
		(end 143.499586 -95.96247)
		(width 0.254)
		(layer "F.Cu")
		(net "FLT_HDD16")
	)
	(segment
		(start 143.256 -98.552)
		(end 143.256 -96.206056)
		(width 0.254)
		(layer "F.Cu")
		(net "FLT_HDD16")
	)
	(segment
		(start 143.499586 -95.96247)
		(end 143.499586 -84.646516)
		(width 0.254)
		(layer "F.Cu")
		(net "FLT_HDD16")
	)
	(via
		(at 143.499586 -84.646516)
		(size 0.6604)
		(drill 0.3302)
		(layers "F.Cu" "B.Cu")
		(net "FLT_HDD16")
	)
	(segment
		(start 111.949738 -66.13017)
		(end 111.949738 -85.354668)
		(width 0.254)
		(layer "F.Cu")
		(net "FLT_HDD15")
	)
	(segment
		(start 111.76 -96.990916)
		(end 111.949738 -96.801178)
		(width 0.254)
		(layer "F.Cu")
		(net "FLT_HDD15")
	)
	(segment
		(start 111.76 -98.552)
		(end 111.76 -96.990916)
		(width 0.254)
		(layer "F.Cu")
		(net "FLT_HDD15")
	)
	(segment
		(start 111.949738 -96.801178)
		(end 111.949738 -85.354668)
		(width 0.254)
		(layer "F.Cu")
		(net "FLT_HDD15")
	)
	(via
		(at 111.949738 -85.354668)
		(size 0.6604)
		(drill 0.3302)
		(layers "F.Cu" "B.Cu")
		(net "FLT_HDD15")
	)
	(segment
		(start 80.399636 -95.60941)
		(end 80.399636 -86.771226)
		(width 0.254)
		(layer "F.Cu")
		(net "FLT_HDD14")
	)
	(segment
		(start 80.137 -95.872046)
		(end 80.399636 -95.60941)
		(width 0.254)
		(layer "F.Cu")
		(net "FLT_HDD14")
	)
	(segment
		(start 80.399636 -66.13017)
		(end 80.399636 -86.771226)
		(width 0.254)
		(layer "F.Cu")
		(net "FLT_HDD14")
	)
	(segment
		(start 80.137 -98.552)
		(end 80.137 -95.872046)
		(width 0.254)
		(layer "F.Cu")
		(net "FLT_HDD14")
	)
	(via
		(at 80.399636 -86.771226)
		(size 0.6604)
		(drill 0.3302)
		(layers "F.Cu" "B.Cu")
		(net "FLT_HDD14")
	)
	(segment
		(start 48.849534 -86.187534)
		(end 51.8922 -89.2302)
		(width 0.254)
		(layer "F.Cu")
		(net "FLT_HDD13")
	)
	(segment
		(start 54.1528 -91.4908)
		(end 51.8922 -89.2302)
		(width 0.254)
		(layer "F.Cu")
		(net "FLT_HDD13")
	)
	(segment
		(start 54.1528 -98.552)
		(end 54.1528 -91.4908)
		(width 0.254)
		(layer "F.Cu")
		(net "FLT_HDD13")
	)
	(segment
		(start 48.849534 -66.13017)
		(end 48.849534 -86.187534)
		(width 0.254)
		(layer "F.Cu")
		(net "FLT_HDD13")
	)
	(via
		(at 51.8922 -89.2302)
		(size 0.6604)
		(drill 0.3302)
		(layers "F.Cu" "B.Cu")
		(net "FLT_HDD13")
	)
	(segment
		(start 469.474804 -372.2624)
		(end 467.900004 -372.2624)
		(width 0.254)
		(layer "F.Cu")
		(net "FAN_LED_BLUE3")
	)
	(segment
		(start 472.03995 -374.827546)
		(end 469.474804 -372.2624)
		(width 0.254)
		(layer "F.Cu")
		(net "FAN_LED_BLUE3")
	)
	(segment
		(start 472.03995 -377.219972)
		(end 472.03995 -374.827546)
		(width 0.254)
		(layer "F.Cu")
		(net "FAN_LED_BLUE3")
	)
	(segment
		(start 314.440062 -377.219972)
		(end 313.657996 -376.437906)
		(width 0.254)
		(layer "F.Cu")
		(net "FAN_LED_BLUE2")
	)
	(segment
		(start 313.657996 -376.437906)
		(end 313.657996 -374.1928)
		(width 0.254)
		(layer "F.Cu")
		(net "FAN_LED_BLUE2")
	)
	(segment
		(start 182.959502 -379.5395)
		(end 180.639974 -377.219972)
		(width 0.254)
		(layer "F.Cu")
		(net "FAN_LED_BLUE1")
	)
	(segment
		(start 185.7629 -379.5395)
		(end 182.959502 -379.5395)
		(width 0.254)
		(layer "F.Cu")
		(net "FAN_LED_BLUE1")
	)
	(segment
		(start 461.296004 -377.12269)
		(end 461.296004 -376.428)
		(width 0.254)
		(layer "F.Cu")
		(net "FAN_BLUE_LED3")
	)
	(segment
		(start 460.074264 -376.37974)
		(end 459.149704 -376.37974)
		(width 0.254)
		(layer "F.Cu")
		(net "FAN_BLUE_LED3")
	)
	(segment
		(start 459.137004 -377.3678)
		(end 459.137004 -378.29871)
		(width 0.254)
		(layer "F.Cu")
		(net "FAN_BLUE_LED3")
	)
	(segment
		(start 459.137004 -377.3678)
		(end 459.149704 -377.3551)
		(width 0.254)
		(layer "F.Cu")
		(net "FAN_BLUE_LED3")
	)
	(segment
		(start 461.296004 -376.428)
		(end 461.016604 -376.1486)
		(width 0.254)
		(layer "F.Cu")
		(net "FAN_BLUE_LED3")
	)
	(segment
		(start 459.149704 -377.3551)
		(end 459.149704 -376.37974)
		(width 0.254)
		(layer "F.Cu")
		(net "FAN_BLUE_LED3")
	)
	(segment
		(start 459.137004 -378.29871)
		(end 458.950314 -378.4854)
		(width 0.254)
		(layer "F.Cu")
		(net "FAN_BLUE_LED3")
	)
	(segment
		(start 461.016604 -376.1486)
		(end 460.305404 -376.1486)
		(width 0.254)
		(layer "F.Cu")
		(net "FAN_BLUE_LED3")
	)
	(segment
		(start 460.305404 -376.1486)
		(end 460.074264 -376.37974)
		(width 0.254)
		(layer "F.Cu")
		(net "FAN_BLUE_LED3")
	)
	(via
		(at 459.137004 -377.3678)
		(size 0.6604)
		(drill 0.3302)
		(layers "F.Cu" "B.Cu")
		(net "FAN_BLUE_LED3")
	)
	(segment
		(start 319.017396 -377.1392)
		(end 318.924686 -377.04649)
		(width 0.254)
		(layer "F.Cu")
		(net "FAN_BLUE_LED2")
	)
	(segment
		(start 319.995296 -377.1392)
		(end 320.020696 -377.1646)
		(width 0.254)
		(layer "F.Cu")
		(net "FAN_BLUE_LED2")
	)
	(segment
		(start 320.134996 -377.2789)
		(end 320.020696 -377.1646)
		(width 0.254)
		(layer "F.Cu")
		(net "FAN_BLUE_LED2")
	)
	(segment
		(start 319.262506 -379.3236)
		(end 319.93205 -379.3236)
		(width 0.254)
		(layer "F.Cu")
		(net "FAN_BLUE_LED2")
	)
	(segment
		(start 320.134996 -379.120654)
		(end 320.134996 -377.2789)
		(width 0.254)
		(layer "F.Cu")
		(net "FAN_BLUE_LED2")
	)
	(segment
		(start 319.017396 -377.1392)
		(end 319.995296 -377.1392)
		(width 0.254)
		(layer "F.Cu")
		(net "FAN_BLUE_LED2")
	)
	(segment
		(start 319.93205 -379.3236)
		(end 320.134996 -379.120654)
		(width 0.254)
		(layer "F.Cu")
		(net "FAN_BLUE_LED2")
	)
	(segment
		(start 318.924686 -377.04649)
		(end 317.975996 -377.04649)
		(width 0.254)
		(layer "F.Cu")
		(net "FAN_BLUE_LED2")
	)
	(via
		(at 319.017396 -377.1392)
		(size 0.6604)
		(drill 0.3302)
		(layers "F.Cu" "B.Cu")
		(net "FAN_BLUE_LED2")
	)
	(segment
		(start 187.422028 -372.398036)
		(end 187.447428 -372.423436)
		(width 0.254)
		(layer "F.Cu")
		(net "FAN_BLUE_LED1")
	)
	(segment
		(start 187.447428 -373.020336)
		(end 187.447428 -372.423436)
		(width 0.254)
		(layer "F.Cu")
		(net "FAN_BLUE_LED1")
	)
	(segment
		(start 187.095638 -374.531636)
		(end 187.637928 -374.531636)
		(width 0.254)
		(layer "F.Cu")
		(net "FAN_BLUE_LED1")
	)
	(segment
		(start 186.571128 -372.398036)
		(end 187.422028 -372.398036)
		(width 0.254)
		(layer "F.Cu")
		(net "FAN_BLUE_LED1")
	)
	(segment
		(start 186.444128 -372.271036)
		(end 186.571128 -372.398036)
		(width 0.254)
		(layer "F.Cu")
		(net "FAN_BLUE_LED1")
	)
	(segment
		(start 187.637928 -374.531636)
		(end 187.993528 -374.176036)
		(width 0.254)
		(layer "F.Cu")
		(net "FAN_BLUE_LED1")
	)
	(segment
		(start 186.224418 -372.051326)
		(end 186.444128 -372.271036)
		(width 0.254)
		(layer "F.Cu")
		(net "FAN_BLUE_LED1")
	)
	(segment
		(start 187.993528 -374.176036)
		(end 187.993528 -373.566436)
		(width 0.254)
		(layer "F.Cu")
		(net "FAN_BLUE_LED1")
	)
	(segment
		(start 185.478928 -372.051326)
		(end 186.224418 -372.051326)
		(width 0.254)
		(layer "F.Cu")
		(net "FAN_BLUE_LED1")
	)
	(segment
		(start 187.993528 -373.566436)
		(end 187.447428 -373.020336)
		(width 0.254)
		(layer "F.Cu")
		(net "FAN_BLUE_LED1")
	)
	(via
		(at 186.444128 -372.271036)
		(size 0.6604)
		(drill 0.3302)
		(layers "F.Cu" "B.Cu")
		(net "FAN_BLUE_LED1")
	)
	(segment
		(start 249.96648 -214.6427)
		(end 249.96648 -213.00948)
		(width 0.17145)
		(layer "F.Cu")
		(net "EEPROM_WP")
	)
	(segment
		(start 249.96648 -213.00948)
		(end 249.682 -212.725)
		(width 0.17145)
		(layer "F.Cu")
		(net "EEPROM_WP")
	)
	(segment
		(start 249.682 -211.66074)
		(end 249.682 -212.725)
		(width 0.17145)
		(layer "F.Cu")
		(net "EEPROM_WP")
	)
	(segment
		(start 249.69978 -211.64296)
		(end 249.682 -211.66074)
		(width 0.17145)
		(layer "F.Cu")
		(net "EEPROM_WP")
	)
	(via
		(at 249.682 -212.725)
		(size 0.6604)
		(drill 0.3302)
		(layers "F.Cu" "B.Cu")
		(net "EEPROM_WP")
	)
	(segment
		(start 247.42648 -213.158832)
		(end 247.437402 -213.14791)
		(width 0.17145)
		(layer "F.Cu")
		(net "EEPROM_SDA")
	)
	(segment
		(start 247.42648 -214.6427)
		(end 247.42648 -213.158832)
		(width 0.17145)
		(layer "F.Cu")
		(net "EEPROM_SDA")
	)
	(segment
		(start 247.15978 -212.870288)
		(end 247.437402 -213.14791)
		(width 0.17145)
		(layer "F.Cu")
		(net "EEPROM_SDA")
	)
	(segment
		(start 247.15978 -212.135212)
		(end 247.15978 -212.870288)
		(width 0.17145)
		(layer "F.Cu")
		(net "EEPROM_SDA")
	)
	(via
		(at 247.437402 -213.14791)
		(size 0.6604)
		(drill 0.3302)
		(layers "F.Cu" "B.Cu")
		(net "EEPROM_SDA")
	)
	(segment
		(start 248.69648 -214.6427)
		(end 248.69648 -213.129114)
		(width 0.17145)
		(layer "F.Cu")
		(net "EEPROM_SCL")
	)
	(segment
		(start 248.30278 -212.135212)
		(end 248.30278 -212.735414)
		(width 0.17145)
		(layer "F.Cu")
		(net "EEPROM_SCL")
	)
	(segment
		(start 248.69648 -213.129114)
		(end 248.693178 -213.125812)
		(width 0.17145)
		(layer "F.Cu")
		(net "EEPROM_SCL")
	)
	(segment
		(start 248.30278 -212.735414)
		(end 248.693178 -213.125812)
		(width 0.17145)
		(layer "F.Cu")
		(net "EEPROM_SCL")
	)
	(via
		(at 248.693178 -213.125812)
		(size 0.6604)
		(drill 0.3302)
		(layers "F.Cu" "B.Cu")
		(net "EEPROM_SCL")
	)
	(segment
		(start 246.898668 -222.9485)
		(end 247.965468 -222.9485)
		(width 0.17145)
		(layer "F.Cu")
		(net "EEPROM_A2")
	)
	(segment
		(start 248.69648 -219.7227)
		(end 248.69648 -220.853)
		(width 0.17145)
		(layer "F.Cu")
		(net "EEPROM_A2")
	)
	(segment
		(start 248.21134 -221.33814)
		(end 247.451626 -221.33814)
		(width 0.17145)
		(layer "F.Cu")
		(net "EEPROM_A2")
	)
	(segment
		(start 246.898668 -221.921578)
		(end 246.898668 -222.9485)
		(width 0.17145)
		(layer "F.Cu")
		(net "EEPROM_A2")
	)
	(segment
		(start 246.883428 -221.906338)
		(end 246.898668 -221.921578)
		(width 0.17145)
		(layer "F.Cu")
		(net "EEPROM_A2")
	)
	(segment
		(start 248.69648 -220.853)
		(end 248.21134 -221.33814)
		(width 0.17145)
		(layer "F.Cu")
		(net "EEPROM_A2")
	)
	(segment
		(start 247.451626 -221.33814)
		(end 246.883428 -221.906338)
		(width 0.17145)
		(layer "F.Cu")
		(net "EEPROM_A2")
	)
	(via
		(at 246.883428 -221.906338)
		(size 0.6604)
		(drill 0.3302)
		(layers "F.Cu" "B.Cu")
		(net "EEPROM_A2")
	)
	(segment
		(start 249.555 -221.3356)
		(end 249.0216 -221.869)
		(width 0.17145)
		(layer "F.Cu")
		(net "EEPROM_A1")
	)
	(segment
		(start 249.0216 -222.506032)
		(end 249.032268 -222.5167)
		(width 0.17145)
		(layer "F.Cu")
		(net "EEPROM_A1")
	)
	(segment
		(start 249.0216 -221.869)
		(end 249.0216 -222.506032)
		(width 0.17145)
		(layer "F.Cu")
		(net "EEPROM_A1")
	)
	(segment
		(start 249.96648 -219.7227)
		(end 249.96648 -220.92412)
		(width 0.17145)
		(layer "F.Cu")
		(net "EEPROM_A1")
	)
	(segment
		(start 249.032268 -222.5167)
		(end 250.327668 -222.5167)
		(width 0.17145)
		(layer "F.Cu")
		(net "EEPROM_A1")
	)
	(segment
		(start 249.96648 -220.92412)
		(end 249.555 -221.3356)
		(width 0.17145)
		(layer "F.Cu")
		(net "EEPROM_A1")
	)
	(via
		(at 249.555 -221.3356)
		(size 0.6604)
		(drill 0.3302)
		(layers "F.Cu" "B.Cu")
		(net "EEPROM_A1")
	)
	(segment
		(start 251.442982 -221.488)
		(end 251.442982 -222.023686)
		(width 0.17145)
		(layer "F.Cu")
		(net "EEPROM_A0")
	)
	(segment
		(start 251.23648 -219.7227)
		(end 251.23648 -220.726)
		(width 0.17145)
		(layer "F.Cu")
		(net "EEPROM_A0")
	)
	(segment
		(start 251.394468 -222.0722)
		(end 251.394468 -222.5167)
		(width 0.17145)
		(layer "F.Cu")
		(net "EEPROM_A0")
	)
	(segment
		(start 251.442982 -220.932502)
		(end 251.442982 -221.488)
		(width 0.17145)
		(layer "F.Cu")
		(net "EEPROM_A0")
	)
	(segment
		(start 251.442982 -222.023686)
		(end 251.394468 -222.0722)
		(width 0.17145)
		(layer "F.Cu")
		(net "EEPROM_A0")
	)
	(segment
		(start 251.23648 -220.726)
		(end 251.442982 -220.932502)
		(width 0.17145)
		(layer "F.Cu")
		(net "EEPROM_A0")
	)
	(segment
		(start 251.394468 -222.5167)
		(end 252.461268 -222.5167)
		(width 0.17145)
		(layer "F.Cu")
		(net "EEPROM_A0")
	)
	(via
		(at 251.442982 -221.488)
		(size 0.6604)
		(drill 0.3302)
		(layers "F.Cu" "B.Cu")
		(net "EEPROM_A0")
	)
	(segment
		(start 473.400374 -66.13017)
		(end 473.400374 -83.473544)
		(width 0.254)
		(layer "F.Cu")
		(net "DRV_ACT_23")
	)
	(segment
		(start 465.3534 -98.6282)
		(end 465.3534 -91.520518)
		(width 0.254)
		(layer "F.Cu")
		(net "DRV_ACT_23")
	)
	(segment
		(start 465.3534 -91.520518)
		(end 466.539326 -90.334592)
		(width 0.254)
		(layer "F.Cu")
		(net "DRV_ACT_23")
	)
	(segment
		(start 473.400374 -83.473544)
		(end 466.539326 -90.334592)
		(width 0.254)
		(layer "F.Cu")
		(net "DRV_ACT_23")
	)
	(via
		(at 466.539326 -90.334592)
		(size 0.6604)
		(drill 0.3302)
		(layers "F.Cu" "B.Cu")
		(net "DRV_ACT_23")
	)
	(segment
		(start 441.850272 -66.13017)
		(end 441.850272 -91.921584)
		(width 0.254)
		(layer "F.Cu")
		(net "DRV_ACT_22")
	)
	(segment
		(start 441.850272 -95.07601)
		(end 441.850272 -91.921584)
		(width 0.254)
		(layer "F.Cu")
		(net "DRV_ACT_22")
	)
	(segment
		(start 441.96 -98.425)
		(end 441.96 -95.185738)
		(width 0.254)
		(layer "F.Cu")
		(net "DRV_ACT_22")
	)
	(segment
		(start 441.96 -95.185738)
		(end 441.850272 -95.07601)
		(width 0.254)
		(layer "F.Cu")
		(net "DRV_ACT_22")
	)
	(via
		(at 441.850272 -91.921584)
		(size 0.6604)
		(drill 0.3302)
		(layers "F.Cu" "B.Cu")
		(net "DRV_ACT_22")
	)
	(segment
		(start 410.464 -94.868746)
		(end 410.300424 -94.70517)
		(width 0.254)
		(layer "F.Cu")
		(net "DRV_ACT_21")
	)
	(segment
		(start 410.300424 -66.13017)
		(end 410.300424 -92.243656)
		(width 0.254)
		(layer "F.Cu")
		(net "DRV_ACT_21")
	)
	(segment
		(start 410.300424 -94.70517)
		(end 410.300424 -92.243656)
		(width 0.254)
		(layer "F.Cu")
		(net "DRV_ACT_21")
	)
	(segment
		(start 410.464 -98.425)
		(end 410.464 -94.868746)
		(width 0.254)
		(layer "F.Cu")
		(net "DRV_ACT_21")
	)
	(via
		(at 410.300424 -92.243656)
		(size 0.6604)
		(drill 0.3302)
		(layers "F.Cu" "B.Cu")
		(net "DRV_ACT_21")
	)
	(segment
		(start 378.750322 -66.13017)
		(end 378.750322 -92.694252)
		(width 0.254)
		(layer "F.Cu")
		(net "DRV_ACT_20")
	)
	(segment
		(start 378.750322 -95.155766)
		(end 378.750322 -92.694252)
		(width 0.254)
		(layer "F.Cu")
		(net "DRV_ACT_20")
	)
	(segment
		(start 378.968 -95.373444)
		(end 378.750322 -95.155766)
		(width 0.254)
		(layer "F.Cu")
		(net "DRV_ACT_20")
	)
	(segment
		(start 378.968 -98.425)
		(end 378.968 -95.373444)
		(width 0.254)
		(layer "F.Cu")
		(net "DRV_ACT_20")
	)
	(via
		(at 378.750322 -92.694252)
		(size 0.6604)
		(drill 0.3302)
		(layers "F.Cu" "B.Cu")
		(net "DRV_ACT_20")
	)
	(segment
		(start 347.200474 -66.13017)
		(end 347.200474 -91.29649)
		(width 0.254)
		(layer "F.Cu")
		(net "DRV_ACT_19")
	)
	(segment
		(start 347.200474 -95.29953)
		(end 347.200474 -91.29649)
		(width 0.254)
		(layer "F.Cu")
		(net "DRV_ACT_19")
	)
	(segment
		(start 347.345 -98.425)
		(end 347.345 -95.444056)
		(width 0.254)
		(layer "F.Cu")
		(net "DRV_ACT_19")
	)
	(segment
		(start 347.345 -95.444056)
		(end 347.200474 -95.29953)
		(width 0.254)
		(layer "F.Cu")
		(net "DRV_ACT_19")
	)
	(via
		(at 347.200474 -91.29649)
		(size 0.6604)
		(drill 0.3302)
		(layers "F.Cu" "B.Cu")
		(net "DRV_ACT_19")
	)
	(segment
		(start 317.119 -97.409)
		(end 317.119 -92.056458)
		(width 0.254)
		(layer "F.Cu")
		(net "DRV_ACT_18")
	)
	(segment
		(start 315.650372 -85.113114)
		(end 315.650372 -66.13017)
		(width 0.254)
		(layer "F.Cu")
		(net "DRV_ACT_18")
	)
	(segment
		(start 317.119 -92.056458)
		(end 315.650372 -90.58783)
		(width 0.254)
		(layer "F.Cu")
		(net "DRV_ACT_18")
	)
	(segment
		(start 315.650372 -90.58783)
		(end 315.650372 -85.113114)
		(width 0.254)
		(layer "F.Cu")
		(net "DRV_ACT_18")
	)
	(via
		(at 315.650372 -85.113114)
		(size 0.6604)
		(drill 0.3302)
		(layers "F.Cu" "B.Cu")
		(net "DRV_ACT_18")
	)
	(segment
		(start 176.050448 -87.982552)
		(end 176.050448 -86.980522)
		(width 0.254)
		(layer "F.Cu")
		(net "DRV_ACT_17")
	)
	(segment
		(start 174.117 -89.916)
		(end 176.050448 -87.982552)
		(width 0.254)
		(layer "F.Cu")
		(net "DRV_ACT_17")
	)
	(segment
		(start 174.117 -98.552)
		(end 174.117 -89.916)
		(width 0.254)
		(layer "F.Cu")
		(net "DRV_ACT_17")
	)
	(segment
		(start 176.050448 -86.980522)
		(end 176.050448 -66.13017)
		(width 0.254)
		(layer "F.Cu")
		(net "DRV_ACT_17")
	)
	(via
		(at 176.050448 -86.980522)
		(size 0.6604)
		(drill 0.3302)
		(layers "F.Cu" "B.Cu")
		(net "DRV_ACT_17")
	)
	(segment
		(start 144.526 -98.552)
		(end 144.526 -96.111822)
		(width 0.254)
		(layer "F.Cu")
		(net "DRV_ACT_16")
	)
	(segment
		(start 144.500346 -96.086168)
		(end 144.500346 -90.361008)
		(width 0.254)
		(layer "F.Cu")
		(net "DRV_ACT_16")
	)
	(segment
		(start 144.500346 -66.13017)
		(end 144.500346 -90.361008)
		(width 0.254)
		(layer "F.Cu")
		(net "DRV_ACT_16")
	)
	(segment
		(start 144.526 -96.111822)
		(end 144.500346 -96.086168)
		(width 0.254)
		(layer "F.Cu")
		(net "DRV_ACT_16")
	)
	(via
		(at 144.500346 -90.361008)
		(size 0.6604)
		(drill 0.3302)
		(layers "F.Cu" "B.Cu")
		(net "DRV_ACT_16")
	)
	(segment
		(start 112.950498 -66.13017)
		(end 112.950498 -91.06916)
		(width 0.254)
		(layer "F.Cu")
		(net "DRV_ACT_15")
	)
	(segment
		(start 113.03 -97.011998)
		(end 112.950498 -96.932496)
		(width 0.254)
		(layer "F.Cu")
		(net "DRV_ACT_15")
	)
	(segment
		(start 113.03 -98.552)
		(end 113.03 -97.011998)
		(width 0.254)
		(layer "F.Cu")
		(net "DRV_ACT_15")
	)
	(segment
		(start 112.950498 -96.932496)
		(end 112.950498 -91.06916)
		(width 0.254)
		(layer "F.Cu")
		(net "DRV_ACT_15")
	)
	(via
		(at 112.950498 -91.06916)
		(size 0.6604)
		(drill 0.3302)
		(layers "F.Cu" "B.Cu")
		(net "DRV_ACT_15")
	)
	(segment
		(start 81.407 -98.552)
		(end 81.407 -95.451168)
		(width 0.254)
		(layer "F.Cu")
		(net "DRV_ACT_14")
	)
	(segment
		(start 81.407 -95.451168)
		(end 81.400396 -95.444564)
		(width 0.254)
		(layer "F.Cu")
		(net "DRV_ACT_14")
	)
	(segment
		(start 81.400396 -66.13017)
		(end 81.400396 -92.485718)
		(width 0.254)
		(layer "F.Cu")
		(net "DRV_ACT_14")
	)
	(segment
		(start 81.400396 -95.444564)
		(end 81.400396 -92.485718)
		(width 0.254)
		(layer "F.Cu")
		(net "DRV_ACT_14")
	)
	(via
		(at 81.400396 -92.485718)
		(size 0.6604)
		(drill 0.3302)
		(layers "F.Cu" "B.Cu")
		(net "DRV_ACT_14")
	)
	(segment
		(start 55.4228 -91.2368)
		(end 55.4228 -91.5924)
		(width 0.254)
		(layer "F.Cu")
		(net "DRV_ACT_13")
	)
	(segment
		(start 49.850294 -66.13017)
		(end 49.850294 -85.664294)
		(width 0.254)
		(layer "F.Cu")
		(net "DRV_ACT_13")
	)
	(segment
		(start 49.850294 -85.664294)
		(end 55.4228 -91.2368)
		(width 0.254)
		(layer "F.Cu")
		(net "DRV_ACT_13")
	)
	(segment
		(start 55.4228 -98.552)
		(end 55.4228 -91.5924)
		(width 0.254)
		(layer "F.Cu")
		(net "DRV_ACT_13")
	)
	(via
		(at 55.4228 -91.5924)
		(size 0.6604)
		(drill 0.3302)
		(layers "F.Cu" "B.Cu")
		(net "DRV_ACT_13")
	)
	(segment
		(start 429.133 -244.0305)
		(end 427.863 -244.0305)
		(width 0.17145)
		(layer "F.Cu")
		(net "SW_PWR_R_HDD9")
	)
	(segment
		(start 427.863 -244.0305)
		(end 426.72 -244.0305)
		(width 0.17145)
		(layer "F.Cu")
		(net "SW_PWR_R_HDD9")
	)
	(segment
		(start 425.7802 -246.253)
		(end 424.8912 -246.253)
		(width 0.17145)
		(layer "F.Cu")
		(net "SW_PWR_R_HDD9")
	)
	(segment
		(start 424.4848 -245.8466)
		(end 424.4848 -244.602)
		(width 0.17145)
		(layer "F.Cu")
		(net "SW_PWR_R_HDD9")
	)
	(segment
		(start 424.8912 -246.253)
		(end 424.4848 -245.8466)
		(width 0.17145)
		(layer "F.Cu")
		(net "SW_PWR_R_HDD9")
	)
	(segment
		(start 430.403 -244.0305)
		(end 429.133 -244.0305)
		(width 0.17145)
		(layer "F.Cu")
		(net "SW_PWR_R_HDD9")
	)
	(segment
		(start 424.4848 -244.602)
		(end 425.0563 -244.0305)
		(width 0.17145)
		(layer "F.Cu")
		(net "SW_PWR_R_HDD9")
	)
	(segment
		(start 425.0563 -244.0305)
		(end 426.72 -244.0305)
		(width 0.17145)
		(layer "F.Cu")
		(net "SW_PWR_R_HDD9")
	)
	(via
		(at 429.133 -244.0305)
		(size 0.6604)
		(drill 0.3302)
		(layers "F.Cu" "B.Cu")
		(net "SW_PWR_R_HDD9")
	)
	(segment
		(start 396.367 -244.0305)
		(end 395.224 -244.0305)
		(width 0.17145)
		(layer "F.Cu")
		(net "SW_PWR_R_HDD8")
	)
	(segment
		(start 393.3698 -246.253)
		(end 392.8872 -245.7704)
		(width 0.17145)
		(layer "F.Cu")
		(net "SW_PWR_R_HDD8")
	)
	(segment
		(start 397.637 -244.0305)
		(end 396.367 -244.0305)
		(width 0.17145)
		(layer "F.Cu")
		(net "SW_PWR_R_HDD8")
	)
	(segment
		(start 392.8872 -244.3988)
		(end 393.2555 -244.0305)
		(width 0.17145)
		(layer "F.Cu")
		(net "SW_PWR_R_HDD8")
	)
	(segment
		(start 398.907 -244.0305)
		(end 397.637 -244.0305)
		(width 0.17145)
		(layer "F.Cu")
		(net "SW_PWR_R_HDD8")
	)
	(segment
		(start 393.2555 -244.0305)
		(end 395.224 -244.0305)
		(width 0.17145)
		(layer "F.Cu")
		(net "SW_PWR_R_HDD8")
	)
	(segment
		(start 394.2842 -246.253)
		(end 393.3698 -246.253)
		(width 0.17145)
		(layer "F.Cu")
		(net "SW_PWR_R_HDD8")
	)
	(segment
		(start 392.8872 -245.7704)
		(end 392.8872 -244.3988)
		(width 0.17145)
		(layer "F.Cu")
		(net "SW_PWR_R_HDD8")
	)
	(via
		(at 397.637 -244.0305)
		(size 0.6604)
		(drill 0.3302)
		(layers "F.Cu" "B.Cu")
		(net "SW_PWR_R_HDD8")
	)
	(segment
		(start 362.6612 -246.253)
		(end 361.8992 -246.253)
		(width 0.17145)
		(layer "F.Cu")
		(net "SW_PWR_R_HDD7")
	)
	(segment
		(start 361.8992 -246.253)
		(end 361.2642 -245.618)
		(width 0.17145)
		(layer "F.Cu")
		(net "SW_PWR_R_HDD7")
	)
	(segment
		(start 361.2642 -245.618)
		(end 361.2642 -244.6782)
		(width 0.17145)
		(layer "F.Cu")
		(net "SW_PWR_R_HDD7")
	)
	(segment
		(start 361.9119 -244.0305)
		(end 363.601 -244.0305)
		(width 0.17145)
		(layer "F.Cu")
		(net "SW_PWR_R_HDD7")
	)
	(segment
		(start 366.014 -244.0305)
		(end 364.744 -244.0305)
		(width 0.17145)
		(layer "F.Cu")
		(net "SW_PWR_R_HDD7")
	)
	(segment
		(start 367.284 -244.0305)
		(end 366.014 -244.0305)
		(width 0.17145)
		(layer "F.Cu")
		(net "SW_PWR_R_HDD7")
	)
	(segment
		(start 364.744 -244.0305)
		(end 363.601 -244.0305)
		(width 0.17145)
		(layer "F.Cu")
		(net "SW_PWR_R_HDD7")
	)
	(segment
		(start 361.2642 -244.6782)
		(end 361.9119 -244.0305)
		(width 0.17145)
		(layer "F.Cu")
		(net "SW_PWR_R_HDD7")
	)
	(via
		(at 366.014 -244.0305)
		(size 0.6604)
		(drill 0.3302)
		(layers "F.Cu" "B.Cu")
		(net "SW_PWR_R_HDD7")
	)
	(segment
		(start 329.819 -245.8466)
		(end 329.819 -244.475)
		(width 0.17145)
		(layer "F.Cu")
		(net "SW_PWR_R_HDD6")
	)
	(segment
		(start 329.819 -244.475)
		(end 330.2635 -244.0305)
		(width 0.17145)
		(layer "F.Cu")
		(net "SW_PWR_R_HDD6")
	)
	(segment
		(start 334.518 -244.0305)
		(end 333.248 -244.0305)
		(width 0.17145)
		(layer "F.Cu")
		(net "SW_PWR_R_HDD6")
	)
	(segment
		(start 335.788 -244.0305)
		(end 334.518 -244.0305)
		(width 0.17145)
		(layer "F.Cu")
		(net "SW_PWR_R_HDD6")
	)
	(segment
		(start 330.2254 -246.253)
		(end 329.819 -245.8466)
		(width 0.17145)
		(layer "F.Cu")
		(net "SW_PWR_R_HDD6")
	)
	(segment
		(start 333.248 -244.0305)
		(end 332.105 -244.0305)
		(width 0.17145)
		(layer "F.Cu")
		(net "SW_PWR_R_HDD6")
	)
	(segment
		(start 330.2635 -244.0305)
		(end 332.105 -244.0305)
		(width 0.17145)
		(layer "F.Cu")
		(net "SW_PWR_R_HDD6")
	)
	(segment
		(start 331.1652 -246.253)
		(end 330.2254 -246.253)
		(width 0.17145)
		(layer "F.Cu")
		(net "SW_PWR_R_HDD6")
	)
	(via
		(at 334.518 -244.0305)
		(size 0.6604)
		(drill 0.3302)
		(layers "F.Cu" "B.Cu")
		(net "SW_PWR_R_HDD6")
	)
	(segment
		(start 179.6923 -247.2944)
		(end 179.6923 -246.2784)
		(width 0.17145)
		(layer "F.Cu")
		(net "SW_PWR_R_HDD5")
	)
	(segment
		(start 180.2765 -249.555)
		(end 180.3019 -249.5296)
		(width 0.17145)
		(layer "F.Cu")
		(net "SW_PWR_R_HDD5")
	)
	(segment
		(start 178.181 -250.4948)
		(end 178.181 -249.936)
		(width 0.17145)
		(layer "F.Cu")
		(net "SW_PWR_R_HDD5")
	)
	(segment
		(start 178.562 -249.555)
		(end 180.2765 -249.555)
		(width 0.17145)
		(layer "F.Cu")
		(net "SW_PWR_R_HDD5")
	)
	(segment
		(start 179.6923 -247.8786)
		(end 179.6923 -247.2944)
		(width 0.17145)
		(layer "F.Cu")
		(net "SW_PWR_R_HDD5")
	)
	(segment
		(start 178.181 -249.936)
		(end 178.562 -249.555)
		(width 0.17145)
		(layer "F.Cu")
		(net "SW_PWR_R_HDD5")
	)
	(segment
		(start 180.3019 -248.4882)
		(end 179.6923 -247.8786)
		(width 0.17145)
		(layer "F.Cu")
		(net "SW_PWR_R_HDD5")
	)
	(segment
		(start 180.3019 -249.5296)
		(end 180.3019 -248.4882)
		(width 0.17145)
		(layer "F.Cu")
		(net "SW_PWR_R_HDD5")
	)
	(via
		(at 179.6923 -247.2944)
		(size 0.6604)
		(drill 0.3302)
		(layers "F.Cu" "B.Cu")
		(net "SW_PWR_R_HDD5")
	)
	(segment
		(start 148.0947 -247.7516)
		(end 148.0947 -247.2436)
		(width 0.17145)
		(layer "F.Cu")
		(net "SW_PWR_R_HDD4")
	)
	(segment
		(start 147.066 -249.555)
		(end 148.7805 -249.555)
		(width 0.17145)
		(layer "F.Cu")
		(net "SW_PWR_R_HDD4")
	)
	(segment
		(start 148.7805 -249.555)
		(end 148.7805 -248.4374)
		(width 0.17145)
		(layer "F.Cu")
		(net "SW_PWR_R_HDD4")
	)
	(segment
		(start 148.0947 -247.2436)
		(end 148.0947 -246.253)
		(width 0.17145)
		(layer "F.Cu")
		(net "SW_PWR_R_HDD4")
	)
	(segment
		(start 146.685 -249.936)
		(end 147.066 -249.555)
		(width 0.17145)
		(layer "F.Cu")
		(net "SW_PWR_R_HDD4")
	)
	(segment
		(start 148.7805 -248.4374)
		(end 148.0947 -247.7516)
		(width 0.17145)
		(layer "F.Cu")
		(net "SW_PWR_R_HDD4")
	)
	(segment
		(start 146.685 -250.4948)
		(end 146.685 -249.936)
		(width 0.17145)
		(layer "F.Cu")
		(net "SW_PWR_R_HDD4")
	)
	(via
		(at 148.0947 -247.2436)
		(size 0.6604)
		(drill 0.3302)
		(layers "F.Cu" "B.Cu")
		(net "SW_PWR_R_HDD4")
	)
	(segment
		(start 476.6818 -10.7315)
		(end 477.647 -10.7315)
		(width 0.17145)
		(layer "F.Cu")
		(net "SW_PWR_R_HDD35")
	)
	(segment
		(start 478.409 -10.0076)
		(end 478.6884 -10.287)
		(width 0.17145)
		(layer "F.Cu")
		(net "SW_PWR_R_HDD35")
	)
	(segment
		(start 475.7166 -10.7315)
		(end 476.6818 -10.7315)
		(width 0.17145)
		(layer "F.Cu")
		(net "SW_PWR_R_HDD35")
	)
	(segment
		(start 478.6884 -10.7315)
		(end 477.647 -10.7315)
		(width 0.17145)
		(layer "F.Cu")
		(net "SW_PWR_R_HDD35")
	)
	(segment
		(start 478.409 -9.3218)
		(end 478.409 -10.0076)
		(width 0.17145)
		(layer "F.Cu")
		(net "SW_PWR_R_HDD35")
	)
	(segment
		(start 478.6884 -10.287)
		(end 478.6884 -10.7315)
		(width 0.17145)
		(layer "F.Cu")
		(net "SW_PWR_R_HDD35")
	)
	(via
		(at 476.6818 -10.7315)
		(size 0.6604)
		(drill 0.3302)
		(layers "F.Cu" "B.Cu")
		(net "SW_PWR_R_HDD35")
	)
	(segment
		(start 460.4385 -18.1229)
		(end 460.4385 -16.3576)
		(width 0.17145)
		(layer "F.Cu")
		(net "SW_PWR_R_HDD34")
	)
	(segment
		(start 460.4258 -16.3703)
		(end 460.4385 -16.3576)
		(width 0.17145)
		(layer "F.Cu")
		(net "SW_PWR_R_HDD34")
	)
	(segment
		(start 458.3938 -16.0528)
		(end 458.4192 -16.0274)
		(width 0.17145)
		(layer "F.Cu")
		(net "SW_PWR_R_HDD34")
	)
	(segment
		(start 459.359 -16.3703)
		(end 460.4258 -16.3703)
		(width 0.17145)
		(layer "F.Cu")
		(net "SW_PWR_R_HDD34")
	)
	(segment
		(start 460.0956 -18.4658)
		(end 460.4385 -18.1229)
		(width 0.17145)
		(layer "F.Cu")
		(net "SW_PWR_R_HDD34")
	)
	(segment
		(start 457.4921 -16.0528)
		(end 458.3938 -16.0528)
		(width 0.17145)
		(layer "F.Cu")
		(net "SW_PWR_R_HDD34")
	)
	(segment
		(start 458.7621 -16.3703)
		(end 459.359 -16.3703)
		(width 0.17145)
		(layer "F.Cu")
		(net "SW_PWR_R_HDD34")
	)
	(segment
		(start 459.3844 -18.4658)
		(end 460.0956 -18.4658)
		(width 0.17145)
		(layer "F.Cu")
		(net "SW_PWR_R_HDD34")
	)
	(segment
		(start 458.4192 -16.0274)
		(end 458.7621 -16.3703)
		(width 0.17145)
		(layer "F.Cu")
		(net "SW_PWR_R_HDD34")
	)
	(via
		(at 458.4192 -16.0274)
		(size 0.6604)
		(drill 0.3302)
		(layers "F.Cu" "B.Cu")
		(net "SW_PWR_R_HDD34")
	)
	(segment
		(start 426.72 -14.0335)
		(end 427.863 -14.0335)
		(width 0.17145)
		(layer "F.Cu")
		(net "SW_PWR_R_HDD33")
	)
	(segment
		(start 425.7802 -16.256)
		(end 425.0182 -16.256)
		(width 0.17145)
		(layer "F.Cu")
		(net "SW_PWR_R_HDD33")
	)
	(segment
		(start 424.5102 -14.7066)
		(end 425.1833 -14.0335)
		(width 0.17145)
		(layer "F.Cu")
		(net "SW_PWR_R_HDD33")
	)
	(segment
		(start 424.5102 -15.748)
		(end 424.5102 -14.7066)
		(width 0.17145)
		(layer "F.Cu")
		(net "SW_PWR_R_HDD33")
	)
	(segment
		(start 430.403 -14.0335)
		(end 429.133 -14.0335)
		(width 0.17145)
		(layer "F.Cu")
		(net "SW_PWR_R_HDD33")
	)
	(segment
		(start 425.0182 -16.256)
		(end 424.5102 -15.748)
		(width 0.17145)
		(layer "F.Cu")
		(net "SW_PWR_R_HDD33")
	)
	(segment
		(start 427.863 -14.0335)
		(end 429.133 -14.0335)
		(width 0.17145)
		(layer "F.Cu")
		(net "SW_PWR_R_HDD33")
	)
	(segment
		(start 425.1833 -14.0335)
		(end 426.72 -14.0335)
		(width 0.17145)
		(layer "F.Cu")
		(net "SW_PWR_R_HDD33")
	)
	(via
		(at 429.133 -14.0335)
		(size 0.6604)
		(drill 0.3302)
		(layers "F.Cu" "B.Cu")
		(net "SW_PWR_R_HDD33")
	)
	(segment
		(start 392.4554 -10.8204)
		(end 392.4554 -12.4968)
		(width 0.17145)
		(layer "F.Cu")
		(net "SW_PWR_R_HDD32")
	)
	(segment
		(start 396.875 -10.6045)
		(end 395.605 -10.6045)
		(width 0.17145)
		(layer "F.Cu")
		(net "SW_PWR_R_HDD32")
	)
	(segment
		(start 392.4554 -12.4968)
		(end 392.7856 -12.827)
		(width 0.17145)
		(layer "F.Cu")
		(net "SW_PWR_R_HDD32")
	)
	(segment
		(start 392.7856 -12.827)
		(end 393.5222 -12.827)
		(width 0.17145)
		(layer "F.Cu")
		(net "SW_PWR_R_HDD32")
	)
	(segment
		(start 392.6713 -10.6045)
		(end 392.4554 -10.8204)
		(width 0.17145)
		(layer "F.Cu")
		(net "SW_PWR_R_HDD32")
	)
	(segment
		(start 398.145 -10.6045)
		(end 396.875 -10.6045)
		(width 0.17145)
		(layer "F.Cu")
		(net "SW_PWR_R_HDD32")
	)
	(segment
		(start 395.605 -10.6045)
		(end 394.462 -10.6045)
		(width 0.17145)
		(layer "F.Cu")
		(net "SW_PWR_R_HDD32")
	)
	(segment
		(start 394.462 -10.6045)
		(end 392.6713 -10.6045)
		(width 0.17145)
		(layer "F.Cu")
		(net "SW_PWR_R_HDD32")
	)
	(via
		(at 396.875 -10.6045)
		(size 0.6604)
		(drill 0.3302)
		(layers "F.Cu" "B.Cu")
		(net "SW_PWR_R_HDD32")
	)
	(segment
		(start 363.601 -14.0335)
		(end 364.744 -14.0335)
		(width 0.17145)
		(layer "F.Cu")
		(net "SW_PWR_R_HDD31")
	)
	(segment
		(start 361.4166 -14.6304)
		(end 362.0135 -14.0335)
		(width 0.17145)
		(layer "F.Cu")
		(net "SW_PWR_R_HDD31")
	)
	(segment
		(start 362.0135 -14.0335)
		(end 363.601 -14.0335)
		(width 0.17145)
		(layer "F.Cu")
		(net "SW_PWR_R_HDD31")
	)
	(segment
		(start 362.6612 -16.256)
		(end 361.7976 -16.256)
		(width 0.17145)
		(layer "F.Cu")
		(net "SW_PWR_R_HDD31")
	)
	(segment
		(start 361.7976 -16.256)
		(end 361.4166 -15.875)
		(width 0.17145)
		(layer "F.Cu")
		(net "SW_PWR_R_HDD31")
	)
	(segment
		(start 361.4166 -15.875)
		(end 361.4166 -14.6304)
		(width 0.17145)
		(layer "F.Cu")
		(net "SW_PWR_R_HDD31")
	)
	(segment
		(start 364.744 -14.0335)
		(end 366.014 -14.0335)
		(width 0.17145)
		(layer "F.Cu")
		(net "SW_PWR_R_HDD31")
	)
	(segment
		(start 367.284 -14.0335)
		(end 366.014 -14.0335)
		(width 0.17145)
		(layer "F.Cu")
		(net "SW_PWR_R_HDD31")
	)
	(via
		(at 366.014 -14.0335)
		(size 0.6604)
		(drill 0.3302)
		(layers "F.Cu" "B.Cu")
		(net "SW_PWR_R_HDD31")
	)
	(segment
		(start 333.502 -10.6045)
		(end 332.232 -10.6045)
		(width 0.17145)
		(layer "F.Cu")
		(net "SW_PWR_R_HDD30")
	)
	(segment
		(start 329.3618 -12.4206)
		(end 329.7682 -12.827)
		(width 0.17145)
		(layer "F.Cu")
		(net "SW_PWR_R_HDD30")
	)
	(segment
		(start 329.7682 -12.827)
		(end 330.1492 -12.827)
		(width 0.17145)
		(layer "F.Cu")
		(net "SW_PWR_R_HDD30")
	)
	(segment
		(start 331.089 -10.6045)
		(end 329.6539 -10.6045)
		(width 0.17145)
		(layer "F.Cu")
		(net "SW_PWR_R_HDD30")
	)
	(segment
		(start 329.6539 -10.6045)
		(end 329.3618 -10.8966)
		(width 0.17145)
		(layer "F.Cu")
		(net "SW_PWR_R_HDD30")
	)
	(segment
		(start 334.772 -10.6045)
		(end 333.502 -10.6045)
		(width 0.17145)
		(layer "F.Cu")
		(net "SW_PWR_R_HDD30")
	)
	(segment
		(start 329.3618 -10.8966)
		(end 329.3618 -12.4206)
		(width 0.17145)
		(layer "F.Cu")
		(net "SW_PWR_R_HDD30")
	)
	(segment
		(start 332.232 -10.6045)
		(end 331.089 -10.6045)
		(width 0.17145)
		(layer "F.Cu")
		(net "SW_PWR_R_HDD30")
	)
	(via
		(at 333.502 -10.6045)
		(size 0.6604)
		(drill 0.3302)
		(layers "F.Cu" "B.Cu")
		(net "SW_PWR_R_HDD30")
	)
	(segment
		(start 115.443 -249.555)
		(end 117.1575 -249.555)
		(width 0.17145)
		(layer "F.Cu")
		(net "SW_PWR_R_HDD3")
	)
	(segment
		(start 117.1575 -248.954036)
		(end 117.1321 -248.928636)
		(width 0.17145)
		(layer "F.Cu")
		(net "SW_PWR_R_HDD3")
	)
	(segment
		(start 117.1321 -248.412)
		(end 116.6241 -247.904)
		(width 0.17145)
		(layer "F.Cu")
		(net "SW_PWR_R_HDD3")
	)
	(segment
		(start 115.062 -250.4948)
		(end 115.062 -249.936)
		(width 0.17145)
		(layer "F.Cu")
		(net "SW_PWR_R_HDD3")
	)
	(segment
		(start 117.1575 -249.555)
		(end 117.1575 -248.954036)
		(width 0.17145)
		(layer "F.Cu")
		(net "SW_PWR_R_HDD3")
	)
	(segment
		(start 116.6241 -247.269)
		(end 116.6241 -246.1768)
		(width 0.17145)
		(layer "F.Cu")
		(net "SW_PWR_R_HDD3")
	)
	(segment
		(start 117.1321 -248.928636)
		(end 117.1321 -248.412)
		(width 0.17145)
		(layer "F.Cu")
		(net "SW_PWR_R_HDD3")
	)
	(segment
		(start 116.6241 -247.904)
		(end 116.6241 -247.269)
		(width 0.17145)
		(layer "F.Cu")
		(net "SW_PWR_R_HDD3")
	)
	(segment
		(start 115.062 -249.936)
		(end 115.443 -249.555)
		(width 0.17145)
		(layer "F.Cu")
		(net "SW_PWR_R_HDD3")
	)
	(via
		(at 116.6241 -247.269)
		(size 0.6604)
		(drill 0.3302)
		(layers "F.Cu" "B.Cu")
		(net "SW_PWR_R_HDD3")
	)
	(segment
		(start 178.816 -17.018)
		(end 178.816 -18.7325)
		(width 0.17145)
		(layer "F.Cu")
		(net "SW_PWR_R_HDD29")
	)
	(segment
		(start 178.435 -16.637)
		(end 178.816 -17.018)
		(width 0.17145)
		(layer "F.Cu")
		(net "SW_PWR_R_HDD29")
	)
	(segment
		(start 180.975 -18.7325)
		(end 182.118 -18.7325)
		(width 0.17145)
		(layer "F.Cu")
		(net "SW_PWR_R_HDD29")
	)
	(segment
		(start 178.816 -18.7325)
		(end 179.815998 -18.7325)
		(width 0.17145)
		(layer "F.Cu")
		(net "SW_PWR_R_HDD29")
	)
	(segment
		(start 177.8762 -16.637)
		(end 178.435 -16.637)
		(width 0.17145)
		(layer "F.Cu")
		(net "SW_PWR_R_HDD29")
	)
	(segment
		(start 179.815998 -18.7325)
		(end 180.975 -18.7325)
		(width 0.17145)
		(layer "F.Cu")
		(net "SW_PWR_R_HDD29")
	)
	(via
		(at 179.815998 -18.7325)
		(size 0.6604)
		(drill 0.3302)
		(layers "F.Cu" "B.Cu")
		(net "SW_PWR_R_HDD29")
	)
	(segment
		(start 146.685 -19.939)
		(end 147.066 -19.558)
		(width 0.17145)
		(layer "F.Cu")
		(net "SW_PWR_R_HDD28")
	)
	(segment
		(start 148.2725 -16.3322)
		(end 148.2598 -16.3449)
		(width 0.17145)
		(layer "F.Cu")
		(net "SW_PWR_R_HDD28")
	)
	(segment
		(start 148.2598 -17.9959)
		(end 148.7551 -18.4912)
		(width 0.17145)
		(layer "F.Cu")
		(net "SW_PWR_R_HDD28")
	)
	(segment
		(start 148.2598 -17.3228)
		(end 148.2598 -17.9959)
		(width 0.17145)
		(layer "F.Cu")
		(net "SW_PWR_R_HDD28")
	)
	(segment
		(start 148.2598 -16.3449)
		(end 148.2598 -17.3228)
		(width 0.17145)
		(layer "F.Cu")
		(net "SW_PWR_R_HDD28")
	)
	(segment
		(start 148.7551 -18.9992)
		(end 148.7805 -19.0246)
		(width 0.17145)
		(layer "F.Cu")
		(net "SW_PWR_R_HDD28")
	)
	(segment
		(start 146.685 -20.4978)
		(end 146.685 -19.939)
		(width 0.17145)
		(layer "F.Cu")
		(net "SW_PWR_R_HDD28")
	)
	(segment
		(start 148.7551 -18.4912)
		(end 148.7551 -18.9992)
		(width 0.17145)
		(layer "F.Cu")
		(net "SW_PWR_R_HDD28")
	)
	(segment
		(start 147.066 -19.558)
		(end 148.7805 -19.558)
		(width 0.17145)
		(layer "F.Cu")
		(net "SW_PWR_R_HDD28")
	)
	(segment
		(start 148.7805 -19.0246)
		(end 148.7805 -19.558)
		(width 0.17145)
		(layer "F.Cu")
		(net "SW_PWR_R_HDD28")
	)
	(via
		(at 148.2598 -17.3228)
		(size 0.6604)
		(drill 0.3302)
		(layers "F.Cu" "B.Cu")
		(net "SW_PWR_R_HDD28")
	)
	(segment
		(start 117.3099 -18.7325)
		(end 117.856 -18.7325)
		(width 0.17145)
		(layer "F.Cu")
		(net "SW_PWR_R_HDD27")
	)
	(segment
		(start 116.4463 -19.5961)
		(end 116.5606 -19.4818)
		(width 0.17145)
		(layer "F.Cu")
		(net "SW_PWR_R_HDD27")
	)
	(segment
		(start 115.316 -19.5961)
		(end 116.4463 -19.5961)
		(width 0.17145)
		(layer "F.Cu")
		(net "SW_PWR_R_HDD27")
	)
	(segment
		(start 114.935 -16.637)
		(end 115.316 -17.018)
		(width 0.17145)
		(layer "F.Cu")
		(net "SW_PWR_R_HDD27")
	)
	(segment
		(start 114.3762 -16.637)
		(end 114.935 -16.637)
		(width 0.17145)
		(layer "F.Cu")
		(net "SW_PWR_R_HDD27")
	)
	(segment
		(start 117.856 -18.7325)
		(end 118.999 -18.7325)
		(width 0.17145)
		(layer "F.Cu")
		(net "SW_PWR_R_HDD27")
	)
	(segment
		(start 115.316 -17.018)
		(end 115.316 -19.5961)
		(width 0.17145)
		(layer "F.Cu")
		(net "SW_PWR_R_HDD27")
	)
	(segment
		(start 116.5606 -19.4818)
		(end 117.3099 -18.7325)
		(width 0.17145)
		(layer "F.Cu")
		(net "SW_PWR_R_HDD27")
	)
	(via
		(at 116.5606 -19.4818)
		(size 0.6604)
		(drill 0.3302)
		(layers "F.Cu" "B.Cu")
		(net "SW_PWR_R_HDD27")
	)
	(segment
		(start 85.6615 -18.976086)
		(end 85.6361 -18.950686)
		(width 0.17145)
		(layer "F.Cu")
		(net "SW_PWR_R_HDD26")
	)
	(segment
		(start 85.0773 -16.581374)
		(end 85.1154 -16.619474)
		(width 0.17145)
		(layer "F.Cu")
		(net "SW_PWR_R_HDD26")
	)
	(segment
		(start 85.6361 -18.950686)
		(end 85.6361 -18.4404)
		(width 0.17145)
		(layer "F.Cu")
		(net "SW_PWR_R_HDD26")
	)
	(segment
		(start 83.566 -20.4978)
		(end 83.566 -19.939)
		(width 0.17145)
		(layer "F.Cu")
		(net "SW_PWR_R_HDD26")
	)
	(segment
		(start 85.6615 -19.558)
		(end 85.6615 -18.976086)
		(width 0.17145)
		(layer "F.Cu")
		(net "SW_PWR_R_HDD26")
	)
	(segment
		(start 85.6361 -18.090896)
		(end 85.6361 -18.4404)
		(width 0.17145)
		(layer "F.Cu")
		(net "SW_PWR_R_HDD26")
	)
	(segment
		(start 83.947 -19.558)
		(end 85.6615 -19.558)
		(width 0.17145)
		(layer "F.Cu")
		(net "SW_PWR_R_HDD26")
	)
	(segment
		(start 85.1154 -17.570196)
		(end 85.6361 -18.090896)
		(width 0.17145)
		(layer "F.Cu")
		(net "SW_PWR_R_HDD26")
	)
	(segment
		(start 85.0773 -16.1798)
		(end 85.0773 -16.581374)
		(width 0.17145)
		(layer "F.Cu")
		(net "SW_PWR_R_HDD26")
	)
	(segment
		(start 85.1154 -17.2212)
		(end 85.1154 -17.570196)
		(width 0.17145)
		(layer "F.Cu")
		(net "SW_PWR_R_HDD26")
	)
	(segment
		(start 83.566 -19.939)
		(end 83.947 -19.558)
		(width 0.17145)
		(layer "F.Cu")
		(net "SW_PWR_R_HDD26")
	)
	(segment
		(start 85.1154 -16.619474)
		(end 85.1154 -17.2212)
		(width 0.17145)
		(layer "F.Cu")
		(net "SW_PWR_R_HDD26")
	)
	(via
		(at 85.1154 -17.2212)
		(size 0.6604)
		(drill 0.3302)
		(layers "F.Cu" "B.Cu")
		(net "SW_PWR_R_HDD26")
	)
	(segment
		(start 52.578 -18.7325)
		(end 53.615844 -18.7325)
		(width 0.17145)
		(layer "F.Cu")
		(net "SW_PWR_R_HDD25")
	)
	(segment
		(start 51.6382 -16.637)
		(end 52.197 -16.637)
		(width 0.17145)
		(layer "F.Cu")
		(net "SW_PWR_R_HDD25")
	)
	(segment
		(start 52.578 -17.018)
		(end 52.578 -18.7325)
		(width 0.17145)
		(layer "F.Cu")
		(net "SW_PWR_R_HDD25")
	)
	(segment
		(start 55.88 -18.7325)
		(end 54.737 -18.7325)
		(width 0.17145)
		(layer "F.Cu")
		(net "SW_PWR_R_HDD25")
	)
	(segment
		(start 52.197 -16.637)
		(end 52.578 -17.018)
		(width 0.17145)
		(layer "F.Cu")
		(net "SW_PWR_R_HDD25")
	)
	(segment
		(start 53.615844 -18.7325)
		(end 54.737 -18.7325)
		(width 0.17145)
		(layer "F.Cu")
		(net "SW_PWR_R_HDD25")
	)
	(via
		(at 53.615844 -18.7325)
		(size 0.6604)
		(drill 0.3302)
		(layers "F.Cu" "B.Cu")
		(net "SW_PWR_R_HDD25")
	)
	(segment
		(start 21.7297 -15.9512)
		(end 21.7297 -17.1831)
		(width 0.17145)
		(layer "F.Cu")
		(net "SW_PWR_R_HDD24")
	)
	(segment
		(start 22.5425 -17.9959)
		(end 22.5425 -18.3896)
		(width 0.17145)
		(layer "F.Cu")
		(net "SW_PWR_R_HDD24")
	)
	(segment
		(start 20.447 -19.939)
		(end 20.828 -19.558)
		(width 0.17145)
		(layer "F.Cu")
		(net "SW_PWR_R_HDD24")
	)
	(segment
		(start 21.7424 -17.1958)
		(end 22.5425 -17.9959)
		(width 0.17145)
		(layer "F.Cu")
		(net "SW_PWR_R_HDD24")
	)
	(segment
		(start 21.7297 -17.1831)
		(end 21.7424 -17.1958)
		(width 0.17145)
		(layer "F.Cu")
		(net "SW_PWR_R_HDD24")
	)
	(segment
		(start 20.447 -20.4978)
		(end 20.447 -19.939)
		(width 0.17145)
		(layer "F.Cu")
		(net "SW_PWR_R_HDD24")
	)
	(segment
		(start 20.828 -19.558)
		(end 22.5425 -19.558)
		(width 0.17145)
		(layer "F.Cu")
		(net "SW_PWR_R_HDD24")
	)
	(segment
		(start 22.5425 -19.558)
		(end 22.5425 -18.3896)
		(width 0.17145)
		(layer "F.Cu")
		(net "SW_PWR_R_HDD24")
	)
	(via
		(at 21.7424 -17.1958)
		(size 0.6604)
		(drill 0.3302)
		(layers "F.Cu" "B.Cu")
		(net "SW_PWR_R_HDD24")
	)
	(segment
		(start 470.662 -129.7305)
		(end 471.932 -129.7305)
		(width 0.17145)
		(layer "F.Cu")
		(net "SW_PWR_R_HDD23")
	)
	(segment
		(start 473.583 -131.826)
		(end 473.202 -131.445)
		(width 0.17145)
		(layer "F.Cu")
		(net "SW_PWR_R_HDD23")
	)
	(segment
		(start 473.202 -131.445)
		(end 473.202 -129.7305)
		(width 0.17145)
		(layer "F.Cu")
		(net "SW_PWR_R_HDD23")
	)
	(segment
		(start 469.519 -129.7305)
		(end 470.662 -129.7305)
		(width 0.17145)
		(layer "F.Cu")
		(net "SW_PWR_R_HDD23")
	)
	(segment
		(start 473.202 -129.7305)
		(end 471.932 -129.7305)
		(width 0.17145)
		(layer "F.Cu")
		(net "SW_PWR_R_HDD23")
	)
	(segment
		(start 474.1418 -131.826)
		(end 473.583 -131.826)
		(width 0.17145)
		(layer "F.Cu")
		(net "SW_PWR_R_HDD23")
	)
	(via
		(at 471.932 -129.7305)
		(size 0.6604)
		(drill 0.3302)
		(layers "F.Cu" "B.Cu")
		(net "SW_PWR_R_HDD23")
	)
	(segment
		(start 460.629 -129.0955)
		(end 459.359 -129.0955)
		(width 0.17145)
		(layer "F.Cu")
		(net "SW_PWR_R_HDD22")
	)
	(segment
		(start 457.2762 -131.318)
		(end 456.4634 -131.318)
		(width 0.17145)
		(layer "F.Cu")
		(net "SW_PWR_R_HDD22")
	)
	(segment
		(start 456.7301 -129.0955)
		(end 458.216 -129.0955)
		(width 0.17145)
		(layer "F.Cu")
		(net "SW_PWR_R_HDD22")
	)
	(segment
		(start 456.4634 -131.318)
		(end 456.057 -130.9116)
		(width 0.17145)
		(layer "F.Cu")
		(net "SW_PWR_R_HDD22")
	)
	(segment
		(start 459.359 -129.0955)
		(end 458.216 -129.0955)
		(width 0.17145)
		(layer "F.Cu")
		(net "SW_PWR_R_HDD22")
	)
	(segment
		(start 456.057 -130.9116)
		(end 456.057 -129.7686)
		(width 0.17145)
		(layer "F.Cu")
		(net "SW_PWR_R_HDD22")
	)
	(segment
		(start 456.057 -129.7686)
		(end 456.7301 -129.0955)
		(width 0.17145)
		(layer "F.Cu")
		(net "SW_PWR_R_HDD22")
	)
	(segment
		(start 461.899 -129.0955)
		(end 460.629 -129.0955)
		(width 0.17145)
		(layer "F.Cu")
		(net "SW_PWR_R_HDD22")
	)
	(via
		(at 460.629 -129.0955)
		(size 0.6604)
		(drill 0.3302)
		(layers "F.Cu" "B.Cu")
		(net "SW_PWR_R_HDD22")
	)
	(segment
		(start 424.8912 -131.318)
		(end 424.5356 -130.9624)
		(width 0.17145)
		(layer "F.Cu")
		(net "SW_PWR_R_HDD21")
	)
	(segment
		(start 427.863 -129.0955)
		(end 426.72 -129.0955)
		(width 0.17145)
		(layer "F.Cu")
		(net "SW_PWR_R_HDD21")
	)
	(segment
		(start 429.133 -129.0955)
		(end 427.863 -129.0955)
		(width 0.17145)
		(layer "F.Cu")
		(net "SW_PWR_R_HDD21")
	)
	(segment
		(start 425.7802 -131.318)
		(end 424.8912 -131.318)
		(width 0.17145)
		(layer "F.Cu")
		(net "SW_PWR_R_HDD21")
	)
	(segment
		(start 424.5356 -130.9624)
		(end 424.5356 -129.413)
		(width 0.17145)
		(layer "F.Cu")
		(net "SW_PWR_R_HDD21")
	)
	(segment
		(start 424.5356 -129.413)
		(end 424.8531 -129.0955)
		(width 0.17145)
		(layer "F.Cu")
		(net "SW_PWR_R_HDD21")
	)
	(segment
		(start 424.8531 -129.0955)
		(end 426.72 -129.0955)
		(width 0.17145)
		(layer "F.Cu")
		(net "SW_PWR_R_HDD21")
	)
	(segment
		(start 430.403 -129.0955)
		(end 429.133 -129.0955)
		(width 0.17145)
		(layer "F.Cu")
		(net "SW_PWR_R_HDD21")
	)
	(via
		(at 429.133 -129.0955)
		(size 0.6604)
		(drill 0.3302)
		(layers "F.Cu" "B.Cu")
		(net "SW_PWR_R_HDD21")
	)
	(segment
		(start 394.2842 -131.318)
		(end 393.4714 -131.318)
		(width 0.17145)
		(layer "F.Cu")
		(net "SW_PWR_R_HDD20")
	)
	(segment
		(start 393.2809 -129.0955)
		(end 395.224 -129.0955)
		(width 0.17145)
		(layer "F.Cu")
		(net "SW_PWR_R_HDD20")
	)
	(segment
		(start 393.4714 -131.318)
		(end 392.938 -130.7846)
		(width 0.17145)
		(layer "F.Cu")
		(net "SW_PWR_R_HDD20")
	)
	(segment
		(start 397.637 -129.0955)
		(end 396.367 -129.0955)
		(width 0.17145)
		(layer "F.Cu")
		(net "SW_PWR_R_HDD20")
	)
	(segment
		(start 392.938 -130.7846)
		(end 392.938 -129.4384)
		(width 0.17145)
		(layer "F.Cu")
		(net "SW_PWR_R_HDD20")
	)
	(segment
		(start 396.367 -129.0955)
		(end 395.224 -129.0955)
		(width 0.17145)
		(layer "F.Cu")
		(net "SW_PWR_R_HDD20")
	)
	(segment
		(start 392.938 -129.4384)
		(end 393.2809 -129.0955)
		(width 0.17145)
		(layer "F.Cu")
		(net "SW_PWR_R_HDD20")
	)
	(segment
		(start 398.907 -129.0955)
		(end 397.637 -129.0955)
		(width 0.17145)
		(layer "F.Cu")
		(net "SW_PWR_R_HDD20")
	)
	(via
		(at 397.637 -129.0955)
		(size 0.6604)
		(drill 0.3302)
		(layers "F.Cu" "B.Cu")
		(net "SW_PWR_R_HDD20")
	)
	(segment
		(start 85.6361 -248.4628)
		(end 85.0265 -247.8532)
		(width 0.17145)
		(layer "F.Cu")
		(net "SW_PWR_R_HDD2")
	)
	(segment
		(start 85.6615 -249.555)
		(end 85.6361 -249.5296)
		(width 0.17145)
		(layer "F.Cu")
		(net "SW_PWR_R_HDD2")
	)
	(segment
		(start 83.947 -249.555)
		(end 85.6615 -249.555)
		(width 0.17145)
		(layer "F.Cu")
		(net "SW_PWR_R_HDD2")
	)
	(segment
		(start 83.566 -249.936)
		(end 83.947 -249.555)
		(width 0.17145)
		(layer "F.Cu")
		(net "SW_PWR_R_HDD2")
	)
	(segment
		(start 85.0265 -247.1928)
		(end 85.0265 -246.2276)
		(width 0.17145)
		(layer "F.Cu")
		(net "SW_PWR_R_HDD2")
	)
	(segment
		(start 85.6361 -249.5296)
		(end 85.6361 -248.4628)
		(width 0.17145)
		(layer "F.Cu")
		(net "SW_PWR_R_HDD2")
	)
	(segment
		(start 83.566 -250.4948)
		(end 83.566 -249.936)
		(width 0.17145)
		(layer "F.Cu")
		(net "SW_PWR_R_HDD2")
	)
	(segment
		(start 85.0265 -247.8532)
		(end 85.0265 -247.1928)
		(width 0.17145)
		(layer "F.Cu")
		(net "SW_PWR_R_HDD2")
	)
	(via
		(at 85.0265 -247.1928)
		(size 0.6604)
		(drill 0.3302)
		(layers "F.Cu" "B.Cu")
		(net "SW_PWR_R_HDD2")
	)
	(segment
		(start 361.1118 -130.8862)
		(end 361.1118 -129.7432)
		(width 0.17145)
		(layer "F.Cu")
		(net "SW_PWR_R_HDD19")
	)
	(segment
		(start 366.014 -129.0955)
		(end 364.744 -129.0955)
		(width 0.17145)
		(layer "F.Cu")
		(net "SW_PWR_R_HDD19")
	)
	(segment
		(start 362.6612 -131.318)
		(end 361.5436 -131.318)
		(width 0.17145)
		(layer "F.Cu")
		(net "SW_PWR_R_HDD19")
	)
	(segment
		(start 361.7595 -129.0955)
		(end 363.601 -129.0955)
		(width 0.17145)
		(layer "F.Cu")
		(net "SW_PWR_R_HDD19")
	)
	(segment
		(start 364.744 -129.0955)
		(end 363.601 -129.0955)
		(width 0.17145)
		(layer "F.Cu")
		(net "SW_PWR_R_HDD19")
	)
	(segment
		(start 361.1118 -129.7432)
		(end 361.7595 -129.0955)
		(width 0.17145)
		(layer "F.Cu")
		(net "SW_PWR_R_HDD19")
	)
	(segment
		(start 361.5436 -131.318)
		(end 361.1118 -130.8862)
		(width 0.17145)
		(layer "F.Cu")
		(net "SW_PWR_R_HDD19")
	)
	(segment
		(start 367.284 -129.0955)
		(end 366.014 -129.0955)
		(width 0.17145)
		(layer "F.Cu")
		(net "SW_PWR_R_HDD19")
	)
	(via
		(at 366.014 -129.0955)
		(size 0.6604)
		(drill 0.3302)
		(layers "F.Cu" "B.Cu")
		(net "SW_PWR_R_HDD19")
	)
	(segment
		(start 329.8698 -130.8354)
		(end 329.8698 -129.4892)
		(width 0.17145)
		(layer "F.Cu")
		(net "SW_PWR_R_HDD18")
	)
	(segment
		(start 335.788 -129.0955)
		(end 334.518 -129.0955)
		(width 0.17145)
		(layer "F.Cu")
		(net "SW_PWR_R_HDD18")
	)
	(segment
		(start 330.3524 -131.318)
		(end 329.8698 -130.8354)
		(width 0.17145)
		(layer "F.Cu")
		(net "SW_PWR_R_HDD18")
	)
	(segment
		(start 334.518 -129.0955)
		(end 333.248 -129.0955)
		(width 0.17145)
		(layer "F.Cu")
		(net "SW_PWR_R_HDD18")
	)
	(segment
		(start 329.8698 -129.4892)
		(end 330.2635 -129.0955)
		(width 0.17145)
		(layer "F.Cu")
		(net "SW_PWR_R_HDD18")
	)
	(segment
		(start 331.1652 -131.318)
		(end 330.3524 -131.318)
		(width 0.17145)
		(layer "F.Cu")
		(net "SW_PWR_R_HDD18")
	)
	(segment
		(start 330.2635 -129.0955)
		(end 332.105 -129.0955)
		(width 0.17145)
		(layer "F.Cu")
		(net "SW_PWR_R_HDD18")
	)
	(segment
		(start 333.248 -129.0955)
		(end 332.105 -129.0955)
		(width 0.17145)
		(layer "F.Cu")
		(net "SW_PWR_R_HDD18")
	)
	(via
		(at 334.518 -129.0955)
		(size 0.6604)
		(drill 0.3302)
		(layers "F.Cu" "B.Cu")
		(net "SW_PWR_R_HDD18")
	)
	(segment
		(start 179.7812 -132.2832)
		(end 179.7812 -131.3053)
		(width 0.17145)
		(layer "F.Cu")
		(net "SW_PWR_R_HDD17")
	)
	(segment
		(start 178.562 -134.493)
		(end 180.2765 -134.493)
		(width 0.17145)
		(layer "F.Cu")
		(net "SW_PWR_R_HDD17")
	)
	(segment
		(start 180.2511 -134.4676)
		(end 180.2765 -134.493)
		(width 0.17145)
		(layer "F.Cu")
		(net "SW_PWR_R_HDD17")
	)
	(segment
		(start 178.181 -135.4328)
		(end 178.181 -134.874)
		(width 0.17145)
		(layer "F.Cu")
		(net "SW_PWR_R_HDD17")
	)
	(segment
		(start 178.181 -134.874)
		(end 178.562 -134.493)
		(width 0.17145)
		(layer "F.Cu")
		(net "SW_PWR_R_HDD17")
	)
	(segment
		(start 180.2511 -133.4262)
		(end 180.2511 -134.4676)
		(width 0.17145)
		(layer "F.Cu")
		(net "SW_PWR_R_HDD17")
	)
	(segment
		(start 180.2511 -133.4262)
		(end 179.7812 -132.9563)
		(width 0.17145)
		(layer "F.Cu")
		(net "SW_PWR_R_HDD17")
	)
	(segment
		(start 179.7812 -132.9563)
		(end 179.7812 -132.2832)
		(width 0.17145)
		(layer "F.Cu")
		(net "SW_PWR_R_HDD17")
	)
	(via
		(at 179.7812 -132.2832)
		(size 0.6604)
		(drill 0.3302)
		(layers "F.Cu" "B.Cu")
		(net "SW_PWR_R_HDD17")
	)
	(segment
		(start 148.2217 -132.1562)
		(end 148.2217 -131.1402)
		(width 0.17145)
		(layer "F.Cu")
		(net "SW_PWR_R_HDD16")
	)
	(segment
		(start 148.2217 -132.9182)
		(end 148.2217 -132.1562)
		(width 0.17145)
		(layer "F.Cu")
		(net "SW_PWR_R_HDD16")
	)
	(segment
		(start 148.7551 -133.4516)
		(end 148.2217 -132.9182)
		(width 0.17145)
		(layer "F.Cu")
		(net "SW_PWR_R_HDD16")
	)
	(segment
		(start 146.685 -134.874)
		(end 147.066 -134.493)
		(width 0.17145)
		(layer "F.Cu")
		(net "SW_PWR_R_HDD16")
	)
	(segment
		(start 147.066 -134.493)
		(end 148.7805 -134.493)
		(width 0.17145)
		(layer "F.Cu")
		(net "SW_PWR_R_HDD16")
	)
	(segment
		(start 148.7805 -134.493)
		(end 148.7805 -133.477)
		(width 0.17145)
		(layer "F.Cu")
		(net "SW_PWR_R_HDD16")
	)
	(segment
		(start 146.685 -135.4328)
		(end 146.685 -134.874)
		(width 0.17145)
		(layer "F.Cu")
		(net "SW_PWR_R_HDD16")
	)
	(segment
		(start 148.7805 -133.477)
		(end 148.7551 -133.4516)
		(width 0.17145)
		(layer "F.Cu")
		(net "SW_PWR_R_HDD16")
	)
	(via
		(at 148.2217 -132.1562)
		(size 0.6604)
		(drill 0.3302)
		(layers "F.Cu" "B.Cu")
		(net "SW_PWR_R_HDD16")
	)
	(segment
		(start 116.6749 -132.2324)
		(end 116.6749 -132.9436)
		(width 0.17145)
		(layer "F.Cu")
		(net "SW_PWR_R_HDD15")
	)
	(segment
		(start 117.1575 -134.493)
		(end 117.1575 -133.4262)
		(width 0.17145)
		(layer "F.Cu")
		(net "SW_PWR_R_HDD15")
	)
	(segment
		(start 116.6749 -132.2324)
		(end 116.6749 -131.2926)
		(width 0.17145)
		(layer "F.Cu")
		(net "SW_PWR_R_HDD15")
	)
	(segment
		(start 115.062 -134.874)
		(end 115.443 -134.493)
		(width 0.17145)
		(layer "F.Cu")
		(net "SW_PWR_R_HDD15")
	)
	(segment
		(start 115.443 -134.493)
		(end 117.1575 -134.493)
		(width 0.17145)
		(layer "F.Cu")
		(net "SW_PWR_R_HDD15")
	)
	(segment
		(start 115.062 -135.4328)
		(end 115.062 -134.874)
		(width 0.17145)
		(layer "F.Cu")
		(net "SW_PWR_R_HDD15")
	)
	(segment
		(start 116.6749 -132.9436)
		(end 117.1575 -133.4262)
		(width 0.17145)
		(layer "F.Cu")
		(net "SW_PWR_R_HDD15")
	)
	(via
		(at 116.6749 -132.2324)
		(size 0.6604)
		(drill 0.3302)
		(layers "F.Cu" "B.Cu")
		(net "SW_PWR_R_HDD15")
	)
	(segment
		(start 83.566 -135.4328)
		(end 83.566 -134.874)
		(width 0.17145)
		(layer "F.Cu")
		(net "SW_PWR_R_HDD14")
	)
	(segment
		(start 85.1027 -132.2578)
		(end 85.1027 -131.2672)
		(width 0.17145)
		(layer "F.Cu")
		(net "SW_PWR_R_HDD14")
	)
	(segment
		(start 85.6615 -134.493)
		(end 85.6615 -133.4262)
		(width 0.17145)
		(layer "F.Cu")
		(net "SW_PWR_R_HDD14")
	)
	(segment
		(start 85.6615 -133.4262)
		(end 85.1027 -132.8674)
		(width 0.17145)
		(layer "F.Cu")
		(net "SW_PWR_R_HDD14")
	)
	(segment
		(start 83.947 -134.493)
		(end 85.6615 -134.493)
		(width 0.17145)
		(layer "F.Cu")
		(net "SW_PWR_R_HDD14")
	)
	(segment
		(start 83.566 -134.874)
		(end 83.947 -134.493)
		(width 0.17145)
		(layer "F.Cu")
		(net "SW_PWR_R_HDD14")
	)
	(segment
		(start 85.1027 -132.8674)
		(end 85.1027 -132.2578)
		(width 0.17145)
		(layer "F.Cu")
		(net "SW_PWR_R_HDD14")
	)
	(via
		(at 85.1027 -132.2578)
		(size 0.6604)
		(drill 0.3302)
		(layers "F.Cu" "B.Cu")
		(net "SW_PWR_R_HDD14")
	)
	(segment
		(start 53.6321 -133.0198)
		(end 53.6321 -132.207)
		(width 0.17145)
		(layer "F.Cu")
		(net "SW_PWR_R_HDD13")
	)
	(segment
		(start 51.943 -134.874)
		(end 52.324 -134.493)
		(width 0.17145)
		(layer "F.Cu")
		(net "SW_PWR_R_HDD13")
	)
	(segment
		(start 54.0131 -133.8072)
		(end 54.0131 -133.4008)
		(width 0.17145)
		(layer "F.Cu")
		(net "SW_PWR_R_HDD13")
	)
	(segment
		(start 52.324 -134.493)
		(end 54.0385 -134.493)
		(width 0.17145)
		(layer "F.Cu")
		(net "SW_PWR_R_HDD13")
	)
	(segment
		(start 53.6321 -132.207)
		(end 53.6321 -131.2164)
		(width 0.17145)
		(layer "F.Cu")
		(net "SW_PWR_R_HDD13")
	)
	(segment
		(start 54.0385 -133.8326)
		(end 54.0131 -133.8072)
		(width 0.17145)
		(layer "F.Cu")
		(net "SW_PWR_R_HDD13")
	)
	(segment
		(start 54.0131 -133.4008)
		(end 53.6321 -133.0198)
		(width 0.17145)
		(layer "F.Cu")
		(net "SW_PWR_R_HDD13")
	)
	(segment
		(start 54.0385 -134.493)
		(end 54.0385 -133.8326)
		(width 0.17145)
		(layer "F.Cu")
		(net "SW_PWR_R_HDD13")
	)
	(segment
		(start 51.943 -135.4328)
		(end 51.943 -134.874)
		(width 0.17145)
		(layer "F.Cu")
		(net "SW_PWR_R_HDD13")
	)
	(via
		(at 53.6321 -132.207)
		(size 0.6604)
		(drill 0.3302)
		(layers "F.Cu" "B.Cu")
		(net "SW_PWR_R_HDD13")
	)
	(segment
		(start 22.5425 -134.493)
		(end 22.5425 -133.9342)
		(width 0.17145)
		(layer "F.Cu")
		(net "SW_PWR_R_HDD12")
	)
	(segment
		(start 22.4917 -133.4262)
		(end 22.0599 -132.9944)
		(width 0.17145)
		(layer "F.Cu")
		(net "SW_PWR_R_HDD12")
	)
	(segment
		(start 20.828 -134.493)
		(end 22.5425 -134.493)
		(width 0.17145)
		(layer "F.Cu")
		(net "SW_PWR_R_HDD12")
	)
	(segment
		(start 22.5425 -133.9342)
		(end 22.4917 -133.8834)
		(width 0.17145)
		(layer "F.Cu")
		(net "SW_PWR_R_HDD12")
	)
	(segment
		(start 20.447 -135.4328)
		(end 20.447 -134.874)
		(width 0.17145)
		(layer "F.Cu")
		(net "SW_PWR_R_HDD12")
	)
	(segment
		(start 22.0599 -132.9944)
		(end 22.0599 -132.2324)
		(width 0.17145)
		(layer "F.Cu")
		(net "SW_PWR_R_HDD12")
	)
	(segment
		(start 20.447 -134.874)
		(end 20.828 -134.493)
		(width 0.17145)
		(layer "F.Cu")
		(net "SW_PWR_R_HDD12")
	)
	(segment
		(start 22.0599 -131.2672)
		(end 22.0599 -132.2324)
		(width 0.17145)
		(layer "F.Cu")
		(net "SW_PWR_R_HDD12")
	)
	(segment
		(start 22.4917 -133.8834)
		(end 22.4917 -133.4262)
		(width 0.17145)
		(layer "F.Cu")
		(net "SW_PWR_R_HDD12")
	)
	(via
		(at 22.0599 -132.2324)
		(size 0.6604)
		(drill 0.3302)
		(layers "F.Cu" "B.Cu")
		(net "SW_PWR_R_HDD12")
	)
	(segment
		(start 470.662 -244.7925)
		(end 469.519 -244.7925)
		(width 0.17145)
		(layer "F.Cu")
		(net "SW_PWR_R_HDD11")
	)
	(segment
		(start 474.1418 -246.888)
		(end 474.113606 -246.916194)
		(width 0.17145)
		(layer "F.Cu")
		(net "SW_PWR_R_HDD11")
	)
	(segment
		(start 473.202 -246.507)
		(end 473.202 -244.7925)
		(width 0.17145)
		(layer "F.Cu")
		(net "SW_PWR_R_HDD11")
	)
	(segment
		(start 471.932 -244.7925)
		(end 470.662 -244.7925)
		(width 0.17145)
		(layer "F.Cu")
		(net "SW_PWR_R_HDD11")
	)
	(segment
		(start 474.113606 -246.916194)
		(end 473.611194 -246.916194)
		(width 0.17145)
		(layer "F.Cu")
		(net "SW_PWR_R_HDD11")
	)
	(segment
		(start 473.202 -244.7925)
		(end 471.932 -244.7925)
		(width 0.17145)
		(layer "F.Cu")
		(net "SW_PWR_R_HDD11")
	)
	(segment
		(start 473.611194 -246.916194)
		(end 473.202 -246.507)
		(width 0.17145)
		(layer "F.Cu")
		(net "SW_PWR_R_HDD11")
	)
	(via
		(at 471.932 -244.7925)
		(size 0.6604)
		(drill 0.3302)
		(layers "F.Cu" "B.Cu")
		(net "SW_PWR_R_HDD11")
	)
	(segment
		(start 455.9808 -245.8466)
		(end 455.9808 -244.3988)
		(width 0.17145)
		(layer "F.Cu")
		(net "SW_PWR_R_HDD10")
	)
	(segment
		(start 459.359 -244.0305)
		(end 458.216 -244.0305)
		(width 0.17145)
		(layer "F.Cu")
		(net "SW_PWR_R_HDD10")
	)
	(segment
		(start 461.899 -244.0305)
		(end 460.629 -244.0305)
		(width 0.17145)
		(layer "F.Cu")
		(net "SW_PWR_R_HDD10")
	)
	(segment
		(start 457.2762 -246.253)
		(end 456.3872 -246.253)
		(width 0.17145)
		(layer "F.Cu")
		(net "SW_PWR_R_HDD10")
	)
	(segment
		(start 456.3491 -244.0305)
		(end 458.216 -244.0305)
		(width 0.17145)
		(layer "F.Cu")
		(net "SW_PWR_R_HDD10")
	)
	(segment
		(start 456.3872 -246.253)
		(end 455.9808 -245.8466)
		(width 0.17145)
		(layer "F.Cu")
		(net "SW_PWR_R_HDD10")
	)
	(segment
		(start 460.629 -244.0305)
		(end 459.359 -244.0305)
		(width 0.17145)
		(layer "F.Cu")
		(net "SW_PWR_R_HDD10")
	)
	(segment
		(start 455.9808 -244.3988)
		(end 456.3491 -244.0305)
		(width 0.17145)
		(layer "F.Cu")
		(net "SW_PWR_R_HDD10")
	)
	(via
		(at 460.629 -244.0305)
		(size 0.6604)
		(drill 0.3302)
		(layers "F.Cu" "B.Cu")
		(net "SW_PWR_R_HDD10")
	)
	(segment
		(start 52.07 -249.936)
		(end 52.451 -249.555)
		(width 0.17145)
		(layer "F.Cu")
		(net "SW_PWR_R_HDD1")
	)
	(segment
		(start 54.1655 -248.4374)
		(end 53.5559 -247.8278)
		(width 0.17145)
		(layer "F.Cu")
		(net "SW_PWR_R_HDD1")
	)
	(segment
		(start 53.5559 -247.8278)
		(end 53.5559 -247.3452)
		(width 0.17145)
		(layer "F.Cu")
		(net "SW_PWR_R_HDD1")
	)
	(segment
		(start 52.451 -249.555)
		(end 54.1655 -249.555)
		(width 0.17145)
		(layer "F.Cu")
		(net "SW_PWR_R_HDD1")
	)
	(segment
		(start 53.5559 -247.3452)
		(end 53.5559 -246.3038)
		(width 0.17145)
		(layer "F.Cu")
		(net "SW_PWR_R_HDD1")
	)
	(segment
		(start 54.1655 -249.555)
		(end 54.1655 -248.4374)
		(width 0.17145)
		(layer "F.Cu")
		(net "SW_PWR_R_HDD1")
	)
	(segment
		(start 52.07 -250.4948)
		(end 52.07 -249.936)
		(width 0.17145)
		(layer "F.Cu")
		(net "SW_PWR_R_HDD1")
	)
	(via
		(at 53.5559 -247.3452)
		(size 0.6604)
		(drill 0.3302)
		(layers "F.Cu" "B.Cu")
		(net "SW_PWR_R_HDD1")
	)
	(segment
		(start 428.51324 -246.90324)
		(end 428.8155 -247.2055)
		(width 0.17145)
		(layer "F.Cu")
		(net "SW_HDD_R9")
	)
	(segment
		(start 431.546 -247.2055)
		(end 431.546 -248.031)
		(width 0.17145)
		(layer "F.Cu")
		(net "SW_HDD_R9")
	)
	(segment
		(start 431.546 -248.031)
		(end 430.784 -248.793)
		(width 0.17145)
		(layer "F.Cu")
		(net "SW_HDD_R9")
	)
	(segment
		(start 432.2445 -250.444)
		(end 431.038 -250.444)
		(width 0.17145)
		(layer "F.Cu")
		(net "SW_HDD_R9")
	)
	(segment
		(start 427.6598 -246.90324)
		(end 428.51324 -246.90324)
		(width 0.17145)
		(layer "F.Cu")
		(net "SW_HDD_R9")
	)
	(segment
		(start 430.784 -250.19)
		(end 431.038 -250.444)
		(width 0.17145)
		(layer "F.Cu")
		(net "SW_HDD_R9")
	)
	(segment
		(start 428.8155 -247.2055)
		(end 430.403 -247.2055)
		(width 0.17145)
		(layer "F.Cu")
		(net "SW_HDD_R9")
	)
	(segment
		(start 430.403 -247.2055)
		(end 431.546 -247.2055)
		(width 0.17145)
		(layer "F.Cu")
		(net "SW_HDD_R9")
	)
	(segment
		(start 430.784 -248.793)
		(end 430.784 -250.19)
		(width 0.17145)
		(layer "F.Cu")
		(net "SW_HDD_R9")
	)
	(via
		(at 431.038 -250.444)
		(size 0.6604)
		(drill 0.3302)
		(layers "F.Cu" "B.Cu")
		(net "SW_HDD_R9")
	)
	(segment
		(start 399.288 -250.19)
		(end 399.542 -250.444)
		(width 0.17145)
		(layer "F.Cu")
		(net "SW_HDD_R8")
	)
	(segment
		(start 397.01724 -246.90324)
		(end 397.3195 -247.2055)
		(width 0.17145)
		(layer "F.Cu")
		(net "SW_HDD_R8")
	)
	(segment
		(start 399.288 -248.793)
		(end 399.288 -250.19)
		(width 0.17145)
		(layer "F.Cu")
		(net "SW_HDD_R8")
	)
	(segment
		(start 396.1638 -246.90324)
		(end 397.01724 -246.90324)
		(width 0.17145)
		(layer "F.Cu")
		(net "SW_HDD_R8")
	)
	(segment
		(start 400.05 -247.2055)
		(end 400.05 -248.031)
		(width 0.17145)
		(layer "F.Cu")
		(net "SW_HDD_R8")
	)
	(segment
		(start 398.907 -247.2055)
		(end 400.05 -247.2055)
		(width 0.17145)
		(layer "F.Cu")
		(net "SW_HDD_R8")
	)
	(segment
		(start 400.05 -248.031)
		(end 399.288 -248.793)
		(width 0.17145)
		(layer "F.Cu")
		(net "SW_HDD_R8")
	)
	(segment
		(start 397.3195 -247.2055)
		(end 398.907 -247.2055)
		(width 0.17145)
		(layer "F.Cu")
		(net "SW_HDD_R8")
	)
	(segment
		(start 400.7485 -250.444)
		(end 399.542 -250.444)
		(width 0.17145)
		(layer "F.Cu")
		(net "SW_HDD_R8")
	)
	(via
		(at 399.542 -250.444)
		(size 0.6604)
		(drill 0.3302)
		(layers "F.Cu" "B.Cu")
		(net "SW_HDD_R8")
	)
	(segment
		(start 365.6965 -247.2055)
		(end 367.284 -247.2055)
		(width 0.17145)
		(layer "F.Cu")
		(net "SW_HDD_R7")
	)
	(segment
		(start 368.427 -248.031)
		(end 367.665 -248.793)
		(width 0.17145)
		(layer "F.Cu")
		(net "SW_HDD_R7")
	)
	(segment
		(start 369.1255 -250.444)
		(end 367.919 -250.444)
		(width 0.17145)
		(layer "F.Cu")
		(net "SW_HDD_R7")
	)
	(segment
		(start 367.284 -247.2055)
		(end 368.427 -247.2055)
		(width 0.17145)
		(layer "F.Cu")
		(net "SW_HDD_R7")
	)
	(segment
		(start 364.5408 -246.90324)
		(end 365.39424 -246.90324)
		(width 0.17145)
		(layer "F.Cu")
		(net "SW_HDD_R7")
	)
	(segment
		(start 367.665 -248.793)
		(end 367.665 -250.19)
		(width 0.17145)
		(layer "F.Cu")
		(net "SW_HDD_R7")
	)
	(segment
		(start 365.39424 -246.90324)
		(end 365.6965 -247.2055)
		(width 0.17145)
		(layer "F.Cu")
		(net "SW_HDD_R7")
	)
	(segment
		(start 368.427 -247.2055)
		(end 368.427 -248.031)
		(width 0.17145)
		(layer "F.Cu")
		(net "SW_HDD_R7")
	)
	(segment
		(start 367.665 -250.19)
		(end 367.919 -250.444)
		(width 0.17145)
		(layer "F.Cu")
		(net "SW_HDD_R7")
	)
	(via
		(at 367.919 -250.444)
		(size 0.6604)
		(drill 0.3302)
		(layers "F.Cu" "B.Cu")
		(net "SW_HDD_R7")
	)
	(segment
		(start 335.788 -247.2055)
		(end 336.931 -247.2055)
		(width 0.17145)
		(layer "F.Cu")
		(net "SW_HDD_R6")
	)
	(segment
		(start 334.2005 -247.2055)
		(end 335.788 -247.2055)
		(width 0.17145)
		(layer "F.Cu")
		(net "SW_HDD_R6")
	)
	(segment
		(start 337.6295 -250.444)
		(end 336.423 -250.444)
		(width 0.17145)
		(layer "F.Cu")
		(net "SW_HDD_R6")
	)
	(segment
		(start 336.931 -247.2055)
		(end 336.931 -248.031)
		(width 0.17145)
		(layer "F.Cu")
		(net "SW_HDD_R6")
	)
	(segment
		(start 336.169 -250.19)
		(end 336.423 -250.444)
		(width 0.17145)
		(layer "F.Cu")
		(net "SW_HDD_R6")
	)
	(segment
		(start 333.89824 -246.90324)
		(end 334.2005 -247.2055)
		(width 0.17145)
		(layer "F.Cu")
		(net "SW_HDD_R6")
	)
	(segment
		(start 336.169 -248.793)
		(end 336.169 -250.19)
		(width 0.17145)
		(layer "F.Cu")
		(net "SW_HDD_R6")
	)
	(segment
		(start 336.931 -248.031)
		(end 336.169 -248.793)
		(width 0.17145)
		(layer "F.Cu")
		(net "SW_HDD_R6")
	)
	(segment
		(start 333.0448 -246.90324)
		(end 333.89824 -246.90324)
		(width 0.17145)
		(layer "F.Cu")
		(net "SW_HDD_R6")
	)
	(via
		(at 336.423 -250.444)
		(size 0.6604)
		(drill 0.3302)
		(layers "F.Cu" "B.Cu")
		(net "SW_HDD_R6")
	)
	(segment
		(start 178.83124 -246.80164)
		(end 177.9778 -245.9482)
		(width 0.17145)
		(layer "F.Cu")
		(net "SW_HDD_R5")
	)
	(segment
		(start 172.974 -247.7135)
		(end 172.974 -246.6975)
		(width 0.17145)
		(layer "F.Cu")
		(net "SW_HDD_R5")
	)
	(segment
		(start 174.625 -246.507)
		(end 173.1645 -246.507)
		(width 0.17145)
		(layer "F.Cu")
		(net "SW_HDD_R5")
	)
	(segment
		(start 176.149 -246.1895)
		(end 176.3903 -245.9482)
		(width 0.17145)
		(layer "F.Cu")
		(net "SW_HDD_R5")
	)
	(segment
		(start 175.26 -246.507)
		(end 174.625 -246.507)
		(width 0.17145)
		(layer "F.Cu")
		(net "SW_HDD_R5")
	)
	(segment
		(start 177.9778 -245.9482)
		(end 177.292 -245.9482)
		(width 0.17145)
		(layer "F.Cu")
		(net "SW_HDD_R5")
	)
	(segment
		(start 172.974 -246.6975)
		(end 173.0375 -246.634)
		(width 0.17145)
		(layer "F.Cu")
		(net "SW_HDD_R5")
	)
	(segment
		(start 173.1645 -246.507)
		(end 173.0375 -246.634)
		(width 0.17145)
		(layer "F.Cu")
		(net "SW_HDD_R5")
	)
	(segment
		(start 176.3903 -245.9482)
		(end 177.292 -245.9482)
		(width 0.17145)
		(layer "F.Cu")
		(net "SW_HDD_R5")
	)
	(segment
		(start 178.83124 -248.6152)
		(end 178.83124 -246.80164)
		(width 0.17145)
		(layer "F.Cu")
		(net "SW_HDD_R5")
	)
	(segment
		(start 175.5775 -246.1895)
		(end 175.26 -246.507)
		(width 0.17145)
		(layer "F.Cu")
		(net "SW_HDD_R5")
	)
	(segment
		(start 176.149 -246.1895)
		(end 175.5775 -246.1895)
		(width 0.17145)
		(layer "F.Cu")
		(net "SW_HDD_R5")
	)
	(via
		(at 177.292 -245.9482)
		(size 0.6604)
		(drill 0.3302)
		(layers "F.Cu" "B.Cu")
		(net "SW_HDD_R5")
	)
	(segment
		(start 144.8943 -245.9482)
		(end 145.8468 -245.9482)
		(width 0.17145)
		(layer "F.Cu")
		(net "SW_HDD_R4")
	)
	(segment
		(start 147.33524 -246.95404)
		(end 146.3294 -245.9482)
		(width 0.17145)
		(layer "F.Cu")
		(net "SW_HDD_R4")
	)
	(segment
		(start 141.500352 -246.675148)
		(end 141.5415 -246.634)
		(width 0.17145)
		(layer "F.Cu")
		(net "SW_HDD_R4")
	)
	(segment
		(start 146.3294 -245.9482)
		(end 145.8468 -245.9482)
		(width 0.17145)
		(layer "F.Cu")
		(net "SW_HDD_R4")
	)
	(segment
		(start 141.478 -247.7135)
		(end 141.478 -247.375934)
		(width 0.17145)
		(layer "F.Cu")
		(net "SW_HDD_R4")
	)
	(segment
		(start 147.33524 -248.6152)
		(end 147.33524 -246.95404)
		(width 0.17145)
		(layer "F.Cu")
		(net "SW_HDD_R4")
	)
	(segment
		(start 144.653 -246.1895)
		(end 144.8943 -245.9482)
		(width 0.17145)
		(layer "F.Cu")
		(net "SW_HDD_R4")
	)
	(segment
		(start 141.6685 -246.507)
		(end 141.5415 -246.634)
		(width 0.17145)
		(layer "F.Cu")
		(net "SW_HDD_R4")
	)
	(segment
		(start 141.500352 -247.353582)
		(end 141.500352 -246.675148)
		(width 0.17145)
		(layer "F.Cu")
		(net "SW_HDD_R4")
	)
	(segment
		(start 141.478 -247.375934)
		(end 141.500352 -247.353582)
		(width 0.17145)
		(layer "F.Cu")
		(net "SW_HDD_R4")
	)
	(segment
		(start 144.0815 -246.1895)
		(end 143.764 -246.507)
		(width 0.17145)
		(layer "F.Cu")
		(net "SW_HDD_R4")
	)
	(segment
		(start 143.129 -246.507)
		(end 141.6685 -246.507)
		(width 0.17145)
		(layer "F.Cu")
		(net "SW_HDD_R4")
	)
	(segment
		(start 144.653 -246.1895)
		(end 144.0815 -246.1895)
		(width 0.17145)
		(layer "F.Cu")
		(net "SW_HDD_R4")
	)
	(segment
		(start 143.764 -246.507)
		(end 143.129 -246.507)
		(width 0.17145)
		(layer "F.Cu")
		(net "SW_HDD_R4")
	)
	(via
		(at 145.8468 -245.9482)
		(size 0.6604)
		(drill 0.3302)
		(layers "F.Cu" "B.Cu")
		(net "SW_HDD_R4")
	)
	(segment
		(start 473.0877 -5.6642)
		(end 474.6752 -5.6642)
		(width 0.17145)
		(layer "F.Cu")
		(net "SW_HDD_R35")
	)
	(segment
		(start 479.05924 -7.4422)
		(end 479.05924 -5.79374)
		(width 0.17145)
		(layer "F.Cu")
		(net "SW_HDD_R35")
	)
	(segment
		(start 479.05924 -5.79374)
		(end 478.0915 -4.826)
		(width 0.17145)
		(layer "F.Cu")
		(net "SW_HDD_R35")
	)
	(segment
		(start 473.0242 -6.7437)
		(end 473.0877 -6.6802)
		(width 0.17145)
		(layer "F.Cu")
		(net "SW_HDD_R35")
	)
	(segment
		(start 476.0849 -5.6642)
		(end 476.2246 -5.5245)
		(width 0.17145)
		(layer "F.Cu")
		(net "SW_HDD_R35")
	)
	(segment
		(start 477.1898 -4.826)
		(end 476.9231 -4.826)
		(width 0.17145)
		(layer "F.Cu")
		(net "SW_HDD_R35")
	)
	(segment
		(start 473.0877 -6.6802)
		(end 473.0877 -5.6642)
		(width 0.17145)
		(layer "F.Cu")
		(net "SW_HDD_R35")
	)
	(segment
		(start 476.9231 -4.826)
		(end 476.2246 -5.5245)
		(width 0.17145)
		(layer "F.Cu")
		(net "SW_HDD_R35")
	)
	(segment
		(start 478.0915 -4.826)
		(end 477.1898 -4.826)
		(width 0.17145)
		(layer "F.Cu")
		(net "SW_HDD_R35")
	)
	(segment
		(start 474.6752 -5.6642)
		(end 476.0849 -5.6642)
		(width 0.17145)
		(layer "F.Cu")
		(net "SW_HDD_R35")
	)
	(via
		(at 477.1898 -4.826)
		(size 0.6604)
		(drill 0.3302)
		(layers "F.Cu" "B.Cu")
		(net "SW_HDD_R35")
	)
	(segment
		(start 462.007712 -21.599906)
		(end 462.007712 -22.548088)
		(width 0.17145)
		(layer "F.Cu")
		(net "SW_HDD_R34")
	)
	(segment
		(start 462.007712 -20.558506)
		(end 462.007712 -21.599906)
		(width 0.17145)
		(layer "F.Cu")
		(net "SW_HDD_R34")
	)
	(segment
		(start 462.007712 -22.548088)
		(end 462.0006 -22.5552)
		(width 0.17145)
		(layer "F.Cu")
		(net "SW_HDD_R34")
	)
	(segment
		(start 462.0006 -24.7777)
		(end 462.8261 -25.6032)
		(width 0.17145)
		(layer "F.Cu")
		(net "SW_HDD_R34")
	)
	(segment
		(start 461.264 -19.11604)
		(end 461.264 -19.814794)
		(width 0.17145)
		(layer "F.Cu")
		(net "SW_HDD_R34")
	)
	(segment
		(start 462.0006 -23.9776)
		(end 462.0006 -24.7777)
		(width 0.17145)
		(layer "F.Cu")
		(net "SW_HDD_R34")
	)
	(segment
		(start 461.264 -19.814794)
		(end 462.007712 -20.558506)
		(width 0.17145)
		(layer "F.Cu")
		(net "SW_HDD_R34")
	)
	(segment
		(start 462.0006 -22.5552)
		(end 462.0006 -23.9776)
		(width 0.17145)
		(layer "F.Cu")
		(net "SW_HDD_R34")
	)
	(via
		(at 462.0006 -22.5552)
		(size 0.6604)
		(drill 0.3302)
		(layers "F.Cu" "B.Cu")
		(net "SW_HDD_R34")
	)
	(segment
		(start 428.8155 -17.2085)
		(end 430.403 -17.2085)
		(width 0.17145)
		(layer "F.Cu")
		(net "SW_HDD_R33")
	)
	(segment
		(start 428.51324 -16.90624)
		(end 428.8155 -17.2085)
		(width 0.17145)
		(layer "F.Cu")
		(net "SW_HDD_R33")
	)
	(segment
		(start 431.546 -18.034)
		(end 430.784 -18.796)
		(width 0.17145)
		(layer "F.Cu")
		(net "SW_HDD_R33")
	)
	(segment
		(start 427.6598 -16.90624)
		(end 428.51324 -16.90624)
		(width 0.17145)
		(layer "F.Cu")
		(net "SW_HDD_R33")
	)
	(segment
		(start 430.784 -18.796)
		(end 430.784 -20.193)
		(width 0.17145)
		(layer "F.Cu")
		(net "SW_HDD_R33")
	)
	(segment
		(start 432.2445 -20.447)
		(end 431.038 -20.447)
		(width 0.17145)
		(layer "F.Cu")
		(net "SW_HDD_R33")
	)
	(segment
		(start 431.546 -17.2085)
		(end 431.546 -18.034)
		(width 0.17145)
		(layer "F.Cu")
		(net "SW_HDD_R33")
	)
	(segment
		(start 430.784 -20.193)
		(end 431.038 -20.447)
		(width 0.17145)
		(layer "F.Cu")
		(net "SW_HDD_R33")
	)
	(segment
		(start 430.403 -17.2085)
		(end 431.546 -17.2085)
		(width 0.17145)
		(layer "F.Cu")
		(net "SW_HDD_R33")
	)
	(via
		(at 431.038 -20.447)
		(size 0.6604)
		(drill 0.3302)
		(layers "F.Cu" "B.Cu")
		(net "SW_HDD_R33")
	)
	(segment
		(start 397.383 -15.24)
		(end 397.129 -15.494)
		(width 0.17145)
		(layer "F.Cu")
		(net "SW_HDD_R32")
	)
	(segment
		(start 399.288 -14.478)
		(end 398.78 -14.986)
		(width 0.17145)
		(layer "F.Cu")
		(net "SW_HDD_R32")
	)
	(segment
		(start 399.288 -13.7795)
		(end 399.288 -14.478)
		(width 0.17145)
		(layer "F.Cu")
		(net "SW_HDD_R32")
	)
	(segment
		(start 398.145 -13.7795)
		(end 399.288 -13.7795)
		(width 0.17145)
		(layer "F.Cu")
		(net "SW_HDD_R32")
	)
	(segment
		(start 396.5575 -13.7795)
		(end 398.145 -13.7795)
		(width 0.17145)
		(layer "F.Cu")
		(net "SW_HDD_R32")
	)
	(segment
		(start 395.4018 -13.47724)
		(end 396.25524 -13.47724)
		(width 0.17145)
		(layer "F.Cu")
		(net "SW_HDD_R32")
	)
	(segment
		(start 398.78 -15.24)
		(end 397.383 -15.24)
		(width 0.17145)
		(layer "F.Cu")
		(net "SW_HDD_R32")
	)
	(segment
		(start 397.129 -16.7005)
		(end 397.129 -15.494)
		(width 0.17145)
		(layer "F.Cu")
		(net "SW_HDD_R32")
	)
	(segment
		(start 396.25524 -13.47724)
		(end 396.5575 -13.7795)
		(width 0.17145)
		(layer "F.Cu")
		(net "SW_HDD_R32")
	)
	(segment
		(start 398.78 -14.986)
		(end 398.78 -15.24)
		(width 0.17145)
		(layer "F.Cu")
		(net "SW_HDD_R32")
	)
	(via
		(at 397.129 -15.494)
		(size 0.6604)
		(drill 0.3302)
		(layers "F.Cu" "B.Cu")
		(net "SW_HDD_R32")
	)
	(segment
		(start 364.88624 -16.90624)
		(end 365.3028 -17.3228)
		(width 0.17145)
		(layer "F.Cu")
		(net "SW_HDD_R31")
	)
	(segment
		(start 368.427 -17.2085)
		(end 368.427 -18.034)
		(width 0.17145)
		(layer "F.Cu")
		(net "SW_HDD_R31")
	)
	(segment
		(start 366.5982 -17.3228)
		(end 366.0648 -17.3228)
		(width 0.17145)
		(layer "F.Cu")
		(net "SW_HDD_R31")
	)
	(segment
		(start 367.665 -19.5072)
		(end 368.6048 -20.447)
		(width 0.17145)
		(layer "F.Cu")
		(net "SW_HDD_R31")
	)
	(segment
		(start 367.665 -18.796)
		(end 367.665 -19.5072)
		(width 0.17145)
		(layer "F.Cu")
		(net "SW_HDD_R31")
	)
	(segment
		(start 368.427 -17.2085)
		(end 367.284 -17.2085)
		(width 0.17145)
		(layer "F.Cu")
		(net "SW_HDD_R31")
	)
	(segment
		(start 364.5408 -16.90624)
		(end 364.88624 -16.90624)
		(width 0.17145)
		(layer "F.Cu")
		(net "SW_HDD_R31")
	)
	(segment
		(start 366.7125 -17.2085)
		(end 366.5982 -17.3228)
		(width 0.17145)
		(layer "F.Cu")
		(net "SW_HDD_R31")
	)
	(segment
		(start 367.284 -17.2085)
		(end 366.7125 -17.2085)
		(width 0.17145)
		(layer "F.Cu")
		(net "SW_HDD_R31")
	)
	(segment
		(start 368.427 -18.034)
		(end 367.665 -18.796)
		(width 0.17145)
		(layer "F.Cu")
		(net "SW_HDD_R31")
	)
	(segment
		(start 365.3028 -17.3228)
		(end 366.0648 -17.3228)
		(width 0.17145)
		(layer "F.Cu")
		(net "SW_HDD_R31")
	)
	(segment
		(start 368.6048 -20.447)
		(end 369.1255 -20.447)
		(width 0.17145)
		(layer "F.Cu")
		(net "SW_HDD_R31")
	)
	(via
		(at 366.0648 -17.3228)
		(size 0.6604)
		(drill 0.3302)
		(layers "F.Cu" "B.Cu")
		(net "SW_HDD_R31")
	)
	(segment
		(start 333.9465 -16.6751)
		(end 334.7466 -15.875)
		(width 0.17145)
		(layer "F.Cu")
		(net "SW_HDD_R30")
	)
	(segment
		(start 333.0194 -14.8082)
		(end 333.2734 -14.8082)
		(width 0.17145)
		(layer "F.Cu")
		(net "SW_HDD_R30")
	)
	(segment
		(start 333.6798 -13.7287)
		(end 334.7212 -13.7287)
		(width 0.17145)
		(layer "F.Cu")
		(net "SW_HDD_R30")
	)
	(segment
		(start 334.7466 -13.7541)
		(end 334.7212 -13.7287)
		(width 0.17145)
		(layer "F.Cu")
		(net "SW_HDD_R30")
	)
	(segment
		(start 333.6798 -13.7287)
		(end 333.6798 -14.4018)
		(width 0.17145)
		(layer "F.Cu")
		(net "SW_HDD_R30")
	)
	(segment
		(start 332.0288 -13.8176)
		(end 333.0194 -14.8082)
		(width 0.17145)
		(layer "F.Cu")
		(net "SW_HDD_R30")
	)
	(segment
		(start 333.1718 -16.6751)
		(end 333.9465 -16.6751)
		(width 0.17145)
		(layer "F.Cu")
		(net "SW_HDD_R30")
	)
	(segment
		(start 334.7466 -15.875)
		(end 334.7466 -15.2146)
		(width 0.17145)
		(layer "F.Cu")
		(net "SW_HDD_R30")
	)
	(segment
		(start 334.7466 -15.2146)
		(end 334.7466 -13.7541)
		(width 0.17145)
		(layer "F.Cu")
		(net "SW_HDD_R30")
	)
	(segment
		(start 332.0288 -13.47724)
		(end 332.0288 -13.8176)
		(width 0.17145)
		(layer "F.Cu")
		(net "SW_HDD_R30")
	)
	(segment
		(start 333.6798 -14.4018)
		(end 333.2734 -14.8082)
		(width 0.17145)
		(layer "F.Cu")
		(net "SW_HDD_R30")
	)
	(via
		(at 333.2734 -14.8082)
		(size 0.6604)
		(drill 0.3302)
		(layers "F.Cu" "B.Cu")
		(net "SW_HDD_R30")
	)
	(segment
		(start 113.03 -246.1895)
		(end 112.4585 -246.1895)
		(width 0.17145)
		(layer "F.Cu")
		(net "SW_HDD_R3")
	)
	(segment
		(start 109.855 -247.7135)
		(end 109.855 -246.6975)
		(width 0.17145)
		(layer "F.Cu")
		(net "SW_HDD_R3")
	)
	(segment
		(start 109.855 -246.6975)
		(end 109.9185 -246.634)
		(width 0.17145)
		(layer "F.Cu")
		(net "SW_HDD_R3")
	)
	(segment
		(start 115.71224 -246.9896)
		(end 114.72164 -245.999)
		(width 0.17145)
		(layer "F.Cu")
		(net "SW_HDD_R3")
	)
	(segment
		(start 113.2205 -245.999)
		(end 114.2238 -245.999)
		(width 0.17145)
		(layer "F.Cu")
		(net "SW_HDD_R3")
	)
	(segment
		(start 110.0455 -246.507)
		(end 109.9185 -246.634)
		(width 0.17145)
		(layer "F.Cu")
		(net "SW_HDD_R3")
	)
	(segment
		(start 115.71224 -248.6152)
		(end 115.71224 -246.9896)
		(width 0.17145)
		(layer "F.Cu")
		(net "SW_HDD_R3")
	)
	(segment
		(start 113.03 -246.1895)
		(end 113.2205 -245.999)
		(width 0.17145)
		(layer "F.Cu")
		(net "SW_HDD_R3")
	)
	(segment
		(start 111.506 -246.507)
		(end 110.0455 -246.507)
		(width 0.17145)
		(layer "F.Cu")
		(net "SW_HDD_R3")
	)
	(segment
		(start 114.72164 -245.999)
		(end 114.2238 -245.999)
		(width 0.17145)
		(layer "F.Cu")
		(net "SW_HDD_R3")
	)
	(segment
		(start 112.141 -246.507)
		(end 111.506 -246.507)
		(width 0.17145)
		(layer "F.Cu")
		(net "SW_HDD_R3")
	)
	(segment
		(start 112.4585 -246.1895)
		(end 112.141 -246.507)
		(width 0.17145)
		(layer "F.Cu")
		(net "SW_HDD_R3")
	)
	(via
		(at 114.2238 -245.999)
		(size 0.6604)
		(drill 0.3302)
		(layers "F.Cu" "B.Cu")
		(net "SW_HDD_R3")
	)
	(segment
		(start 181.483 -11.6205)
		(end 181.356 -11.4935)
		(width 0.17145)
		(layer "F.Cu")
		(net "SW_HDD_R29")
	)
	(segment
		(start 179.657248 -11.303)
		(end 180.34 -11.303)
		(width 0.17145)
		(layer "F.Cu")
		(net "SW_HDD_R29")
	)
	(segment
		(start 181.8005 -14.5796)
		(end 181.8005 -14.0335)
		(width 0.17145)
		(layer "F.Cu")
		(net "SW_HDD_R29")
	)
	(segment
		(start 180.57876 -17.28724)
		(end 181.8005 -16.0655)
		(width 0.17145)
		(layer "F.Cu")
		(net "SW_HDD_R29")
	)
	(segment
		(start 181.356 -11.4935)
		(end 181.1655 -11.303)
		(width 0.17145)
		(layer "F.Cu")
		(net "SW_HDD_R29")
	)
	(segment
		(start 181.483 -13.716)
		(end 181.483 -13.0302)
		(width 0.17145)
		(layer "F.Cu")
		(net "SW_HDD_R29")
	)
	(segment
		(start 181.483 -13.0302)
		(end 181.483 -11.6205)
		(width 0.17145)
		(layer "F.Cu")
		(net "SW_HDD_R29")
	)
	(segment
		(start 181.1655 -11.303)
		(end 180.34 -11.303)
		(width 0.17145)
		(layer "F.Cu")
		(net "SW_HDD_R29")
	)
	(segment
		(start 179.517548 -11.4427)
		(end 179.657248 -11.303)
		(width 0.17145)
		(layer "F.Cu")
		(net "SW_HDD_R29")
	)
	(segment
		(start 179.0065 -11.4427)
		(end 179.517548 -11.4427)
		(width 0.17145)
		(layer "F.Cu")
		(net "SW_HDD_R29")
	)
	(segment
		(start 181.8005 -14.0335)
		(end 181.483 -13.716)
		(width 0.17145)
		(layer "F.Cu")
		(net "SW_HDD_R29")
	)
	(segment
		(start 179.7558 -17.28724)
		(end 180.57876 -17.28724)
		(width 0.17145)
		(layer "F.Cu")
		(net "SW_HDD_R29")
	)
	(segment
		(start 181.8005 -16.0655)
		(end 181.8005 -14.5796)
		(width 0.17145)
		(layer "F.Cu")
		(net "SW_HDD_R29")
	)
	(via
		(at 180.34 -11.303)
		(size 0.6604)
		(drill 0.3302)
		(layers "F.Cu" "B.Cu")
		(net "SW_HDD_R29")
	)
	(segment
		(start 145.3642 -16.1925)
		(end 144.653 -16.1925)
		(width 0.17145)
		(layer "F.Cu")
		(net "SW_HDD_R28")
	)
	(segment
		(start 141.6685 -16.51)
		(end 141.5415 -16.637)
		(width 0.17145)
		(layer "F.Cu")
		(net "SW_HDD_R28")
	)
	(segment
		(start 146.431 -15.9766)
		(end 145.8722 -15.9766)
		(width 0.17145)
		(layer "F.Cu")
		(net "SW_HDD_R28")
	)
	(segment
		(start 147.33524 -18.6182)
		(end 147.33524 -16.88084)
		(width 0.17145)
		(layer "F.Cu")
		(net "SW_HDD_R28")
	)
	(segment
		(start 144.653 -16.1925)
		(end 144.0815 -16.1925)
		(width 0.17145)
		(layer "F.Cu")
		(net "SW_HDD_R28")
	)
	(segment
		(start 141.478 -16.7005)
		(end 141.5415 -16.637)
		(width 0.17145)
		(layer "F.Cu")
		(net "SW_HDD_R28")
	)
	(segment
		(start 143.764 -16.51)
		(end 143.129 -16.51)
		(width 0.17145)
		(layer "F.Cu")
		(net "SW_HDD_R28")
	)
	(segment
		(start 141.478 -17.7165)
		(end 141.478 -16.7005)
		(width 0.17145)
		(layer "F.Cu")
		(net "SW_HDD_R28")
	)
	(segment
		(start 147.33524 -16.88084)
		(end 146.431 -15.9766)
		(width 0.17145)
		(layer "F.Cu")
		(net "SW_HDD_R28")
	)
	(segment
		(start 144.0815 -16.1925)
		(end 143.764 -16.51)
		(width 0.17145)
		(layer "F.Cu")
		(net "SW_HDD_R28")
	)
	(segment
		(start 145.8722 -15.9766)
		(end 145.5801 -15.9766)
		(width 0.17145)
		(layer "F.Cu")
		(net "SW_HDD_R28")
	)
	(segment
		(start 143.129 -16.51)
		(end 141.6685 -16.51)
		(width 0.17145)
		(layer "F.Cu")
		(net "SW_HDD_R28")
	)
	(segment
		(start 145.5801 -15.9766)
		(end 145.3642 -16.1925)
		(width 0.17145)
		(layer "F.Cu")
		(net "SW_HDD_R28")
	)
	(via
		(at 145.8722 -15.9766)
		(size 0.6604)
		(drill 0.3302)
		(layers "F.Cu" "B.Cu")
		(net "SW_HDD_R28")
	)
	(segment
		(start 118.364 -13.716)
		(end 118.364 -13.081)
		(width 0.17145)
		(layer "F.Cu")
		(net "SW_HDD_R27")
	)
	(segment
		(start 117.43436 -17.28724)
		(end 118.6815 -16.0401)
		(width 0.17145)
		(layer "F.Cu")
		(net "SW_HDD_R27")
	)
	(segment
		(start 118.237 -11.4935)
		(end 118.0465 -11.303)
		(width 0.17145)
		(layer "F.Cu")
		(net "SW_HDD_R27")
	)
	(segment
		(start 116.715794 -11.303)
		(end 115.6843 -11.303)
		(width 0.17145)
		(layer "F.Cu")
		(net "SW_HDD_R27")
	)
	(segment
		(start 118.364 -13.081)
		(end 118.364 -11.6205)
		(width 0.17145)
		(layer "F.Cu")
		(net "SW_HDD_R27")
	)
	(segment
		(start 118.0465 -11.303)
		(end 116.715794 -11.303)
		(width 0.17145)
		(layer "F.Cu")
		(net "SW_HDD_R27")
	)
	(segment
		(start 118.6815 -14.605)
		(end 118.6815 -14.0335)
		(width 0.17145)
		(layer "F.Cu")
		(net "SW_HDD_R27")
	)
	(segment
		(start 118.6815 -14.0335)
		(end 118.364 -13.716)
		(width 0.17145)
		(layer "F.Cu")
		(net "SW_HDD_R27")
	)
	(segment
		(start 116.2558 -17.28724)
		(end 117.43436 -17.28724)
		(width 0.17145)
		(layer "F.Cu")
		(net "SW_HDD_R27")
	)
	(segment
		(start 118.364 -11.6205)
		(end 118.237 -11.4935)
		(width 0.17145)
		(layer "F.Cu")
		(net "SW_HDD_R27")
	)
	(segment
		(start 118.6815 -16.0401)
		(end 118.6815 -14.605)
		(width 0.17145)
		(layer "F.Cu")
		(net "SW_HDD_R27")
	)
	(via
		(at 116.715794 -11.303)
		(size 0.6604)
		(drill 0.3302)
		(layers "F.Cu" "B.Cu")
		(net "SW_HDD_R27")
	)
	(segment
		(start 78.359 -17.7165)
		(end 78.359 -16.7005)
		(width 0.17145)
		(layer "F.Cu")
		(net "SW_HDD_R26")
	)
	(segment
		(start 84.21624 -18.6182)
		(end 84.21624 -17.7038)
		(width 0.17145)
		(layer "F.Cu")
		(net "SW_HDD_R26")
	)
	(segment
		(start 80.01 -16.51)
		(end 78.5495 -16.51)
		(width 0.17145)
		(layer "F.Cu")
		(net "SW_HDD_R26")
	)
	(segment
		(start 80.645 -16.51)
		(end 80.01 -16.51)
		(width 0.17145)
		(layer "F.Cu")
		(net "SW_HDD_R26")
	)
	(segment
		(start 84.21624 -17.7038)
		(end 83.7438 -17.23136)
		(width 0.17145)
		(layer "F.Cu")
		(net "SW_HDD_R26")
	)
	(segment
		(start 83.7438 -16.3068)
		(end 83.4136 -15.9766)
		(width 0.17145)
		(layer "F.Cu")
		(net "SW_HDD_R26")
	)
	(segment
		(start 81.534 -16.1925)
		(end 80.9625 -16.1925)
		(width 0.17145)
		(layer "F.Cu")
		(net "SW_HDD_R26")
	)
	(segment
		(start 82.7786 -15.9766)
		(end 81.7499 -15.9766)
		(width 0.17145)
		(layer "F.Cu")
		(net "SW_HDD_R26")
	)
	(segment
		(start 83.7438 -17.23136)
		(end 83.7438 -16.3068)
		(width 0.17145)
		(layer "F.Cu")
		(net "SW_HDD_R26")
	)
	(segment
		(start 78.5495 -16.51)
		(end 78.4225 -16.637)
		(width 0.17145)
		(layer "F.Cu")
		(net "SW_HDD_R26")
	)
	(segment
		(start 78.359 -16.7005)
		(end 78.4225 -16.637)
		(width 0.17145)
		(layer "F.Cu")
		(net "SW_HDD_R26")
	)
	(segment
		(start 81.7499 -15.9766)
		(end 81.534 -16.1925)
		(width 0.17145)
		(layer "F.Cu")
		(net "SW_HDD_R26")
	)
	(segment
		(start 83.4136 -15.9766)
		(end 82.7786 -15.9766)
		(width 0.17145)
		(layer "F.Cu")
		(net "SW_HDD_R26")
	)
	(segment
		(start 80.9625 -16.1925)
		(end 80.645 -16.51)
		(width 0.17145)
		(layer "F.Cu")
		(net "SW_HDD_R26")
	)
	(via
		(at 82.7786 -15.9766)
		(size 0.6604)
		(drill 0.3302)
		(layers "F.Cu" "B.Cu")
		(net "SW_HDD_R26")
	)
	(segment
		(start 55.245 -13.716)
		(end 55.245 -13.0048)
		(width 0.17145)
		(layer "F.Cu")
		(net "SW_HDD_R25")
	)
	(segment
		(start 53.635148 -11.4554)
		(end 54.31663 -11.4554)
		(width 0.17145)
		(layer "F.Cu")
		(net "SW_HDD_R25")
	)
	(segment
		(start 53.5178 -17.28724)
		(end 54.5338 -17.28724)
		(width 0.17145)
		(layer "F.Cu")
		(net "SW_HDD_R25")
	)
	(segment
		(start 55.4609 -14.5796)
		(end 55.4609 -13.9319)
		(width 0.17145)
		(layer "F.Cu")
		(net "SW_HDD_R25")
	)
	(segment
		(start 54.35473 -11.4935)
		(end 55.118 -11.4935)
		(width 0.17145)
		(layer "F.Cu")
		(net "SW_HDD_R25")
	)
	(segment
		(start 55.245 -13.0048)
		(end 55.245 -12.327128)
		(width 0.17145)
		(layer "F.Cu")
		(net "SW_HDD_R25")
	)
	(segment
		(start 55.4609 -13.9319)
		(end 55.245 -13.716)
		(width 0.17145)
		(layer "F.Cu")
		(net "SW_HDD_R25")
	)
	(segment
		(start 52.6415 -11.4554)
		(end 53.635148 -11.4554)
		(width 0.17145)
		(layer "F.Cu")
		(net "SW_HDD_R25")
	)
	(segment
		(start 54.5338 -17.28724)
		(end 55.4609 -16.36014)
		(width 0.17145)
		(layer "F.Cu")
		(net "SW_HDD_R25")
	)
	(segment
		(start 55.118 -12.200128)
		(end 55.118 -11.4935)
		(width 0.17145)
		(layer "F.Cu")
		(net "SW_HDD_R25")
	)
	(segment
		(start 55.4609 -16.36014)
		(end 55.4609 -14.5796)
		(width 0.17145)
		(layer "F.Cu")
		(net "SW_HDD_R25")
	)
	(segment
		(start 54.31663 -11.4554)
		(end 54.35473 -11.4935)
		(width 0.17145)
		(layer "F.Cu")
		(net "SW_HDD_R25")
	)
	(segment
		(start 55.245 -12.327128)
		(end 55.118 -12.200128)
		(width 0.17145)
		(layer "F.Cu")
		(net "SW_HDD_R25")
	)
	(via
		(at 53.635148 -11.4554)
		(size 0.6604)
		(drill 0.3302)
		(layers "F.Cu" "B.Cu")
		(net "SW_HDD_R25")
	)
	(segment
		(start 21.09724 -18.6182)
		(end 21.09724 -16.80464)
		(width 0.17145)
		(layer "F.Cu")
		(net "SW_HDD_R24")
	)
	(segment
		(start 15.4305 -16.51)
		(end 15.3035 -16.637)
		(width 0.17145)
		(layer "F.Cu")
		(net "SW_HDD_R24")
	)
	(segment
		(start 17.526 -16.51)
		(end 16.891 -16.51)
		(width 0.17145)
		(layer "F.Cu")
		(net "SW_HDD_R24")
	)
	(segment
		(start 18.6563 -15.9512)
		(end 18.415 -16.1925)
		(width 0.17145)
		(layer "F.Cu")
		(net "SW_HDD_R24")
	)
	(segment
		(start 17.8435 -16.1925)
		(end 17.526 -16.51)
		(width 0.17145)
		(layer "F.Cu")
		(net "SW_HDD_R24")
	)
	(segment
		(start 21.09724 -16.80464)
		(end 20.2438 -15.9512)
		(width 0.17145)
		(layer "F.Cu")
		(net "SW_HDD_R24")
	)
	(segment
		(start 16.891 -16.51)
		(end 15.4305 -16.51)
		(width 0.17145)
		(layer "F.Cu")
		(net "SW_HDD_R24")
	)
	(segment
		(start 20.2438 -15.9512)
		(end 19.5834 -15.9512)
		(width 0.17145)
		(layer "F.Cu")
		(net "SW_HDD_R24")
	)
	(segment
		(start 15.24 -17.7165)
		(end 15.3035 -17.653)
		(width 0.17145)
		(layer "F.Cu")
		(net "SW_HDD_R24")
	)
	(segment
		(start 15.3035 -17.653)
		(end 15.3035 -16.637)
		(width 0.17145)
		(layer "F.Cu")
		(net "SW_HDD_R24")
	)
	(segment
		(start 18.415 -16.1925)
		(end 17.8435 -16.1925)
		(width 0.17145)
		(layer "F.Cu")
		(net "SW_HDD_R24")
	)
	(segment
		(start 19.5834 -15.9512)
		(end 18.6563 -15.9512)
		(width 0.17145)
		(layer "F.Cu")
		(net "SW_HDD_R24")
	)
	(via
		(at 19.5834 -15.9512)
		(size 0.6604)
		(drill 0.3302)
		(layers "F.Cu" "B.Cu")
		(net "SW_HDD_R24")
	)
	(segment
		(start 468.1855 -136.525)
		(end 468.1855 -135.509)
		(width 0.17145)
		(layer "F.Cu")
		(net "SW_HDD_R23")
	)
	(segment
		(start 469.8365 -133.858)
		(end 469.8365 -135.3185)
		(width 0.17145)
		(layer "F.Cu")
		(net "SW_HDD_R23")
	)
	(segment
		(start 469.8365 -135.3185)
		(end 469.773 -135.382)
		(width 0.17145)
		(layer "F.Cu")
		(net "SW_HDD_R23")
	)
	(segment
		(start 472.2622 -131.17576)
		(end 470.23274 -131.17576)
		(width 0.17145)
		(layer "F.Cu")
		(net "SW_HDD_R23")
	)
	(segment
		(start 469.773 -135.382)
		(end 468.3125 -135.382)
		(width 0.17145)
		(layer "F.Cu")
		(net "SW_HDD_R23")
	)
	(segment
		(start 469.8365 -133.858)
		(end 469.8365 -131.572)
		(width 0.17145)
		(layer "F.Cu")
		(net "SW_HDD_R23")
	)
	(segment
		(start 468.122 -136.5885)
		(end 468.1855 -136.525)
		(width 0.17145)
		(layer "F.Cu")
		(net "SW_HDD_R23")
	)
	(segment
		(start 468.3125 -135.382)
		(end 468.1855 -135.509)
		(width 0.17145)
		(layer "F.Cu")
		(net "SW_HDD_R23")
	)
	(segment
		(start 470.23274 -131.17576)
		(end 469.8365 -131.572)
		(width 0.17145)
		(layer "F.Cu")
		(net "SW_HDD_R23")
	)
	(via
		(at 469.8365 -131.572)
		(size 0.6604)
		(drill 0.3302)
		(layers "F.Cu" "B.Cu")
		(net "SW_HDD_R23")
	)
	(segment
		(start 463.042 -133.096)
		(end 462.28 -133.858)
		(width 0.17145)
		(layer "F.Cu")
		(net "SW_HDD_R22")
	)
	(segment
		(start 462.28 -135.255)
		(end 462.534 -135.509)
		(width 0.17145)
		(layer "F.Cu")
		(net "SW_HDD_R22")
	)
	(segment
		(start 462.28 -133.858)
		(end 462.28 -135.255)
		(width 0.17145)
		(layer "F.Cu")
		(net "SW_HDD_R22")
	)
	(segment
		(start 460.00924 -131.96824)
		(end 460.3115 -132.2705)
		(width 0.17145)
		(layer "F.Cu")
		(net "SW_HDD_R22")
	)
	(segment
		(start 461.899 -132.2705)
		(end 463.042 -132.2705)
		(width 0.17145)
		(layer "F.Cu")
		(net "SW_HDD_R22")
	)
	(segment
		(start 459.1558 -131.96824)
		(end 460.00924 -131.96824)
		(width 0.17145)
		(layer "F.Cu")
		(net "SW_HDD_R22")
	)
	(segment
		(start 460.3115 -132.2705)
		(end 461.899 -132.2705)
		(width 0.17145)
		(layer "F.Cu")
		(net "SW_HDD_R22")
	)
	(segment
		(start 463.7405 -135.509)
		(end 462.534 -135.509)
		(width 0.17145)
		(layer "F.Cu")
		(net "SW_HDD_R22")
	)
	(segment
		(start 463.042 -132.2705)
		(end 463.042 -133.096)
		(width 0.17145)
		(layer "F.Cu")
		(net "SW_HDD_R22")
	)
	(via
		(at 462.534 -135.509)
		(size 0.6604)
		(drill 0.3302)
		(layers "F.Cu" "B.Cu")
		(net "SW_HDD_R22")
	)
	(segment
		(start 432.2445 -135.509)
		(end 431.038 -135.509)
		(width 0.17145)
		(layer "F.Cu")
		(net "SW_HDD_R21")
	)
	(segment
		(start 428.51324 -131.96824)
		(end 428.8155 -132.2705)
		(width 0.17145)
		(layer "F.Cu")
		(net "SW_HDD_R21")
	)
	(segment
		(start 431.546 -132.2705)
		(end 431.546 -133.096)
		(width 0.17145)
		(layer "F.Cu")
		(net "SW_HDD_R21")
	)
	(segment
		(start 430.784 -133.858)
		(end 430.784 -135.255)
		(width 0.17145)
		(layer "F.Cu")
		(net "SW_HDD_R21")
	)
	(segment
		(start 431.546 -133.096)
		(end 430.784 -133.858)
		(width 0.17145)
		(layer "F.Cu")
		(net "SW_HDD_R21")
	)
	(segment
		(start 430.784 -135.255)
		(end 431.038 -135.509)
		(width 0.17145)
		(layer "F.Cu")
		(net "SW_HDD_R21")
	)
	(segment
		(start 427.6598 -131.96824)
		(end 428.51324 -131.96824)
		(width 0.17145)
		(layer "F.Cu")
		(net "SW_HDD_R21")
	)
	(segment
		(start 428.8155 -132.2705)
		(end 430.403 -132.2705)
		(width 0.17145)
		(layer "F.Cu")
		(net "SW_HDD_R21")
	)
	(segment
		(start 430.403 -132.2705)
		(end 431.546 -132.2705)
		(width 0.17145)
		(layer "F.Cu")
		(net "SW_HDD_R21")
	)
	(via
		(at 431.038 -135.509)
		(size 0.6604)
		(drill 0.3302)
		(layers "F.Cu" "B.Cu")
		(net "SW_HDD_R21")
	)
	(segment
		(start 400.05 -132.2705)
		(end 400.05 -133.096)
		(width 0.17145)
		(layer "F.Cu")
		(net "SW_HDD_R20")
	)
	(segment
		(start 400.7485 -135.509)
		(end 399.542 -135.509)
		(width 0.17145)
		(layer "F.Cu")
		(net "SW_HDD_R20")
	)
	(segment
		(start 398.907 -132.2705)
		(end 400.05 -132.2705)
		(width 0.17145)
		(layer "F.Cu")
		(net "SW_HDD_R20")
	)
	(segment
		(start 397.01724 -131.96824)
		(end 397.3195 -132.2705)
		(width 0.17145)
		(layer "F.Cu")
		(net "SW_HDD_R20")
	)
	(segment
		(start 399.288 -133.858)
		(end 399.288 -135.255)
		(width 0.17145)
		(layer "F.Cu")
		(net "SW_HDD_R20")
	)
	(segment
		(start 400.05 -133.096)
		(end 399.288 -133.858)
		(width 0.17145)
		(layer "F.Cu")
		(net "SW_HDD_R20")
	)
	(segment
		(start 396.1638 -131.96824)
		(end 397.01724 -131.96824)
		(width 0.17145)
		(layer "F.Cu")
		(net "SW_HDD_R20")
	)
	(segment
		(start 397.3195 -132.2705)
		(end 398.907 -132.2705)
		(width 0.17145)
		(layer "F.Cu")
		(net "SW_HDD_R20")
	)
	(segment
		(start 399.288 -135.255)
		(end 399.542 -135.509)
		(width 0.17145)
		(layer "F.Cu")
		(net "SW_HDD_R20")
	)
	(via
		(at 399.542 -135.509)
		(size 0.6604)
		(drill 0.3302)
		(layers "F.Cu" "B.Cu")
		(net "SW_HDD_R20")
	)
	(segment
		(start 80.01 -246.507)
		(end 78.5495 -246.507)
		(width 0.17145)
		(layer "F.Cu")
		(net "SW_HDD_R2")
	)
	(segment
		(start 81.534 -246.1895)
		(end 81.7499 -245.9736)
		(width 0.17145)
		(layer "F.Cu")
		(net "SW_HDD_R2")
	)
	(segment
		(start 80.645 -246.507)
		(end 80.01 -246.507)
		(width 0.17145)
		(layer "F.Cu")
		(net "SW_HDD_R2")
	)
	(segment
		(start 78.5495 -246.507)
		(end 78.4225 -246.634)
		(width 0.17145)
		(layer "F.Cu")
		(net "SW_HDD_R2")
	)
	(segment
		(start 81.534 -246.1895)
		(end 80.9625 -246.1895)
		(width 0.17145)
		(layer "F.Cu")
		(net "SW_HDD_R2")
	)
	(segment
		(start 80.9625 -246.1895)
		(end 80.645 -246.507)
		(width 0.17145)
		(layer "F.Cu")
		(net "SW_HDD_R2")
	)
	(segment
		(start 78.359 -247.7135)
		(end 78.359 -246.6975)
		(width 0.17145)
		(layer "F.Cu")
		(net "SW_HDD_R2")
	)
	(segment
		(start 81.7499 -245.9736)
		(end 82.7024 -245.9736)
		(width 0.17145)
		(layer "F.Cu")
		(net "SW_HDD_R2")
	)
	(segment
		(start 83.09864 -245.9736)
		(end 82.7024 -245.9736)
		(width 0.17145)
		(layer "F.Cu")
		(net "SW_HDD_R2")
	)
	(segment
		(start 78.359 -246.6975)
		(end 78.4225 -246.634)
		(width 0.17145)
		(layer "F.Cu")
		(net "SW_HDD_R2")
	)
	(segment
		(start 84.21624 -247.0912)
		(end 83.09864 -245.9736)
		(width 0.17145)
		(layer "F.Cu")
		(net "SW_HDD_R2")
	)
	(segment
		(start 84.21624 -248.6152)
		(end 84.21624 -247.0912)
		(width 0.17145)
		(layer "F.Cu")
		(net "SW_HDD_R2")
	)
	(via
		(at 82.7024 -245.9736)
		(size 0.6604)
		(drill 0.3302)
		(layers "F.Cu" "B.Cu")
		(net "SW_HDD_R2")
	)
	(segment
		(start 368.427 -132.2705)
		(end 368.427 -133.096)
		(width 0.17145)
		(layer "F.Cu")
		(net "SW_HDD_R19")
	)
	(segment
		(start 364.5408 -131.96824)
		(end 365.39424 -131.96824)
		(width 0.17145)
		(layer "F.Cu")
		(net "SW_HDD_R19")
	)
	(segment
		(start 368.427 -133.096)
		(end 367.665 -133.858)
		(width 0.17145)
		(layer "F.Cu")
		(net "SW_HDD_R19")
	)
	(segment
		(start 367.284 -132.2705)
		(end 368.427 -132.2705)
		(width 0.17145)
		(layer "F.Cu")
		(net "SW_HDD_R19")
	)
	(segment
		(start 369.1255 -135.509)
		(end 367.919 -135.509)
		(width 0.17145)
		(layer "F.Cu")
		(net "SW_HDD_R19")
	)
	(segment
		(start 365.6965 -132.2705)
		(end 367.284 -132.2705)
		(width 0.17145)
		(layer "F.Cu")
		(net "SW_HDD_R19")
	)
	(segment
		(start 367.665 -133.858)
		(end 367.665 -135.255)
		(width 0.17145)
		(layer "F.Cu")
		(net "SW_HDD_R19")
	)
	(segment
		(start 367.665 -135.255)
		(end 367.919 -135.509)
		(width 0.17145)
		(layer "F.Cu")
		(net "SW_HDD_R19")
	)
	(segment
		(start 365.39424 -131.96824)
		(end 365.6965 -132.2705)
		(width 0.17145)
		(layer "F.Cu")
		(net "SW_HDD_R19")
	)
	(via
		(at 367.919 -135.509)
		(size 0.6604)
		(drill 0.3302)
		(layers "F.Cu" "B.Cu")
		(net "SW_HDD_R19")
	)
	(segment
		(start 336.169 -135.255)
		(end 336.423 -135.509)
		(width 0.17145)
		(layer "F.Cu")
		(net "SW_HDD_R18")
	)
	(segment
		(start 335.788 -132.2705)
		(end 336.931 -132.2705)
		(width 0.17145)
		(layer "F.Cu")
		(net "SW_HDD_R18")
	)
	(segment
		(start 336.169 -133.858)
		(end 336.169 -135.255)
		(width 0.17145)
		(layer "F.Cu")
		(net "SW_HDD_R18")
	)
	(segment
		(start 337.6295 -135.509)
		(end 336.423 -135.509)
		(width 0.17145)
		(layer "F.Cu")
		(net "SW_HDD_R18")
	)
	(segment
		(start 336.931 -133.096)
		(end 336.169 -133.858)
		(width 0.17145)
		(layer "F.Cu")
		(net "SW_HDD_R18")
	)
	(segment
		(start 333.89824 -131.96824)
		(end 334.2005 -132.2705)
		(width 0.17145)
		(layer "F.Cu")
		(net "SW_HDD_R18")
	)
	(segment
		(start 336.931 -132.2705)
		(end 336.931 -133.096)
		(width 0.17145)
		(layer "F.Cu")
		(net "SW_HDD_R18")
	)
	(segment
		(start 334.2005 -132.2705)
		(end 335.788 -132.2705)
		(width 0.17145)
		(layer "F.Cu")
		(net "SW_HDD_R18")
	)
	(segment
		(start 333.0448 -131.96824)
		(end 333.89824 -131.96824)
		(width 0.17145)
		(layer "F.Cu")
		(net "SW_HDD_R18")
	)
	(via
		(at 336.423 -135.509)
		(size 0.6604)
		(drill 0.3302)
		(layers "F.Cu" "B.Cu")
		(net "SW_HDD_R18")
	)
	(segment
		(start 176.149 -131.1275)
		(end 175.5775 -131.1275)
		(width 0.17145)
		(layer "F.Cu")
		(net "SW_HDD_R17")
	)
	(segment
		(start 178.83124 -131.79044)
		(end 177.8762 -130.8354)
		(width 0.17145)
		(layer "F.Cu")
		(net "SW_HDD_R17")
	)
	(segment
		(start 172.974 -132.6515)
		(end 172.974 -131.6355)
		(width 0.17145)
		(layer "F.Cu")
		(net "SW_HDD_R17")
	)
	(segment
		(start 176.4411 -130.8354)
		(end 176.149 -131.1275)
		(width 0.17145)
		(layer "F.Cu")
		(net "SW_HDD_R17")
	)
	(segment
		(start 177.8762 -130.8354)
		(end 177.3174 -130.8354)
		(width 0.17145)
		(layer "F.Cu")
		(net "SW_HDD_R17")
	)
	(segment
		(start 177.3174 -130.8354)
		(end 176.4411 -130.8354)
		(width 0.17145)
		(layer "F.Cu")
		(net "SW_HDD_R17")
	)
	(segment
		(start 173.1645 -131.445)
		(end 173.0375 -131.572)
		(width 0.17145)
		(layer "F.Cu")
		(net "SW_HDD_R17")
	)
	(segment
		(start 175.26 -131.445)
		(end 174.625 -131.445)
		(width 0.17145)
		(layer "F.Cu")
		(net "SW_HDD_R17")
	)
	(segment
		(start 174.625 -131.445)
		(end 173.1645 -131.445)
		(width 0.17145)
		(layer "F.Cu")
		(net "SW_HDD_R17")
	)
	(segment
		(start 178.83124 -133.5532)
		(end 178.83124 -131.79044)
		(width 0.17145)
		(layer "F.Cu")
		(net "SW_HDD_R17")
	)
	(segment
		(start 175.5775 -131.1275)
		(end 175.26 -131.445)
		(width 0.17145)
		(layer "F.Cu")
		(net "SW_HDD_R17")
	)
	(segment
		(start 172.974 -131.6355)
		(end 173.0375 -131.572)
		(width 0.17145)
		(layer "F.Cu")
		(net "SW_HDD_R17")
	)
	(via
		(at 177.3174 -130.8354)
		(size 0.6604)
		(drill 0.3302)
		(layers "F.Cu" "B.Cu")
		(net "SW_HDD_R17")
	)
	(segment
		(start 144.3355 -131.445)
		(end 143.129 -131.445)
		(width 0.17145)
		(layer "F.Cu")
		(net "SW_HDD_R16")
	)
	(segment
		(start 141.478 -132.6515)
		(end 141.478 -131.6355)
		(width 0.17145)
		(layer "F.Cu")
		(net "SW_HDD_R16")
	)
	(segment
		(start 145.8722 -130.937)
		(end 144.8435 -130.937)
		(width 0.17145)
		(layer "F.Cu")
		(net "SW_HDD_R16")
	)
	(segment
		(start 141.478 -131.6355)
		(end 141.5415 -131.572)
		(width 0.17145)
		(layer "F.Cu")
		(net "SW_HDD_R16")
	)
	(segment
		(start 143.129 -131.445)
		(end 141.6685 -131.445)
		(width 0.17145)
		(layer "F.Cu")
		(net "SW_HDD_R16")
	)
	(segment
		(start 144.8435 -130.937)
		(end 144.653 -131.1275)
		(width 0.17145)
		(layer "F.Cu")
		(net "SW_HDD_R16")
	)
	(segment
		(start 141.6685 -131.445)
		(end 141.5415 -131.572)
		(width 0.17145)
		(layer "F.Cu")
		(net "SW_HDD_R16")
	)
	(segment
		(start 147.33524 -131.81584)
		(end 146.4564 -130.937)
		(width 0.17145)
		(layer "F.Cu")
		(net "SW_HDD_R16")
	)
	(segment
		(start 146.4564 -130.937)
		(end 145.8722 -130.937)
		(width 0.17145)
		(layer "F.Cu")
		(net "SW_HDD_R16")
	)
	(segment
		(start 147.33524 -133.5532)
		(end 147.33524 -131.81584)
		(width 0.17145)
		(layer "F.Cu")
		(net "SW_HDD_R16")
	)
	(segment
		(start 144.653 -131.1275)
		(end 144.3355 -131.445)
		(width 0.17145)
		(layer "F.Cu")
		(net "SW_HDD_R16")
	)
	(via
		(at 145.8722 -130.937)
		(size 0.6604)
		(drill 0.3302)
		(layers "F.Cu" "B.Cu")
		(net "SW_HDD_R16")
	)
	(segment
		(start 109.885988 -132.620512)
		(end 109.885988 -131.604512)
		(width 0.17145)
		(layer "F.Cu")
		(net "SW_HDD_R15")
	)
	(segment
		(start 115.71224 -131.94284)
		(end 114.681 -130.9116)
		(width 0.17145)
		(layer "F.Cu")
		(net "SW_HDD_R15")
	)
	(segment
		(start 115.71224 -133.5532)
		(end 115.71224 -131.94284)
		(width 0.17145)
		(layer "F.Cu")
		(net "SW_HDD_R15")
	)
	(segment
		(start 112.141 -131.445)
		(end 111.506 -131.445)
		(width 0.17145)
		(layer "F.Cu")
		(net "SW_HDD_R15")
	)
	(segment
		(start 109.855 -132.6515)
		(end 109.885988 -132.620512)
		(width 0.17145)
		(layer "F.Cu")
		(net "SW_HDD_R15")
	)
	(segment
		(start 109.885988 -131.604512)
		(end 109.9185 -131.572)
		(width 0.17145)
		(layer "F.Cu")
		(net "SW_HDD_R15")
	)
	(segment
		(start 114.681 -130.9116)
		(end 114.2492 -130.9116)
		(width 0.17145)
		(layer "F.Cu")
		(net "SW_HDD_R15")
	)
	(segment
		(start 113.03 -131.1275)
		(end 112.4585 -131.1275)
		(width 0.17145)
		(layer "F.Cu")
		(net "SW_HDD_R15")
	)
	(segment
		(start 111.506 -131.445)
		(end 110.864396 -131.445)
		(width 0.17145)
		(layer "F.Cu")
		(net "SW_HDD_R15")
	)
	(segment
		(start 114.2492 -130.9116)
		(end 113.2459 -130.9116)
		(width 0.17145)
		(layer "F.Cu")
		(net "SW_HDD_R15")
	)
	(segment
		(start 113.2459 -130.9116)
		(end 113.03 -131.1275)
		(width 0.17145)
		(layer "F.Cu")
		(net "SW_HDD_R15")
	)
	(segment
		(start 112.4585 -131.1275)
		(end 112.141 -131.445)
		(width 0.17145)
		(layer "F.Cu")
		(net "SW_HDD_R15")
	)
	(segment
		(start 110.737396 -131.572)
		(end 109.9185 -131.572)
		(width 0.17145)
		(layer "F.Cu")
		(net "SW_HDD_R15")
	)
	(segment
		(start 110.864396 -131.445)
		(end 110.737396 -131.572)
		(width 0.17145)
		(layer "F.Cu")
		(net "SW_HDD_R15")
	)
	(via
		(at 114.2492 -130.9116)
		(size 0.6604)
		(drill 0.3302)
		(layers "F.Cu" "B.Cu")
		(net "SW_HDD_R15")
	)
	(segment
		(start 80.01 -131.445)
		(end 78.5495 -131.445)
		(width 0.17145)
		(layer "F.Cu")
		(net "SW_HDD_R14")
	)
	(segment
		(start 78.5495 -131.445)
		(end 78.4225 -131.572)
		(width 0.17145)
		(layer "F.Cu")
		(net "SW_HDD_R14")
	)
	(segment
		(start 81.8261 -131.1275)
		(end 82.2198 -130.7338)
		(width 0.17145)
		(layer "F.Cu")
		(net "SW_HDD_R14")
	)
	(segment
		(start 83.4263 -130.7338)
		(end 82.7532 -130.7338)
		(width 0.17145)
		(layer "F.Cu")
		(net "SW_HDD_R14")
	)
	(segment
		(start 81.534 -131.1275)
		(end 80.9625 -131.1275)
		(width 0.17145)
		(layer "F.Cu")
		(net "SW_HDD_R14")
	)
	(segment
		(start 82.2198 -130.7338)
		(end 82.7532 -130.7338)
		(width 0.17145)
		(layer "F.Cu")
		(net "SW_HDD_R14")
	)
	(segment
		(start 84.21624 -131.52374)
		(end 83.4263 -130.7338)
		(width 0.17145)
		(layer "F.Cu")
		(net "SW_HDD_R14")
	)
	(segment
		(start 80.645 -131.445)
		(end 80.01 -131.445)
		(width 0.17145)
		(layer "F.Cu")
		(net "SW_HDD_R14")
	)
	(segment
		(start 78.359 -132.6515)
		(end 78.359 -131.6355)
		(width 0.17145)
		(layer "F.Cu")
		(net "SW_HDD_R14")
	)
	(segment
		(start 84.21624 -133.5532)
		(end 84.21624 -131.52374)
		(width 0.17145)
		(layer "F.Cu")
		(net "SW_HDD_R14")
	)
	(segment
		(start 80.9625 -131.1275)
		(end 80.645 -131.445)
		(width 0.17145)
		(layer "F.Cu")
		(net "SW_HDD_R14")
	)
	(segment
		(start 78.359 -131.6355)
		(end 78.4225 -131.572)
		(width 0.17145)
		(layer "F.Cu")
		(net "SW_HDD_R14")
	)
	(segment
		(start 81.534 -131.1275)
		(end 81.8261 -131.1275)
		(width 0.17145)
		(layer "F.Cu")
		(net "SW_HDD_R14")
	)
	(via
		(at 82.7532 -130.7338)
		(size 0.6604)
		(drill 0.3302)
		(layers "F.Cu" "B.Cu")
		(net "SW_HDD_R14")
	)
	(segment
		(start 49.911 -131.1275)
		(end 50.1523 -130.8862)
		(width 0.17145)
		(layer "F.Cu")
		(net "SW_HDD_R13")
	)
	(segment
		(start 51.6128 -130.8862)
		(end 51.054 -130.8862)
		(width 0.17145)
		(layer "F.Cu")
		(net "SW_HDD_R13")
	)
	(segment
		(start 46.736 -132.6515)
		(end 46.736 -131.6355)
		(width 0.17145)
		(layer "F.Cu")
		(net "SW_HDD_R13")
	)
	(segment
		(start 52.59324 -133.5532)
		(end 52.59324 -131.86664)
		(width 0.17145)
		(layer "F.Cu")
		(net "SW_HDD_R13")
	)
	(segment
		(start 49.022 -131.445)
		(end 48.387 -131.445)
		(width 0.17145)
		(layer "F.Cu")
		(net "SW_HDD_R13")
	)
	(segment
		(start 50.1523 -130.8862)
		(end 51.054 -130.8862)
		(width 0.17145)
		(layer "F.Cu")
		(net "SW_HDD_R13")
	)
	(segment
		(start 48.387 -131.445)
		(end 46.9265 -131.445)
		(width 0.17145)
		(layer "F.Cu")
		(net "SW_HDD_R13")
	)
	(segment
		(start 46.736 -131.6355)
		(end 46.7995 -131.572)
		(width 0.17145)
		(layer "F.Cu")
		(net "SW_HDD_R13")
	)
	(segment
		(start 52.59324 -131.86664)
		(end 51.6128 -130.8862)
		(width 0.17145)
		(layer "F.Cu")
		(net "SW_HDD_R13")
	)
	(segment
		(start 49.3395 -131.1275)
		(end 49.022 -131.445)
		(width 0.17145)
		(layer "F.Cu")
		(net "SW_HDD_R13")
	)
	(segment
		(start 49.911 -131.1275)
		(end 49.3395 -131.1275)
		(width 0.17145)
		(layer "F.Cu")
		(net "SW_HDD_R13")
	)
	(segment
		(start 46.9265 -131.445)
		(end 46.7995 -131.572)
		(width 0.17145)
		(layer "F.Cu")
		(net "SW_HDD_R13")
	)
	(via
		(at 51.054 -130.8862)
		(size 0.6604)
		(drill 0.3302)
		(layers "F.Cu" "B.Cu")
		(net "SW_HDD_R13")
	)
	(segment
		(start 21.09724 -133.5532)
		(end 21.09724 -131.52374)
		(width 0.17145)
		(layer "F.Cu")
		(net "SW_HDD_R12")
	)
	(segment
		(start 20.4089 -130.8354)
		(end 19.6088 -130.8354)
		(width 0.17145)
		(layer "F.Cu")
		(net "SW_HDD_R12")
	)
	(segment
		(start 15.4305 -131.445)
		(end 15.3035 -131.572)
		(width 0.17145)
		(layer "F.Cu")
		(net "SW_HDD_R12")
	)
	(segment
		(start 19.0754 -131.1275)
		(end 19.3675 -130.8354)
		(width 0.17145)
		(layer "F.Cu")
		(net "SW_HDD_R12")
	)
	(segment
		(start 18.415 -131.1275)
		(end 17.8435 -131.1275)
		(width 0.17145)
		(layer "F.Cu")
		(net "SW_HDD_R12")
	)
	(segment
		(start 21.09724 -131.52374)
		(end 20.4089 -130.8354)
		(width 0.17145)
		(layer "F.Cu")
		(net "SW_HDD_R12")
	)
	(segment
		(start 19.3675 -130.8354)
		(end 19.6088 -130.8354)
		(width 0.17145)
		(layer "F.Cu")
		(net "SW_HDD_R12")
	)
	(segment
		(start 18.415 -131.1275)
		(end 19.0754 -131.1275)
		(width 0.17145)
		(layer "F.Cu")
		(net "SW_HDD_R12")
	)
	(segment
		(start 17.526 -131.445)
		(end 16.891 -131.445)
		(width 0.17145)
		(layer "F.Cu")
		(net "SW_HDD_R12")
	)
	(segment
		(start 16.891 -131.445)
		(end 15.4305 -131.445)
		(width 0.17145)
		(layer "F.Cu")
		(net "SW_HDD_R12")
	)
	(segment
		(start 15.24 -132.6515)
		(end 15.24 -131.6355)
		(width 0.17145)
		(layer "F.Cu")
		(net "SW_HDD_R12")
	)
	(segment
		(start 17.8435 -131.1275)
		(end 17.526 -131.445)
		(width 0.17145)
		(layer "F.Cu")
		(net "SW_HDD_R12")
	)
	(segment
		(start 15.24 -131.6355)
		(end 15.3035 -131.572)
		(width 0.17145)
		(layer "F.Cu")
		(net "SW_HDD_R12")
	)
	(via
		(at 19.6088 -130.8354)
		(size 0.6604)
		(drill 0.3302)
		(layers "F.Cu" "B.Cu")
		(net "SW_HDD_R12")
	)
	(segment
		(start 469.8365 -248.92)
		(end 469.8365 -250.3805)
		(width 0.17145)
		(layer "F.Cu")
		(net "SW_HDD_R11")
	)
	(segment
		(start 468.1855 -251.587)
		(end 468.1855 -250.571)
		(width 0.17145)
		(layer "F.Cu")
		(net "SW_HDD_R11")
	)
	(segment
		(start 468.3125 -250.444)
		(end 468.1855 -250.571)
		(width 0.17145)
		(layer "F.Cu")
		(net "SW_HDD_R11")
	)
	(segment
		(start 469.773 -250.444)
		(end 468.3125 -250.444)
		(width 0.17145)
		(layer "F.Cu")
		(net "SW_HDD_R11")
	)
	(segment
		(start 472.2622 -246.23776)
		(end 470.23274 -246.23776)
		(width 0.17145)
		(layer "F.Cu")
		(net "SW_HDD_R11")
	)
	(segment
		(start 469.8365 -250.3805)
		(end 469.773 -250.444)
		(width 0.17145)
		(layer "F.Cu")
		(net "SW_HDD_R11")
	)
	(segment
		(start 468.122 -251.6505)
		(end 468.1855 -251.587)
		(width 0.17145)
		(layer "F.Cu")
		(net "SW_HDD_R11")
	)
	(segment
		(start 469.8365 -248.92)
		(end 469.8365 -246.634)
		(width 0.17145)
		(layer "F.Cu")
		(net "SW_HDD_R11")
	)
	(segment
		(start 470.23274 -246.23776)
		(end 469.8365 -246.634)
		(width 0.17145)
		(layer "F.Cu")
		(net "SW_HDD_R11")
	)
	(via
		(at 469.8365 -246.634)
		(size 0.6604)
		(drill 0.3302)
		(layers "F.Cu" "B.Cu")
		(net "SW_HDD_R11")
	)
	(segment
		(start 462.28 -250.19)
		(end 462.534 -250.444)
		(width 0.17145)
		(layer "F.Cu")
		(net "SW_HDD_R10")
	)
	(segment
		(start 460.3115 -247.2055)
		(end 461.899 -247.2055)
		(width 0.17145)
		(layer "F.Cu")
		(net "SW_HDD_R10")
	)
	(segment
		(start 461.899 -247.2055)
		(end 463.042 -247.2055)
		(width 0.17145)
		(layer "F.Cu")
		(net "SW_HDD_R10")
	)
	(segment
		(start 459.1558 -246.90324)
		(end 460.00924 -246.90324)
		(width 0.17145)
		(layer "F.Cu")
		(net "SW_HDD_R10")
	)
	(segment
		(start 460.00924 -246.90324)
		(end 460.3115 -247.2055)
		(width 0.17145)
		(layer "F.Cu")
		(net "SW_HDD_R10")
	)
	(segment
		(start 463.042 -248.031)
		(end 462.28 -248.793)
		(width 0.17145)
		(layer "F.Cu")
		(net "SW_HDD_R10")
	)
	(segment
		(start 463.7405 -250.444)
		(end 462.534 -250.444)
		(width 0.17145)
		(layer "F.Cu")
		(net "SW_HDD_R10")
	)
	(segment
		(start 462.28 -248.793)
		(end 462.28 -250.19)
		(width 0.17145)
		(layer "F.Cu")
		(net "SW_HDD_R10")
	)
	(segment
		(start 463.042 -247.2055)
		(end 463.042 -248.031)
		(width 0.17145)
		(layer "F.Cu")
		(net "SW_HDD_R10")
	)
	(via
		(at 462.534 -250.444)
		(size 0.6604)
		(drill 0.3302)
		(layers "F.Cu" "B.Cu")
		(net "SW_HDD_R10")
	)
	(segment
		(start 51.6636 -245.9736)
		(end 51.2064 -245.9736)
		(width 0.17145)
		(layer "F.Cu")
		(net "SW_HDD_R1")
	)
	(segment
		(start 46.863 -246.6975)
		(end 46.9265 -246.634)
		(width 0.17145)
		(layer "F.Cu")
		(net "SW_HDD_R1")
	)
	(segment
		(start 50.038 -246.1895)
		(end 50.2539 -245.9736)
		(width 0.17145)
		(layer "F.Cu")
		(net "SW_HDD_R1")
	)
	(segment
		(start 49.149 -246.507)
		(end 48.514 -246.507)
		(width 0.17145)
		(layer "F.Cu")
		(net "SW_HDD_R1")
	)
	(segment
		(start 48.514 -246.507)
		(end 47.0535 -246.507)
		(width 0.17145)
		(layer "F.Cu")
		(net "SW_HDD_R1")
	)
	(segment
		(start 50.038 -246.1895)
		(end 49.4665 -246.1895)
		(width 0.17145)
		(layer "F.Cu")
		(net "SW_HDD_R1")
	)
	(segment
		(start 52.72024 -247.03024)
		(end 51.6636 -245.9736)
		(width 0.17145)
		(layer "F.Cu")
		(net "SW_HDD_R1")
	)
	(segment
		(start 47.0535 -246.507)
		(end 46.9265 -246.634)
		(width 0.17145)
		(layer "F.Cu")
		(net "SW_HDD_R1")
	)
	(segment
		(start 46.863 -247.7135)
		(end 46.863 -246.6975)
		(width 0.17145)
		(layer "F.Cu")
		(net "SW_HDD_R1")
	)
	(segment
		(start 49.4665 -246.1895)
		(end 49.149 -246.507)
		(width 0.17145)
		(layer "F.Cu")
		(net "SW_HDD_R1")
	)
	(segment
		(start 50.2539 -245.9736)
		(end 51.2064 -245.9736)
		(width 0.17145)
		(layer "F.Cu")
		(net "SW_HDD_R1")
	)
	(segment
		(start 52.72024 -248.6152)
		(end 52.72024 -247.03024)
		(width 0.17145)
		(layer "F.Cu")
		(net "SW_HDD_R1")
	)
	(via
		(at 51.2064 -245.9736)
		(size 0.6604)
		(drill 0.3302)
		(layers "F.Cu" "B.Cu")
		(net "SW_HDD_R1")
	)
	(segment
		(start 426.974 -250.8631)
		(end 426.6311 -250.5202)
		(width 0.17145)
		(layer "F.Cu")
		(net "SW_HDD_P9")
	)
	(segment
		(start 426.974 -251.968)
		(end 426.974 -250.8631)
		(width 0.17145)
		(layer "F.Cu")
		(net "SW_HDD_P9")
	)
	(segment
		(start 426.42536 -245.60276)
		(end 426.6311 -245.8085)
		(width 0.17145)
		(layer "F.Cu")
		(net "SW_HDD_P9")
	)
	(segment
		(start 426.6311 -249.5042)
		(end 426.6311 -250.5202)
		(width 0.17145)
		(layer "F.Cu")
		(net "SW_HDD_P9")
	)
	(segment
		(start 425.7802 -245.60276)
		(end 426.42536 -245.60276)
		(width 0.17145)
		(layer "F.Cu")
		(net "SW_HDD_P9")
	)
	(segment
		(start 426.6311 -248.412)
		(end 426.6311 -249.5042)
		(width 0.17145)
		(layer "F.Cu")
		(net "SW_HDD_P9")
	)
	(segment
		(start 426.6311 -245.8085)
		(end 426.6311 -248.412)
		(width 0.17145)
		(layer "F.Cu")
		(net "SW_HDD_P9")
	)
	(via
		(at 426.6311 -248.412)
		(size 0.6604)
		(drill 0.3302)
		(layers "F.Cu" "B.Cu")
		(net "SW_HDD_P9")
	)
	(segment
		(start 394.92936 -245.60276)
		(end 395.1605 -245.8339)
		(width 0.17145)
		(layer "F.Cu")
		(net "SW_HDD_P8")
	)
	(segment
		(start 395.478 -250.9139)
		(end 395.1605 -250.5964)
		(width 0.17145)
		(layer "F.Cu")
		(net "SW_HDD_P8")
	)
	(segment
		(start 395.478 -251.968)
		(end 395.478 -250.9139)
		(width 0.17145)
		(layer "F.Cu")
		(net "SW_HDD_P8")
	)
	(segment
		(start 395.1605 -245.8339)
		(end 395.1605 -248.5644)
		(width 0.17145)
		(layer "F.Cu")
		(net "SW_HDD_P8")
	)
	(segment
		(start 395.1605 -248.5644)
		(end 395.1605 -249.5804)
		(width 0.17145)
		(layer "F.Cu")
		(net "SW_HDD_P8")
	)
	(segment
		(start 394.2842 -245.60276)
		(end 394.92936 -245.60276)
		(width 0.17145)
		(layer "F.Cu")
		(net "SW_HDD_P8")
	)
	(segment
		(start 395.1605 -249.5804)
		(end 395.1605 -250.5964)
		(width 0.17145)
		(layer "F.Cu")
		(net "SW_HDD_P8")
	)
	(via
		(at 395.1605 -248.5644)
		(size 0.6604)
		(drill 0.3302)
		(layers "F.Cu" "B.Cu")
		(net "SW_HDD_P8")
	)
	(segment
		(start 363.855 -250.8377)
		(end 363.5629 -250.5456)
		(width 0.17145)
		(layer "F.Cu")
		(net "SW_HDD_P7")
	)
	(segment
		(start 363.5629 -249.5296)
		(end 363.5629 -250.5456)
		(width 0.17145)
		(layer "F.Cu")
		(net "SW_HDD_P7")
	)
	(segment
		(start 363.855 -251.968)
		(end 363.855 -250.8377)
		(width 0.17145)
		(layer "F.Cu")
		(net "SW_HDD_P7")
	)
	(segment
		(start 363.5629 -247.6627)
		(end 363.5629 -248.4628)
		(width 0.17145)
		(layer "F.Cu")
		(net "SW_HDD_P7")
	)
	(segment
		(start 363.5629 -248.4628)
		(end 363.5629 -249.5296)
		(width 0.17145)
		(layer "F.Cu")
		(net "SW_HDD_P7")
	)
	(segment
		(start 363.25556 -245.60276)
		(end 363.6264 -245.9736)
		(width 0.17145)
		(layer "F.Cu")
		(net "SW_HDD_P7")
	)
	(segment
		(start 362.6612 -245.60276)
		(end 363.25556 -245.60276)
		(width 0.17145)
		(layer "F.Cu")
		(net "SW_HDD_P7")
	)
	(segment
		(start 363.6264 -245.9736)
		(end 363.6264 -247.5992)
		(width 0.17145)
		(layer "F.Cu")
		(net "SW_HDD_P7")
	)
	(segment
		(start 363.6264 -247.5992)
		(end 363.5629 -247.6627)
		(width 0.17145)
		(layer "F.Cu")
		(net "SW_HDD_P7")
	)
	(via
		(at 363.5629 -248.4628)
		(size 0.6604)
		(drill 0.3302)
		(layers "F.Cu" "B.Cu")
		(net "SW_HDD_P7")
	)
	(segment
		(start 332.1939 -249.4788)
		(end 332.1939 -250.4948)
		(width 0.17145)
		(layer "F.Cu")
		(net "SW_HDD_P6")
	)
	(segment
		(start 332.1939 -245.8339)
		(end 332.1939 -248.3612)
		(width 0.17145)
		(layer "F.Cu")
		(net "SW_HDD_P6")
	)
	(segment
		(start 332.359 -251.968)
		(end 332.359 -251.333)
		(width 0.17145)
		(layer "F.Cu")
		(net "SW_HDD_P6")
	)
	(segment
		(start 332.1939 -251.1679)
		(end 332.1939 -250.4948)
		(width 0.17145)
		(layer "F.Cu")
		(net "SW_HDD_P6")
	)
	(segment
		(start 332.1939 -248.3612)
		(end 332.1939 -249.4788)
		(width 0.17145)
		(layer "F.Cu")
		(net "SW_HDD_P6")
	)
	(segment
		(start 332.359 -251.333)
		(end 332.1939 -251.1679)
		(width 0.17145)
		(layer "F.Cu")
		(net "SW_HDD_P6")
	)
	(segment
		(start 331.96276 -245.60276)
		(end 332.1939 -245.8339)
		(width 0.17145)
		(layer "F.Cu")
		(net "SW_HDD_P6")
	)
	(segment
		(start 331.1652 -245.60276)
		(end 331.96276 -245.60276)
		(width 0.17145)
		(layer "F.Cu")
		(net "SW_HDD_P6")
	)
	(via
		(at 332.1939 -248.3612)
		(size 0.6604)
		(drill 0.3302)
		(layers "F.Cu" "B.Cu")
		(net "SW_HDD_P6")
	)
	(segment
		(start 174.9425 -251.612654)
		(end 175.295814 -251.25934)
		(width 0.17145)
		(layer "F.Cu")
		(net "SW_HDD_P5")
	)
	(segment
		(start 176.060354 -250.4948)
		(end 175.295814 -251.25934)
		(width 0.17145)
		(layer "F.Cu")
		(net "SW_HDD_P5")
	)
	(segment
		(start 176.53 -257.302)
		(end 174.9425 -255.7145)
		(width 0.17145)
		(layer "F.Cu")
		(net "SW_HDD_P5")
	)
	(segment
		(start 174.9425 -255.7145)
		(end 174.9425 -254.127)
		(width 0.17145)
		(layer "F.Cu")
		(net "SW_HDD_P5")
	)
	(segment
		(start 174.9425 -254.127)
		(end 174.9425 -253.111)
		(width 0.17145)
		(layer "F.Cu")
		(net "SW_HDD_P5")
	)
	(segment
		(start 174.9425 -253.111)
		(end 174.9425 -251.612654)
		(width 0.17145)
		(layer "F.Cu")
		(net "SW_HDD_P5")
	)
	(segment
		(start 176.53 -258.826)
		(end 176.53 -257.302)
		(width 0.17145)
		(layer "F.Cu")
		(net "SW_HDD_P5")
	)
	(segment
		(start 177.53076 -250.4948)
		(end 176.060354 -250.4948)
		(width 0.17145)
		(layer "F.Cu")
		(net "SW_HDD_P5")
	)
	(via
		(at 175.295814 -251.25934)
		(size 0.6604)
		(drill 0.3302)
		(layers "F.Cu" "B.Cu")
		(net "SW_HDD_P5")
	)
	(segment
		(start 146.03476 -250.4948)
		(end 144.450054 -250.4948)
		(width 0.17145)
		(layer "F.Cu")
		(net "SW_HDD_P4")
	)
	(segment
		(start 143.4465 -251.498354)
		(end 143.4465 -253.111)
		(width 0.17145)
		(layer "F.Cu")
		(net "SW_HDD_P4")
	)
	(segment
		(start 143.4465 -253.111)
		(end 143.4465 -254.127)
		(width 0.17145)
		(layer "F.Cu")
		(net "SW_HDD_P4")
	)
	(segment
		(start 143.909796 -251.035058)
		(end 143.4465 -251.498354)
		(width 0.17145)
		(layer "F.Cu")
		(net "SW_HDD_P4")
	)
	(segment
		(start 145.034 -258.826)
		(end 145.034 -257.302)
		(width 0.17145)
		(layer "F.Cu")
		(net "SW_HDD_P4")
	)
	(segment
		(start 145.034 -257.302)
		(end 143.4465 -255.7145)
		(width 0.17145)
		(layer "F.Cu")
		(net "SW_HDD_P4")
	)
	(segment
		(start 143.4465 -255.7145)
		(end 143.4465 -254.127)
		(width 0.17145)
		(layer "F.Cu")
		(net "SW_HDD_P4")
	)
	(segment
		(start 144.450054 -250.4948)
		(end 143.909796 -251.035058)
		(width 0.17145)
		(layer "F.Cu")
		(net "SW_HDD_P4")
	)
	(via
		(at 143.909796 -251.035058)
		(size 0.6604)
		(drill 0.3302)
		(layers "F.Cu" "B.Cu")
		(net "SW_HDD_P4")
	)
	(segment
		(start 477.75876 -9.3218)
		(end 475.3102 -9.3218)
		(width 0.17145)
		(layer "F.Cu")
		(net "SW_HDD_P35")
	)
	(segment
		(start 473.1385 -18.669)
		(end 473.1385 -19.812)
		(width 0.17145)
		(layer "F.Cu")
		(net "SW_HDD_P35")
	)
	(segment
		(start 473.456 -28.702)
		(end 472.694 -27.94)
		(width 0.17145)
		(layer "F.Cu")
		(net "SW_HDD_P35")
	)
	(segment
		(start 472.694 -21.2725)
		(end 473.1385 -20.828)
		(width 0.17145)
		(layer "F.Cu")
		(net "SW_HDD_P35")
	)
	(segment
		(start 475.0308 -16.002)
		(end 473.1385 -17.8943)
		(width 0.17145)
		(layer "F.Cu")
		(net "SW_HDD_P35")
	)
	(segment
		(start 473.1385 -17.8943)
		(end 473.1385 -18.669)
		(width 0.17145)
		(layer "F.Cu")
		(net "SW_HDD_P35")
	)
	(segment
		(start 475.3102 -9.3218)
		(end 475.0308 -9.6012)
		(width 0.17145)
		(layer "F.Cu")
		(net "SW_HDD_P35")
	)
	(segment
		(start 472.694 -27.94)
		(end 472.694 -21.2725)
		(width 0.17145)
		(layer "F.Cu")
		(net "SW_HDD_P35")
	)
	(segment
		(start 473.1385 -19.812)
		(end 473.1385 -20.828)
		(width 0.17145)
		(layer "F.Cu")
		(net "SW_HDD_P35")
	)
	(segment
		(start 475.0308 -9.6012)
		(end 475.0308 -16.002)
		(width 0.17145)
		(layer "F.Cu")
		(net "SW_HDD_P35")
	)
	(segment
		(start 473.837 -28.702)
		(end 473.456 -28.702)
		(width 0.17145)
		(layer "F.Cu")
		(net "SW_HDD_P35")
	)
	(via
		(at 473.1385 -18.669)
		(size 0.6604)
		(drill 0.3302)
		(layers "F.Cu" "B.Cu")
		(net "SW_HDD_P35")
	)
	(segment
		(start 458.0128 -18.4785)
		(end 458.1271 -18.5928)
		(width 0.17145)
		(layer "F.Cu")
		(net "SW_HDD_P34")
	)
	(segment
		(start 458.12964 -17.81556)
		(end 458.0128 -17.9324)
		(width 0.17145)
		(layer "F.Cu")
		(net "SW_HDD_P34")
	)
	(segment
		(start 456.9714 -19.0627)
		(end 457.9874 -19.0627)
		(width 0.17145)
		(layer "F.Cu")
		(net "SW_HDD_P34")
	)
	(segment
		(start 455.168 -20.0152)
		(end 456.1205 -19.0627)
		(width 0.17145)
		(layer "F.Cu")
		(net "SW_HDD_P34")
	)
	(segment
		(start 458.0128 -17.9324)
		(end 458.0128 -18.4785)
		(width 0.17145)
		(layer "F.Cu")
		(net "SW_HDD_P34")
	)
	(segment
		(start 459.3844 -17.81556)
		(end 458.12964 -17.81556)
		(width 0.17145)
		(layer "F.Cu")
		(net "SW_HDD_P34")
	)
	(segment
		(start 456.2602 -25.4762)
		(end 455.168 -24.384)
		(width 0.17145)
		(layer "F.Cu")
		(net "SW_HDD_P34")
	)
	(segment
		(start 458.1271 -18.923)
		(end 457.9874 -19.0627)
		(width 0.17145)
		(layer "F.Cu")
		(net "SW_HDD_P34")
	)
	(segment
		(start 455.168 -24.384)
		(end 455.168 -20.0152)
		(width 0.17145)
		(layer "F.Cu")
		(net "SW_HDD_P34")
	)
	(segment
		(start 458.1271 -18.5928)
		(end 458.1271 -18.923)
		(width 0.17145)
		(layer "F.Cu")
		(net "SW_HDD_P34")
	)
	(segment
		(start 456.2602 -28.2194)
		(end 456.2602 -25.4762)
		(width 0.17145)
		(layer "F.Cu")
		(net "SW_HDD_P34")
	)
	(segment
		(start 456.1205 -19.0627)
		(end 456.9714 -19.0627)
		(width 0.17145)
		(layer "F.Cu")
		(net "SW_HDD_P34")
	)
	(via
		(at 458.0128 -17.9324)
		(size 0.6604)
		(drill 0.3302)
		(layers "F.Cu" "B.Cu")
		(net "SW_HDD_P34")
	)
	(segment
		(start 425.7802 -15.60576)
		(end 426.19676 -15.60576)
		(width 0.17145)
		(layer "F.Cu")
		(net "SW_HDD_P33")
	)
	(segment
		(start 426.6184 -18.415)
		(end 426.6184 -19.5453)
		(width 0.17145)
		(layer "F.Cu")
		(net "SW_HDD_P33")
	)
	(segment
		(start 426.19676 -15.60576)
		(end 426.6184 -16.0274)
		(width 0.17145)
		(layer "F.Cu")
		(net "SW_HDD_P33")
	)
	(segment
		(start 426.6311 -19.558)
		(end 426.6311 -20.574)
		(width 0.17145)
		(layer "F.Cu")
		(net "SW_HDD_P33")
	)
	(segment
		(start 426.6311 -20.574)
		(end 426.974 -20.9169)
		(width 0.17145)
		(layer "F.Cu")
		(net "SW_HDD_P33")
	)
	(segment
		(start 426.6184 -19.5453)
		(end 426.6311 -19.558)
		(width 0.17145)
		(layer "F.Cu")
		(net "SW_HDD_P33")
	)
	(segment
		(start 426.974 -20.9169)
		(end 426.974 -21.971)
		(width 0.17145)
		(layer "F.Cu")
		(net "SW_HDD_P33")
	)
	(segment
		(start 426.6184 -16.0274)
		(end 426.6184 -18.415)
		(width 0.17145)
		(layer "F.Cu")
		(net "SW_HDD_P33")
	)
	(via
		(at 426.6184 -18.415)
		(size 0.6604)
		(drill 0.3302)
		(layers "F.Cu" "B.Cu")
		(net "SW_HDD_P33")
	)
	(segment
		(start 395.0843 -16.0782)
		(end 395.0843 -17.6022)
		(width 0.17145)
		(layer "F.Cu")
		(net "SW_HDD_P32")
	)
	(segment
		(start 393.446 -25.908)
		(end 393.446 -25.3746)
		(width 0.17145)
		(layer "F.Cu")
		(net "SW_HDD_P32")
	)
	(segment
		(start 394.21816 -12.17676)
		(end 394.5128 -12.4714)
		(width 0.17145)
		(layer "F.Cu")
		(net "SW_HDD_P32")
	)
	(segment
		(start 395.0843 -15.113)
		(end 395.0843 -16.0782)
		(width 0.17145)
		(layer "F.Cu")
		(net "SW_HDD_P32")
	)
	(segment
		(start 394.5128 -14.0716)
		(end 395.0843 -14.6431)
		(width 0.17145)
		(layer "F.Cu")
		(net "SW_HDD_P32")
	)
	(segment
		(start 392.43 -19.05)
		(end 392.8618 -18.6182)
		(width 0.17145)
		(layer "F.Cu")
		(net "SW_HDD_P32")
	)
	(segment
		(start 392.43 -24.3586)
		(end 392.43 -19.05)
		(width 0.17145)
		(layer "F.Cu")
		(net "SW_HDD_P32")
	)
	(segment
		(start 394.5128 -12.4714)
		(end 394.5128 -14.0716)
		(width 0.17145)
		(layer "F.Cu")
		(net "SW_HDD_P32")
	)
	(segment
		(start 393.446 -25.3746)
		(end 392.43 -24.3586)
		(width 0.17145)
		(layer "F.Cu")
		(net "SW_HDD_P32")
	)
	(segment
		(start 393.5222 -12.17676)
		(end 394.21816 -12.17676)
		(width 0.17145)
		(layer "F.Cu")
		(net "SW_HDD_P32")
	)
	(segment
		(start 394.0683 -18.6182)
		(end 395.0843 -17.6022)
		(width 0.17145)
		(layer "F.Cu")
		(net "SW_HDD_P32")
	)
	(segment
		(start 395.0843 -14.6431)
		(end 395.0843 -15.113)
		(width 0.17145)
		(layer "F.Cu")
		(net "SW_HDD_P32")
	)
	(segment
		(start 392.8618 -18.6182)
		(end 394.0683 -18.6182)
		(width 0.17145)
		(layer "F.Cu")
		(net "SW_HDD_P32")
	)
	(via
		(at 395.0843 -15.113)
		(size 0.6604)
		(drill 0.3302)
		(layers "F.Cu" "B.Cu")
		(net "SW_HDD_P32")
	)
	(segment
		(start 363.7915 -20.574)
		(end 363.7915 -19.558)
		(width 0.17145)
		(layer "F.Cu")
		(net "SW_HDD_P31")
	)
	(segment
		(start 363.7915 -21.9075)
		(end 363.7915 -20.574)
		(width 0.17145)
		(layer "F.Cu")
		(net "SW_HDD_P31")
	)
	(segment
		(start 362.6612 -15.60576)
		(end 363.07776 -15.60576)
		(width 0.17145)
		(layer "F.Cu")
		(net "SW_HDD_P31")
	)
	(segment
		(start 363.855 -21.971)
		(end 363.7915 -21.9075)
		(width 0.17145)
		(layer "F.Cu")
		(net "SW_HDD_P31")
	)
	(segment
		(start 363.5502 -19.3167)
		(end 363.5502 -18.3261)
		(width 0.17145)
		(layer "F.Cu")
		(net "SW_HDD_P31")
	)
	(segment
		(start 363.07776 -15.60576)
		(end 363.5502 -16.0782)
		(width 0.17145)
		(layer "F.Cu")
		(net "SW_HDD_P31")
	)
	(segment
		(start 363.7915 -19.558)
		(end 363.5502 -19.3167)
		(width 0.17145)
		(layer "F.Cu")
		(net "SW_HDD_P31")
	)
	(segment
		(start 363.5502 -16.0782)
		(end 363.5502 -18.3261)
		(width 0.17145)
		(layer "F.Cu")
		(net "SW_HDD_P31")
	)
	(via
		(at 363.5502 -18.3261)
		(size 0.6604)
		(drill 0.3302)
		(layers "F.Cu" "B.Cu")
		(net "SW_HDD_P31")
	)
	(segment
		(start 330.7588 -18.3896)
		(end 331.4827 -17.6657)
		(width 0.17145)
		(layer "F.Cu")
		(net "SW_HDD_P30")
	)
	(segment
		(start 331.4827 -16.2306)
		(end 331.4827 -15.7099)
		(width 0.17145)
		(layer "F.Cu")
		(net "SW_HDD_P30")
	)
	(segment
		(start 330.073 -25.908)
		(end 330.073 -23.5204)
		(width 0.17145)
		(layer "F.Cu")
		(net "SW_HDD_P30")
	)
	(segment
		(start 331.4827 -15.7099)
		(end 331.9653 -15.2273)
		(width 0.17145)
		(layer "F.Cu")
		(net "SW_HDD_P30")
	)
	(segment
		(start 331.089 -13.716)
		(end 331.9653 -14.5923)
		(width 0.17145)
		(layer "F.Cu")
		(net "SW_HDD_P30")
	)
	(segment
		(start 331.4827 -17.5006)
		(end 331.4827 -16.2306)
		(width 0.17145)
		(layer "F.Cu")
		(net "SW_HDD_P30")
	)
	(segment
		(start 328.93 -22.3774)
		(end 328.93 -18.9484)
		(width 0.17145)
		(layer "F.Cu")
		(net "SW_HDD_P30")
	)
	(segment
		(start 330.073 -23.5204)
		(end 328.93 -22.3774)
		(width 0.17145)
		(layer "F.Cu")
		(net "SW_HDD_P30")
	)
	(segment
		(start 331.9653 -14.5923)
		(end 331.9653 -15.2273)
		(width 0.17145)
		(layer "F.Cu")
		(net "SW_HDD_P30")
	)
	(segment
		(start 331.089 -12.3952)
		(end 331.089 -13.716)
		(width 0.17145)
		(layer "F.Cu")
		(net "SW_HDD_P30")
	)
	(segment
		(start 330.87056 -12.17676)
		(end 331.089 -12.3952)
		(width 0.17145)
		(layer "F.Cu")
		(net "SW_HDD_P30")
	)
	(segment
		(start 329.4888 -18.3896)
		(end 330.7588 -18.3896)
		(width 0.17145)
		(layer "F.Cu")
		(net "SW_HDD_P30")
	)
	(segment
		(start 331.4827 -17.6657)
		(end 331.4827 -17.5006)
		(width 0.17145)
		(layer "F.Cu")
		(net "SW_HDD_P30")
	)
	(segment
		(start 330.1492 -12.17676)
		(end 330.87056 -12.17676)
		(width 0.17145)
		(layer "F.Cu")
		(net "SW_HDD_P30")
	)
	(segment
		(start 328.93 -18.9484)
		(end 329.4888 -18.3896)
		(width 0.17145)
		(layer "F.Cu")
		(net "SW_HDD_P30")
	)
	(via
		(at 331.9653 -15.2273)
		(size 0.6604)
		(drill 0.3302)
		(layers "F.Cu" "B.Cu")
		(net "SW_HDD_P30")
	)
	(segment
		(start 113.411 -257.302)
		(end 111.8235 -255.7145)
		(width 0.17145)
		(layer "F.Cu")
		(net "SW_HDD_P3")
	)
	(segment
		(start 111.8235 -253.111)
		(end 111.8235 -254.127)
		(width 0.17145)
		(layer "F.Cu")
		(net "SW_HDD_P3")
	)
	(segment
		(start 112.919764 -250.4948)
		(end 112.115092 -251.299472)
		(width 0.17145)
		(layer "F.Cu")
		(net "SW_HDD_P3")
	)
	(segment
		(start 114.41176 -250.4948)
		(end 112.919764 -250.4948)
		(width 0.17145)
		(layer "F.Cu")
		(net "SW_HDD_P3")
	)
	(segment
		(start 112.115092 -251.299472)
		(end 111.8235 -251.591064)
		(width 0.17145)
		(layer "F.Cu")
		(net "SW_HDD_P3")
	)
	(segment
		(start 113.411 -258.826)
		(end 113.411 -257.302)
		(width 0.17145)
		(layer "F.Cu")
		(net "SW_HDD_P3")
	)
	(segment
		(start 111.8235 -255.7145)
		(end 111.8235 -254.127)
		(width 0.17145)
		(layer "F.Cu")
		(net "SW_HDD_P3")
	)
	(segment
		(start 111.8235 -251.591064)
		(end 111.8235 -253.111)
		(width 0.17145)
		(layer "F.Cu")
		(net "SW_HDD_P3")
	)
	(via
		(at 112.115092 -251.299472)
		(size 0.6604)
		(drill 0.3302)
		(layers "F.Cu" "B.Cu")
		(net "SW_HDD_P3")
	)
	(segment
		(start 175.387 -21.3995)
		(end 175.8315 -20.955)
		(width 0.17145)
		(layer "F.Cu")
		(net "SW_HDD_P29")
	)
	(segment
		(start 175.8315 -19.939)
		(end 175.8315 -20.955)
		(width 0.17145)
		(layer "F.Cu")
		(net "SW_HDD_P29")
	)
	(segment
		(start 175.8315 -18.796)
		(end 175.8315 -19.939)
		(width 0.17145)
		(layer "F.Cu")
		(net "SW_HDD_P29")
	)
	(segment
		(start 176.53 -28.361894)
		(end 175.387 -27.218894)
		(width 0.17145)
		(layer "F.Cu")
		(net "SW_HDD_P29")
	)
	(segment
		(start 175.387 -27.218894)
		(end 175.387 -21.3995)
		(width 0.17145)
		(layer "F.Cu")
		(net "SW_HDD_P29")
	)
	(segment
		(start 175.8315 -18.796)
		(end 175.8315 -17.5895)
		(width 0.17145)
		(layer "F.Cu")
		(net "SW_HDD_P29")
	)
	(segment
		(start 177.43424 -15.98676)
		(end 177.8762 -15.98676)
		(width 0.17145)
		(layer "F.Cu")
		(net "SW_HDD_P29")
	)
	(segment
		(start 175.8315 -17.5895)
		(end 177.43424 -15.98676)
		(width 0.17145)
		(layer "F.Cu")
		(net "SW_HDD_P29")
	)
	(segment
		(start 176.53 -28.829)
		(end 176.53 -28.361894)
		(width 0.17145)
		(layer "F.Cu")
		(net "SW_HDD_P29")
	)
	(via
		(at 175.8315 -18.796)
		(size 0.6604)
		(drill 0.3302)
		(layers "F.Cu" "B.Cu")
		(net "SW_HDD_P29")
	)
	(segment
		(start 143.4465 -23.114)
		(end 143.4465 -24.13)
		(width 0.17145)
		(layer "F.Cu")
		(net "SW_HDD_P28")
	)
	(segment
		(start 143.702278 -21.236686)
		(end 143.4465 -21.492464)
		(width 0.17145)
		(layer "F.Cu")
		(net "SW_HDD_P28")
	)
	(segment
		(start 145.034 -27.305)
		(end 143.4465 -25.7175)
		(width 0.17145)
		(layer "F.Cu")
		(net "SW_HDD_P28")
	)
	(segment
		(start 143.4465 -25.7175)
		(end 143.4465 -24.13)
		(width 0.17145)
		(layer "F.Cu")
		(net "SW_HDD_P28")
	)
	(segment
		(start 146.03476 -20.4978)
		(end 144.441164 -20.4978)
		(width 0.17145)
		(layer "F.Cu")
		(net "SW_HDD_P28")
	)
	(segment
		(start 145.034 -28.829)
		(end 145.034 -27.305)
		(width 0.17145)
		(layer "F.Cu")
		(net "SW_HDD_P28")
	)
	(segment
		(start 143.4465 -21.492464)
		(end 143.4465 -23.114)
		(width 0.17145)
		(layer "F.Cu")
		(net "SW_HDD_P28")
	)
	(segment
		(start 144.441164 -20.4978)
		(end 143.702278 -21.236686)
		(width 0.17145)
		(layer "F.Cu")
		(net "SW_HDD_P28")
	)
	(via
		(at 143.702278 -21.236686)
		(size 0.6604)
		(drill 0.3302)
		(layers "F.Cu" "B.Cu")
		(net "SW_HDD_P28")
	)
	(segment
		(start 111.975646 -30.1879)
		(end 110.5154 -30.1879)
		(width 0.17145)
		(layer "F.Cu")
		(net "SW_HDD_P27")
	)
	(segment
		(start 112.8522 -29.7434)
		(end 112.4077 -30.1879)
		(width 0.17145)
		(layer "F.Cu")
		(net "SW_HDD_P27")
	)
	(segment
		(start 112.2172 -27.097482)
		(end 112.2172 -20.447)
		(width 0.17145)
		(layer "F.Cu")
		(net "SW_HDD_P27")
	)
	(segment
		(start 112.2172 -20.447)
		(end 113.157 -19.5072)
		(width 0.17145)
		(layer "F.Cu")
		(net "SW_HDD_P27")
	)
	(segment
		(start 113.157 -16.383)
		(end 113.157 -18.8722)
		(width 0.17145)
		(layer "F.Cu")
		(net "SW_HDD_P27")
	)
	(segment
		(start 113.5126 -29.7434)
		(end 112.8522 -29.7434)
		(width 0.17145)
		(layer "F.Cu")
		(net "SW_HDD_P27")
	)
	(segment
		(start 110.5154 -28.799282)
		(end 112.2172 -27.097482)
		(width 0.17145)
		(layer "F.Cu")
		(net "SW_HDD_P27")
	)
	(segment
		(start 113.157 -19.5072)
		(end 113.157 -18.8722)
		(width 0.17145)
		(layer "F.Cu")
		(net "SW_HDD_P27")
	)
	(segment
		(start 113.55324 -15.98676)
		(end 113.157 -16.383)
		(width 0.17145)
		(layer "F.Cu")
		(net "SW_HDD_P27")
	)
	(segment
		(start 110.5154 -30.1879)
		(end 110.5154 -28.799282)
		(width 0.17145)
		(layer "F.Cu")
		(net "SW_HDD_P27")
	)
	(segment
		(start 112.4077 -30.1879)
		(end 111.975646 -30.1879)
		(width 0.17145)
		(layer "F.Cu")
		(net "SW_HDD_P27")
	)
	(segment
		(start 114.3762 -15.98676)
		(end 113.55324 -15.98676)
		(width 0.17145)
		(layer "F.Cu")
		(net "SW_HDD_P27")
	)
	(via
		(at 113.157 -18.8722)
		(size 0.6604)
		(drill 0.3302)
		(layers "F.Cu" "B.Cu")
		(net "SW_HDD_P27")
	)
	(segment
		(start 81.915 -28.829)
		(end 81.915 -27.305)
		(width 0.17145)
		(layer "F.Cu")
		(net "SW_HDD_P26")
	)
	(segment
		(start 81.915 -27.305)
		(end 80.3275 -25.7175)
		(width 0.17145)
		(layer "F.Cu")
		(net "SW_HDD_P26")
	)
	(segment
		(start 81.3054 -20.4978)
		(end 80.4672 -21.336)
		(width 0.17145)
		(layer "F.Cu")
		(net "SW_HDD_P26")
	)
	(segment
		(start 80.4672 -21.336)
		(end 80.3275 -21.4757)
		(width 0.17145)
		(layer "F.Cu")
		(net "SW_HDD_P26")
	)
	(segment
		(start 80.3275 -23.114)
		(end 80.3275 -24.13)
		(width 0.17145)
		(layer "F.Cu")
		(net "SW_HDD_P26")
	)
	(segment
		(start 82.91576 -20.4978)
		(end 81.3054 -20.4978)
		(width 0.17145)
		(layer "F.Cu")
		(net "SW_HDD_P26")
	)
	(segment
		(start 80.3275 -21.4757)
		(end 80.3275 -23.114)
		(width 0.17145)
		(layer "F.Cu")
		(net "SW_HDD_P26")
	)
	(segment
		(start 80.3275 -25.7175)
		(end 80.3275 -24.13)
		(width 0.17145)
		(layer "F.Cu")
		(net "SW_HDD_P26")
	)
	(via
		(at 80.4672 -21.336)
		(size 0.6604)
		(drill 0.3302)
		(layers "F.Cu" "B.Cu")
		(net "SW_HDD_P26")
	)
	(segment
		(start 50.8 -17.2085)
		(end 49.5935 -18.415)
		(width 0.17145)
		(layer "F.Cu")
		(net "SW_HDD_P25")
	)
	(segment
		(start 49.5935 -18.669)
		(end 49.5935 -19.939)
		(width 0.17145)
		(layer "F.Cu")
		(net "SW_HDD_P25")
	)
	(segment
		(start 49.5935 -19.939)
		(end 49.5935 -20.955)
		(width 0.17145)
		(layer "F.Cu")
		(net "SW_HDD_P25")
	)
	(segment
		(start 49.149 -28.067)
		(end 49.149 -21.3995)
		(width 0.17145)
		(layer "F.Cu")
		(net "SW_HDD_P25")
	)
	(segment
		(start 49.911 -28.829)
		(end 49.149 -28.067)
		(width 0.17145)
		(layer "F.Cu")
		(net "SW_HDD_P25")
	)
	(segment
		(start 50.8 -16.383)
		(end 50.8 -17.2085)
		(width 0.17145)
		(layer "F.Cu")
		(net "SW_HDD_P25")
	)
	(segment
		(start 49.5935 -18.415)
		(end 49.5935 -18.669)
		(width 0.17145)
		(layer "F.Cu")
		(net "SW_HDD_P25")
	)
	(segment
		(start 51.6382 -15.98676)
		(end 51.19624 -15.98676)
		(width 0.17145)
		(layer "F.Cu")
		(net "SW_HDD_P25")
	)
	(segment
		(start 49.149 -21.3995)
		(end 49.5935 -20.955)
		(width 0.17145)
		(layer "F.Cu")
		(net "SW_HDD_P25")
	)
	(segment
		(start 50.292 -28.829)
		(end 49.911 -28.829)
		(width 0.17145)
		(layer "F.Cu")
		(net "SW_HDD_P25")
	)
	(segment
		(start 51.19624 -15.98676)
		(end 50.8 -16.383)
		(width 0.17145)
		(layer "F.Cu")
		(net "SW_HDD_P25")
	)
	(via
		(at 49.5935 -18.669)
		(size 0.6604)
		(drill 0.3302)
		(layers "F.Cu" "B.Cu")
		(net "SW_HDD_P25")
	)
	(segment
		(start 18.796 -28.829)
		(end 18.796 -27.305)
		(width 0.17145)
		(layer "F.Cu")
		(net "SW_HDD_P24")
	)
	(segment
		(start 17.2085 -25.7175)
		(end 17.2085 -24.13)
		(width 0.17145)
		(layer "F.Cu")
		(net "SW_HDD_P24")
	)
	(segment
		(start 18.1737 -20.4978)
		(end 17.2085 -21.463)
		(width 0.17145)
		(layer "F.Cu")
		(net "SW_HDD_P24")
	)
	(segment
		(start 17.2085 -21.463)
		(end 17.2085 -23.114)
		(width 0.17145)
		(layer "F.Cu")
		(net "SW_HDD_P24")
	)
	(segment
		(start 17.2085 -23.114)
		(end 17.2085 -24.13)
		(width 0.17145)
		(layer "F.Cu")
		(net "SW_HDD_P24")
	)
	(segment
		(start 19.79676 -20.4978)
		(end 18.1737 -20.4978)
		(width 0.17145)
		(layer "F.Cu")
		(net "SW_HDD_P24")
	)
	(segment
		(start 18.796 -27.305)
		(end 17.2085 -25.7175)
		(width 0.17145)
		(layer "F.Cu")
		(net "SW_HDD_P24")
	)
	(via
		(at 17.2085 -21.463)
		(size 0.6604)
		(drill 0.3302)
		(layers "F.Cu" "B.Cu")
		(net "SW_HDD_P24")
	)
	(segment
		(start 473.075 -133.221222)
		(end 472.2495 -134.046722)
		(width 0.17145)
		(layer "F.Cu")
		(net "SW_HDD_P23")
	)
	(segment
		(start 473.837 -141.478)
		(end 472.2495 -139.8905)
		(width 0.17145)
		(layer "F.Cu")
		(net "SW_HDD_P23")
	)
	(segment
		(start 474.1418 -132.47624)
		(end 473.31376 -132.47624)
		(width 0.17145)
		(layer "F.Cu")
		(net "SW_HDD_P23")
	)
	(segment
		(start 473.075 -132.715)
		(end 473.075 -133.221222)
		(width 0.17145)
		(layer "F.Cu")
		(net "SW_HDD_P23")
	)
	(segment
		(start 472.2495 -139.065)
		(end 472.2495 -138.049)
		(width 0.17145)
		(layer "F.Cu")
		(net "SW_HDD_P23")
	)
	(segment
		(start 473.31376 -132.47624)
		(end 473.075 -132.715)
		(width 0.17145)
		(layer "F.Cu")
		(net "SW_HDD_P23")
	)
	(segment
		(start 472.2495 -138.049)
		(end 472.2495 -134.915148)
		(width 0.17145)
		(layer "F.Cu")
		(net "SW_HDD_P23")
	)
	(segment
		(start 472.2495 -134.046722)
		(end 472.2495 -134.915148)
		(width 0.17145)
		(layer "F.Cu")
		(net "SW_HDD_P23")
	)
	(segment
		(start 473.837 -143.764)
		(end 473.837 -141.478)
		(width 0.17145)
		(layer "F.Cu")
		(net "SW_HDD_P23")
	)
	(segment
		(start 472.2495 -139.8905)
		(end 472.2495 -139.065)
		(width 0.17145)
		(layer "F.Cu")
		(net "SW_HDD_P23")
	)
	(via
		(at 472.2495 -134.915148)
		(size 0.6604)
		(drill 0.3302)
		(layers "F.Cu" "B.Cu")
		(net "SW_HDD_P23")
	)
	(segment
		(start 457.2762 -130.66776)
		(end 457.74356 -130.66776)
		(width 0.17145)
		(layer "F.Cu")
		(net "SW_HDD_P22")
	)
	(segment
		(start 458.2287 -134.6454)
		(end 458.2287 -135.6614)
		(width 0.17145)
		(layer "F.Cu")
		(net "SW_HDD_P22")
	)
	(segment
		(start 457.74356 -130.66776)
		(end 458.2287 -131.1529)
		(width 0.17145)
		(layer "F.Cu")
		(net "SW_HDD_P22")
	)
	(segment
		(start 458.2287 -133.3754)
		(end 458.2287 -134.6454)
		(width 0.17145)
		(layer "F.Cu")
		(net "SW_HDD_P22")
	)
	(segment
		(start 458.2287 -131.1529)
		(end 458.2287 -133.3754)
		(width 0.17145)
		(layer "F.Cu")
		(net "SW_HDD_P22")
	)
	(segment
		(start 458.47 -137.033)
		(end 458.47 -135.9027)
		(width 0.17145)
		(layer "F.Cu")
		(net "SW_HDD_P22")
	)
	(segment
		(start 458.47 -135.9027)
		(end 458.2287 -135.6614)
		(width 0.17145)
		(layer "F.Cu")
		(net "SW_HDD_P22")
	)
	(via
		(at 458.2287 -133.3754)
		(size 0.6604)
		(drill 0.3302)
		(layers "F.Cu" "B.Cu")
		(net "SW_HDD_P22")
	)
	(segment
		(start 425.7802 -130.66776)
		(end 426.50156 -130.66776)
		(width 0.17145)
		(layer "F.Cu")
		(net "SW_HDD_P21")
	)
	(segment
		(start 426.7327 -134.6454)
		(end 426.7327 -135.6614)
		(width 0.17145)
		(layer "F.Cu")
		(net "SW_HDD_P21")
	)
	(segment
		(start 426.974 -137.033)
		(end 426.974 -135.9027)
		(width 0.17145)
		(layer "F.Cu")
		(net "SW_HDD_P21")
	)
	(segment
		(start 426.974 -135.9027)
		(end 426.7327 -135.6614)
		(width 0.17145)
		(layer "F.Cu")
		(net "SW_HDD_P21")
	)
	(segment
		(start 426.50156 -130.66776)
		(end 426.7327 -130.8989)
		(width 0.17145)
		(layer "F.Cu")
		(net "SW_HDD_P21")
	)
	(segment
		(start 426.7327 -130.8989)
		(end 426.7327 -133.4008)
		(width 0.17145)
		(layer "F.Cu")
		(net "SW_HDD_P21")
	)
	(segment
		(start 426.7327 -133.4008)
		(end 426.7327 -134.6454)
		(width 0.17145)
		(layer "F.Cu")
		(net "SW_HDD_P21")
	)
	(via
		(at 426.7327 -133.4008)
		(size 0.6604)
		(drill 0.3302)
		(layers "F.Cu" "B.Cu")
		(net "SW_HDD_P21")
	)
	(segment
		(start 395.478 -135.9789)
		(end 395.0843 -135.5852)
		(width 0.17145)
		(layer "F.Cu")
		(net "SW_HDD_P20")
	)
	(segment
		(start 394.2842 -130.66776)
		(end 394.92936 -130.66776)
		(width 0.17145)
		(layer "F.Cu")
		(net "SW_HDD_P20")
	)
	(segment
		(start 394.92936 -130.66776)
		(end 395.0843 -130.8227)
		(width 0.17145)
		(layer "F.Cu")
		(net "SW_HDD_P20")
	)
	(segment
		(start 395.478 -137.033)
		(end 395.478 -135.9789)
		(width 0.17145)
		(layer "F.Cu")
		(net "SW_HDD_P20")
	)
	(segment
		(start 395.0843 -133.3246)
		(end 395.0843 -134.5692)
		(width 0.17145)
		(layer "F.Cu")
		(net "SW_HDD_P20")
	)
	(segment
		(start 395.0843 -130.8227)
		(end 395.0843 -133.3246)
		(width 0.17145)
		(layer "F.Cu")
		(net "SW_HDD_P20")
	)
	(segment
		(start 395.0843 -134.5692)
		(end 395.0843 -135.5852)
		(width 0.17145)
		(layer "F.Cu")
		(net "SW_HDD_P20")
	)
	(via
		(at 395.0843 -133.3246)
		(size 0.6604)
		(drill 0.3302)
		(layers "F.Cu" "B.Cu")
		(net "SW_HDD_P20")
	)
	(segment
		(start 82.91576 -250.4948)
		(end 81.298542 -250.4948)
		(width 0.17145)
		(layer "F.Cu")
		(net "SW_HDD_P2")
	)
	(segment
		(start 80.3275 -251.465842)
		(end 80.3275 -253.111)
		(width 0.17145)
		(layer "F.Cu")
		(net "SW_HDD_P2")
	)
	(segment
		(start 80.3275 -253.111)
		(end 80.3275 -254.127)
		(width 0.17145)
		(layer "F.Cu")
		(net "SW_HDD_P2")
	)
	(segment
		(start 81.915 -258.826)
		(end 81.915 -257.302)
		(width 0.17145)
		(layer "F.Cu")
		(net "SW_HDD_P2")
	)
	(segment
		(start 81.915 -257.302)
		(end 80.3275 -255.7145)
		(width 0.17145)
		(layer "F.Cu")
		(net "SW_HDD_P2")
	)
	(segment
		(start 80.655668 -251.137674)
		(end 80.3275 -251.465842)
		(width 0.17145)
		(layer "F.Cu")
		(net "SW_HDD_P2")
	)
	(segment
		(start 81.298542 -250.4948)
		(end 80.655668 -251.137674)
		(width 0.17145)
		(layer "F.Cu")
		(net "SW_HDD_P2")
	)
	(segment
		(start 80.3275 -255.7145)
		(end 80.3275 -254.127)
		(width 0.17145)
		(layer "F.Cu")
		(net "SW_HDD_P2")
	)
	(via
		(at 80.655668 -251.137674)
		(size 0.6604)
		(drill 0.3302)
		(layers "F.Cu" "B.Cu")
		(net "SW_HDD_P2")
	)
	(segment
		(start 363.5629 -130.8481)
		(end 363.5629 -133.35)
		(width 0.17145)
		(layer "F.Cu")
		(net "SW_HDD_P19")
	)
	(segment
		(start 363.5629 -134.5946)
		(end 363.5629 -135.6106)
		(width 0.17145)
		(layer "F.Cu")
		(net "SW_HDD_P19")
	)
	(segment
		(start 363.5629 -133.35)
		(end 363.5629 -134.5946)
		(width 0.17145)
		(layer "F.Cu")
		(net "SW_HDD_P19")
	)
	(segment
		(start 363.855 -135.9027)
		(end 363.5629 -135.6106)
		(width 0.17145)
		(layer "F.Cu")
		(net "SW_HDD_P19")
	)
	(segment
		(start 362.6612 -130.66776)
		(end 363.38256 -130.66776)
		(width 0.17145)
		(layer "F.Cu")
		(net "SW_HDD_P19")
	)
	(segment
		(start 363.38256 -130.66776)
		(end 363.5629 -130.8481)
		(width 0.17145)
		(layer "F.Cu")
		(net "SW_HDD_P19")
	)
	(segment
		(start 363.855 -137.033)
		(end 363.855 -135.9027)
		(width 0.17145)
		(layer "F.Cu")
		(net "SW_HDD_P19")
	)
	(via
		(at 363.5629 -133.35)
		(size 0.6604)
		(drill 0.3302)
		(layers "F.Cu" "B.Cu")
		(net "SW_HDD_P19")
	)
	(segment
		(start 331.1652 -130.66776)
		(end 331.75956 -130.66776)
		(width 0.17145)
		(layer "F.Cu")
		(net "SW_HDD_P18")
	)
	(segment
		(start 331.9399 -136.036304)
		(end 331.9399 -135.636)
		(width 0.17145)
		(layer "F.Cu")
		(net "SW_HDD_P18")
	)
	(segment
		(start 331.75956 -130.66776)
		(end 331.9272 -130.8354)
		(width 0.17145)
		(layer "F.Cu")
		(net "SW_HDD_P18")
	)
	(segment
		(start 331.9272 -133.477)
		(end 331.9272 -134.6073)
		(width 0.17145)
		(layer "F.Cu")
		(net "SW_HDD_P18")
	)
	(segment
		(start 332.359 -137.033)
		(end 332.359 -136.455404)
		(width 0.17145)
		(layer "F.Cu")
		(net "SW_HDD_P18")
	)
	(segment
		(start 332.359 -136.455404)
		(end 331.9399 -136.036304)
		(width 0.17145)
		(layer "F.Cu")
		(net "SW_HDD_P18")
	)
	(segment
		(start 331.9272 -134.6073)
		(end 331.9399 -134.62)
		(width 0.17145)
		(layer "F.Cu")
		(net "SW_HDD_P18")
	)
	(segment
		(start 331.9399 -134.62)
		(end 331.9399 -135.636)
		(width 0.17145)
		(layer "F.Cu")
		(net "SW_HDD_P18")
	)
	(segment
		(start 331.9272 -130.8354)
		(end 331.9272 -133.477)
		(width 0.17145)
		(layer "F.Cu")
		(net "SW_HDD_P18")
	)
	(via
		(at 331.9272 -133.477)
		(size 0.6604)
		(drill 0.3302)
		(layers "F.Cu" "B.Cu")
		(net "SW_HDD_P18")
	)
	(segment
		(start 177.53076 -135.4328)
		(end 175.969422 -135.4328)
		(width 0.17145)
		(layer "F.Cu")
		(net "SW_HDD_P17")
	)
	(segment
		(start 174.9425 -136.459722)
		(end 174.9425 -138.049)
		(width 0.17145)
		(layer "F.Cu")
		(net "SW_HDD_P17")
	)
	(segment
		(start 174.9425 -138.049)
		(end 174.9425 -139.065)
		(width 0.17145)
		(layer "F.Cu")
		(net "SW_HDD_P17")
	)
	(segment
		(start 176.53 -143.764)
		(end 176.53 -140.6525)
		(width 0.17145)
		(layer "F.Cu")
		(net "SW_HDD_P17")
	)
	(segment
		(start 175.289464 -136.112758)
		(end 174.9425 -136.459722)
		(width 0.17145)
		(layer "F.Cu")
		(net "SW_HDD_P17")
	)
	(segment
		(start 176.53 -140.6525)
		(end 174.9425 -139.065)
		(width 0.17145)
		(layer "F.Cu")
		(net "SW_HDD_P17")
	)
	(segment
		(start 175.969422 -135.4328)
		(end 175.289464 -136.112758)
		(width 0.17145)
		(layer "F.Cu")
		(net "SW_HDD_P17")
	)
	(via
		(at 175.289464 -136.112758)
		(size 0.6604)
		(drill 0.3302)
		(layers "F.Cu" "B.Cu")
		(net "SW_HDD_P17")
	)
	(segment
		(start 146.03476 -135.4328)
		(end 144.6022 -135.4328)
		(width 0.17145)
		(layer "F.Cu")
		(net "SW_HDD_P16")
	)
	(segment
		(start 143.4465 -136.5885)
		(end 143.4465 -138.049)
		(width 0.17145)
		(layer "F.Cu")
		(net "SW_HDD_P16")
	)
	(segment
		(start 145.034 -143.764)
		(end 145.034 -142.24)
		(width 0.17145)
		(layer "F.Cu")
		(net "SW_HDD_P16")
	)
	(segment
		(start 143.637 -136.398)
		(end 143.4465 -136.5885)
		(width 0.17145)
		(layer "F.Cu")
		(net "SW_HDD_P16")
	)
	(segment
		(start 143.4465 -140.6525)
		(end 143.4465 -139.065)
		(width 0.17145)
		(layer "F.Cu")
		(net "SW_HDD_P16")
	)
	(segment
		(start 144.6022 -135.4328)
		(end 143.637 -136.398)
		(width 0.17145)
		(layer "F.Cu")
		(net "SW_HDD_P16")
	)
	(segment
		(start 143.4465 -138.049)
		(end 143.4465 -139.065)
		(width 0.17145)
		(layer "F.Cu")
		(net "SW_HDD_P16")
	)
	(segment
		(start 145.034 -142.24)
		(end 143.4465 -140.6525)
		(width 0.17145)
		(layer "F.Cu")
		(net "SW_HDD_P16")
	)
	(via
		(at 143.637 -136.398)
		(size 0.6604)
		(drill 0.3302)
		(layers "F.Cu" "B.Cu")
		(net "SW_HDD_P16")
	)
	(segment
		(start 114.41176 -135.4328)
		(end 112.691926 -135.4328)
		(width 0.17145)
		(layer "F.Cu")
		(net "SW_HDD_P15")
	)
	(segment
		(start 111.8235 -136.301226)
		(end 111.8235 -138.049)
		(width 0.17145)
		(layer "F.Cu")
		(net "SW_HDD_P15")
	)
	(segment
		(start 111.97717 -136.147556)
		(end 111.8235 -136.301226)
		(width 0.17145)
		(layer "F.Cu")
		(net "SW_HDD_P15")
	)
	(segment
		(start 113.411 -143.764)
		(end 113.411 -142.24)
		(width 0.17145)
		(layer "F.Cu")
		(net "SW_HDD_P15")
	)
	(segment
		(start 111.8235 -138.049)
		(end 111.8235 -139.065)
		(width 0.17145)
		(layer "F.Cu")
		(net "SW_HDD_P15")
	)
	(segment
		(start 113.411 -142.24)
		(end 111.8235 -140.6525)
		(width 0.17145)
		(layer "F.Cu")
		(net "SW_HDD_P15")
	)
	(segment
		(start 112.691926 -135.4328)
		(end 111.97717 -136.147556)
		(width 0.17145)
		(layer "F.Cu")
		(net "SW_HDD_P15")
	)
	(segment
		(start 111.8235 -140.6525)
		(end 111.8235 -139.065)
		(width 0.17145)
		(layer "F.Cu")
		(net "SW_HDD_P15")
	)
	(via
		(at 111.97717 -136.147556)
		(size 0.6604)
		(drill 0.3302)
		(layers "F.Cu" "B.Cu")
		(net "SW_HDD_P15")
	)
	(segment
		(start 81.0514 -135.4328)
		(end 80.3275 -136.1567)
		(width 0.17145)
		(layer "F.Cu")
		(net "SW_HDD_P14")
	)
	(segment
		(start 81.915 -142.24)
		(end 80.3275 -140.6525)
		(width 0.17145)
		(layer "F.Cu")
		(net "SW_HDD_P14")
	)
	(segment
		(start 81.523332 -135.4328)
		(end 81.0514 -135.4328)
		(width 0.17145)
		(layer "F.Cu")
		(net "SW_HDD_P14")
	)
	(segment
		(start 80.3275 -140.6525)
		(end 80.3275 -139.065)
		(width 0.17145)
		(layer "F.Cu")
		(net "SW_HDD_P14")
	)
	(segment
		(start 80.3275 -138.049)
		(end 80.3275 -139.065)
		(width 0.17145)
		(layer "F.Cu")
		(net "SW_HDD_P14")
	)
	(segment
		(start 80.3275 -136.1567)
		(end 80.3275 -138.049)
		(width 0.17145)
		(layer "F.Cu")
		(net "SW_HDD_P14")
	)
	(segment
		(start 81.915 -143.764)
		(end 81.915 -142.24)
		(width 0.17145)
		(layer "F.Cu")
		(net "SW_HDD_P14")
	)
	(segment
		(start 81.523332 -135.4328)
		(end 82.91576 -135.4328)
		(width 0.17145)
		(layer "F.Cu")
		(net "SW_HDD_P14")
	)
	(via
		(at 81.523332 -135.4328)
		(size 0.6604)
		(drill 0.3302)
		(layers "F.Cu" "B.Cu")
		(net "SW_HDD_P14")
	)
	(segment
		(start 48.7045 -140.6525)
		(end 48.7045 -139.065)
		(width 0.17145)
		(layer "F.Cu")
		(net "SW_HDD_P13")
	)
	(segment
		(start 48.7045 -138.049)
		(end 48.7045 -139.065)
		(width 0.17145)
		(layer "F.Cu")
		(net "SW_HDD_P13")
	)
	(segment
		(start 50.292 -143.764)
		(end 50.292 -142.24)
		(width 0.17145)
		(layer "F.Cu")
		(net "SW_HDD_P13")
	)
	(segment
		(start 50.292 -142.24)
		(end 48.7045 -140.6525)
		(width 0.17145)
		(layer "F.Cu")
		(net "SW_HDD_P13")
	)
	(segment
		(start 49.770792 -135.4328)
		(end 48.894746 -136.308846)
		(width 0.17145)
		(layer "F.Cu")
		(net "SW_HDD_P13")
	)
	(segment
		(start 51.29276 -135.4328)
		(end 49.770792 -135.4328)
		(width 0.17145)
		(layer "F.Cu")
		(net "SW_HDD_P13")
	)
	(segment
		(start 48.894746 -136.308846)
		(end 48.7045 -136.499092)
		(width 0.17145)
		(layer "F.Cu")
		(net "SW_HDD_P13")
	)
	(segment
		(start 48.7045 -136.499092)
		(end 48.7045 -138.049)
		(width 0.17145)
		(layer "F.Cu")
		(net "SW_HDD_P13")
	)
	(via
		(at 48.894746 -136.308846)
		(size 0.6604)
		(drill 0.3302)
		(layers "F.Cu" "B.Cu")
		(net "SW_HDD_P13")
	)
	(segment
		(start 17.2085 -136.4869)
		(end 17.2974 -136.398)
		(width 0.17145)
		(layer "F.Cu")
		(net "SW_HDD_P12")
	)
	(segment
		(start 18.796 -142.24)
		(end 17.2085 -140.6525)
		(width 0.17145)
		(layer "F.Cu")
		(net "SW_HDD_P12")
	)
	(segment
		(start 18.2626 -135.4328)
		(end 17.2974 -136.398)
		(width 0.17145)
		(layer "F.Cu")
		(net "SW_HDD_P12")
	)
	(segment
		(start 19.79676 -135.4328)
		(end 18.2626 -135.4328)
		(width 0.17145)
		(layer "F.Cu")
		(net "SW_HDD_P12")
	)
	(segment
		(start 17.2085 -140.6525)
		(end 17.2085 -139.065)
		(width 0.17145)
		(layer "F.Cu")
		(net "SW_HDD_P12")
	)
	(segment
		(start 17.2085 -139.065)
		(end 17.2085 -138.049)
		(width 0.17145)
		(layer "F.Cu")
		(net "SW_HDD_P12")
	)
	(segment
		(start 17.2085 -138.049)
		(end 17.2085 -136.4869)
		(width 0.17145)
		(layer "F.Cu")
		(net "SW_HDD_P12")
	)
	(segment
		(start 18.796 -143.764)
		(end 18.796 -142.24)
		(width 0.17145)
		(layer "F.Cu")
		(net "SW_HDD_P12")
	)
	(via
		(at 17.2974 -136.398)
		(size 0.6604)
		(drill 0.3302)
		(layers "F.Cu" "B.Cu")
		(net "SW_HDD_P12")
	)
	(segment
		(start 472.2495 -249.2375)
		(end 472.2495 -249.752104)
		(width 0.17145)
		(layer "F.Cu")
		(net "SW_HDD_P11")
	)
	(segment
		(start 473.837 -258.826)
		(end 473.837 -256.54)
		(width 0.17145)
		(layer "F.Cu")
		(net "SW_HDD_P11")
	)
	(segment
		(start 473.44076 -247.53824)
		(end 473.075 -247.904)
		(width 0.17145)
		(layer "F.Cu")
		(net "SW_HDD_P11")
	)
	(segment
		(start 472.2495 -253.111)
		(end 472.2495 -249.752104)
		(width 0.17145)
		(layer "F.Cu")
		(net "SW_HDD_P11")
	)
	(segment
		(start 473.837 -256.54)
		(end 472.2495 -254.9525)
		(width 0.17145)
		(layer "F.Cu")
		(net "SW_HDD_P11")
	)
	(segment
		(start 474.1418 -247.53824)
		(end 473.44076 -247.53824)
		(width 0.17145)
		(layer "F.Cu")
		(net "SW_HDD_P11")
	)
	(segment
		(start 473.075 -248.412)
		(end 472.2495 -249.2375)
		(width 0.17145)
		(layer "F.Cu")
		(net "SW_HDD_P11")
	)
	(segment
		(start 472.2495 -254.9525)
		(end 472.2495 -254.127)
		(width 0.17145)
		(layer "F.Cu")
		(net "SW_HDD_P11")
	)
	(segment
		(start 473.075 -247.904)
		(end 473.075 -248.412)
		(width 0.17145)
		(layer "F.Cu")
		(net "SW_HDD_P11")
	)
	(segment
		(start 472.2495 -254.127)
		(end 472.2495 -253.111)
		(width 0.17145)
		(layer "F.Cu")
		(net "SW_HDD_P11")
	)
	(via
		(at 472.2495 -249.752104)
		(size 0.6604)
		(drill 0.3302)
		(layers "F.Cu" "B.Cu")
		(net "SW_HDD_P11")
	)
	(segment
		(start 458.47 -251.968)
		(end 458.47 -250.8123)
		(width 0.17145)
		(layer "F.Cu")
		(net "SW_HDD_P10")
	)
	(segment
		(start 458.1525 -248.4374)
		(end 458.1525 -249.4788)
		(width 0.17145)
		(layer "F.Cu")
		(net "SW_HDD_P10")
	)
	(segment
		(start 457.94676 -245.60276)
		(end 458.1525 -245.8085)
		(width 0.17145)
		(layer "F.Cu")
		(net "SW_HDD_P10")
	)
	(segment
		(start 458.1525 -245.8085)
		(end 458.1525 -248.4374)
		(width 0.17145)
		(layer "F.Cu")
		(net "SW_HDD_P10")
	)
	(segment
		(start 457.2762 -245.60276)
		(end 457.94676 -245.60276)
		(width 0.17145)
		(layer "F.Cu")
		(net "SW_HDD_P10")
	)
	(segment
		(start 458.47 -250.8123)
		(end 458.1525 -250.4948)
		(width 0.17145)
		(layer "F.Cu")
		(net "SW_HDD_P10")
	)
	(segment
		(start 458.1525 -249.4788)
		(end 458.1525 -250.4948)
		(width 0.17145)
		(layer "F.Cu")
		(net "SW_HDD_P10")
	)
	(via
		(at 458.1525 -248.4374)
		(size 0.6604)
		(drill 0.3302)
		(layers "F.Cu" "B.Cu")
		(net "SW_HDD_P10")
	)
	(segment
		(start 49.998884 -250.4948)
		(end 49.263046 -251.230638)
		(width 0.17145)
		(layer "F.Cu")
		(net "SW_HDD_P1")
	)
	(segment
		(start 50.419 -257.302)
		(end 48.8315 -255.7145)
		(width 0.17145)
		(layer "F.Cu")
		(net "SW_HDD_P1")
	)
	(segment
		(start 50.419 -258.826)
		(end 50.419 -257.302)
		(width 0.17145)
		(layer "F.Cu")
		(net "SW_HDD_P1")
	)
	(segment
		(start 48.8315 -253.111)
		(end 48.8315 -254.127)
		(width 0.17145)
		(layer "F.Cu")
		(net "SW_HDD_P1")
	)
	(segment
		(start 51.41976 -250.4948)
		(end 49.998884 -250.4948)
		(width 0.17145)
		(layer "F.Cu")
		(net "SW_HDD_P1")
	)
	(segment
		(start 48.8315 -255.7145)
		(end 48.8315 -254.127)
		(width 0.17145)
		(layer "F.Cu")
		(net "SW_HDD_P1")
	)
	(segment
		(start 49.263046 -251.230638)
		(end 48.8315 -251.662184)
		(width 0.17145)
		(layer "F.Cu")
		(net "SW_HDD_P1")
	)
	(segment
		(start 48.8315 -251.662184)
		(end 48.8315 -253.111)
		(width 0.17145)
		(layer "F.Cu")
		(net "SW_HDD_P1")
	)
	(via
		(at 49.263046 -251.230638)
		(size 0.6604)
		(drill 0.3302)
		(layers "F.Cu" "B.Cu")
		(net "SW_HDD_P1")
	)
	(segment
		(start 433.324 -260.0325)
		(end 433.7685 -259.588)
		(width 0.17145)
		(layer "F.Cu")
		(net "SW_HDD_N9")
	)
	(segment
		(start 433.324 -260.477)
		(end 433.324 -260.0325)
		(width 0.17145)
		(layer "F.Cu")
		(net "SW_HDD_N9")
	)
	(segment
		(start 434.086 -250.444)
		(end 434.467 -250.825)
		(width 0.17145)
		(layer "F.Cu")
		(net "SW_HDD_N9")
	)
	(segment
		(start 433.1335 -250.444)
		(end 434.086 -250.444)
		(width 0.17145)
		(layer "F.Cu")
		(net "SW_HDD_N9")
	)
	(segment
		(start 433.1335 -249.7455)
		(end 433.1335 -250.444)
		(width 0.17145)
		(layer "F.Cu")
		(net "SW_HDD_N9")
	)
	(segment
		(start 434.467 -250.825)
		(end 434.467 -257.1115)
		(width 0.17145)
		(layer "F.Cu")
		(net "SW_HDD_N9")
	)
	(segment
		(start 433.07 -248.793)
		(end 433.07 -249.682)
		(width 0.17145)
		(layer "F.Cu")
		(net "SW_HDD_N9")
	)
	(segment
		(start 433.7685 -257.81)
		(end 433.7685 -258.826)
		(width 0.17145)
		(layer "F.Cu")
		(net "SW_HDD_N9")
	)
	(segment
		(start 433.7685 -259.588)
		(end 433.7685 -258.826)
		(width 0.17145)
		(layer "F.Cu")
		(net "SW_HDD_N9")
	)
	(segment
		(start 433.07 -249.682)
		(end 433.1335 -249.7455)
		(width 0.17145)
		(layer "F.Cu")
		(net "SW_HDD_N9")
	)
	(segment
		(start 434.467 -257.1115)
		(end 433.7685 -257.81)
		(width 0.17145)
		(layer "F.Cu")
		(net "SW_HDD_N9")
	)
	(via
		(at 434.086 -250.444)
		(size 0.6604)
		(drill 0.3302)
		(layers "F.Cu" "B.Cu")
		(net "SW_HDD_N9")
	)
	(segment
		(start 402.971 -250.571)
		(end 402.844 -250.444)
		(width 0.17145)
		(layer "F.Cu")
		(net "SW_HDD_N8")
	)
	(segment
		(start 401.6375 -248.8565)
		(end 401.6375 -250.444)
		(width 0.17145)
		(layer "F.Cu")
		(net "SW_HDD_N8")
	)
	(segment
		(start 402.2725 -257.81)
		(end 402.2725 -257.4925)
		(width 0.17145)
		(layer "F.Cu")
		(net "SW_HDD_N8")
	)
	(segment
		(start 401.6375 -250.444)
		(end 402.844 -250.444)
		(width 0.17145)
		(layer "F.Cu")
		(net "SW_HDD_N8")
	)
	(segment
		(start 402.971 -256.794)
		(end 402.971 -250.571)
		(width 0.17145)
		(layer "F.Cu")
		(net "SW_HDD_N8")
	)
	(segment
		(start 402.2725 -257.4925)
		(end 402.971 -256.794)
		(width 0.17145)
		(layer "F.Cu")
		(net "SW_HDD_N8")
	)
	(segment
		(start 402.2725 -259.588)
		(end 402.2725 -258.826)
		(width 0.17145)
		(layer "F.Cu")
		(net "SW_HDD_N8")
	)
	(segment
		(start 401.828 -260.0325)
		(end 402.2725 -259.588)
		(width 0.17145)
		(layer "F.Cu")
		(net "SW_HDD_N8")
	)
	(segment
		(start 401.574 -248.793)
		(end 401.6375 -248.8565)
		(width 0.17145)
		(layer "F.Cu")
		(net "SW_HDD_N8")
	)
	(segment
		(start 402.2725 -258.826)
		(end 402.2725 -257.81)
		(width 0.17145)
		(layer "F.Cu")
		(net "SW_HDD_N8")
	)
	(segment
		(start 401.828 -260.477)
		(end 401.828 -260.0325)
		(width 0.17145)
		(layer "F.Cu")
		(net "SW_HDD_N8")
	)
	(via
		(at 402.844 -250.444)
		(size 0.6604)
		(drill 0.3302)
		(layers "F.Cu" "B.Cu")
		(net "SW_HDD_N8")
	)
	(segment
		(start 370.6495 -258.826)
		(end 370.6495 -257.81)
		(width 0.17145)
		(layer "F.Cu")
		(net "SW_HDD_N7")
	)
	(segment
		(start 369.951 -248.793)
		(end 370.0145 -248.8565)
		(width 0.17145)
		(layer "F.Cu")
		(net "SW_HDD_N7")
	)
	(segment
		(start 370.205 -260.0325)
		(end 370.6495 -259.588)
		(width 0.17145)
		(layer "F.Cu")
		(net "SW_HDD_N7")
	)
	(segment
		(start 370.205 -260.477)
		(end 370.205 -260.0325)
		(width 0.17145)
		(layer "F.Cu")
		(net "SW_HDD_N7")
	)
	(segment
		(start 370.6495 -257.81)
		(end 371.348 -257.1115)
		(width 0.17145)
		(layer "F.Cu")
		(net "SW_HDD_N7")
	)
	(segment
		(start 370.0145 -248.8565)
		(end 370.0145 -250.444)
		(width 0.17145)
		(layer "F.Cu")
		(net "SW_HDD_N7")
	)
	(segment
		(start 371.348 -257.1115)
		(end 371.348 -250.571)
		(width 0.17145)
		(layer "F.Cu")
		(net "SW_HDD_N7")
	)
	(segment
		(start 370.0145 -250.444)
		(end 371.221 -250.444)
		(width 0.17145)
		(layer "F.Cu")
		(net "SW_HDD_N7")
	)
	(segment
		(start 370.6495 -259.588)
		(end 370.6495 -258.826)
		(width 0.17145)
		(layer "F.Cu")
		(net "SW_HDD_N7")
	)
	(segment
		(start 371.348 -250.571)
		(end 371.221 -250.444)
		(width 0.17145)
		(layer "F.Cu")
		(net "SW_HDD_N7")
	)
	(via
		(at 371.221 -250.444)
		(size 0.6604)
		(drill 0.3302)
		(layers "F.Cu" "B.Cu")
		(net "SW_HDD_N7")
	)
	(segment
		(start 338.709 -260.0325)
		(end 339.1535 -259.588)
		(width 0.17145)
		(layer "F.Cu")
		(net "SW_HDD_N6")
	)
	(segment
		(start 339.725 -250.444)
		(end 338.5185 -250.444)
		(width 0.17145)
		(layer "F.Cu")
		(net "SW_HDD_N6")
	)
	(segment
		(start 339.852 -250.571)
		(end 339.725 -250.444)
		(width 0.17145)
		(layer "F.Cu")
		(net "SW_HDD_N6")
	)
	(segment
		(start 338.455 -248.793)
		(end 338.5185 -248.8565)
		(width 0.17145)
		(layer "F.Cu")
		(net "SW_HDD_N6")
	)
	(segment
		(start 339.1535 -259.588)
		(end 339.1535 -258.826)
		(width 0.17145)
		(layer "F.Cu")
		(net "SW_HDD_N6")
	)
	(segment
		(start 339.1535 -257.81)
		(end 339.852 -257.1115)
		(width 0.17145)
		(layer "F.Cu")
		(net "SW_HDD_N6")
	)
	(segment
		(start 339.1535 -258.826)
		(end 339.1535 -257.81)
		(width 0.17145)
		(layer "F.Cu")
		(net "SW_HDD_N6")
	)
	(segment
		(start 339.852 -257.1115)
		(end 339.852 -250.571)
		(width 0.17145)
		(layer "F.Cu")
		(net "SW_HDD_N6")
	)
	(segment
		(start 338.709 -260.477)
		(end 338.709 -260.0325)
		(width 0.17145)
		(layer "F.Cu")
		(net "SW_HDD_N6")
	)
	(segment
		(start 338.5185 -248.8565)
		(end 338.5185 -250.444)
		(width 0.17145)
		(layer "F.Cu")
		(net "SW_HDD_N6")
	)
	(via
		(at 339.725 -250.444)
		(size 0.6604)
		(drill 0.3302)
		(layers "F.Cu" "B.Cu")
		(net "SW_HDD_N6")
	)
	(segment
		(start 174.498 -258.318)
		(end 174.498 -256.9845)
		(width 0.17145)
		(layer "F.Cu")
		(net "SW_HDD_N5")
	)
	(segment
		(start 174.498 -256.9845)
		(end 173.0375 -255.524)
		(width 0.17145)
		(layer "F.Cu")
		(net "SW_HDD_N5")
	)
	(segment
		(start 174.625 -248.793)
		(end 174.4345 -248.6025)
		(width 0.17145)
		(layer "F.Cu")
		(net "SW_HDD_N5")
	)
	(segment
		(start 172.974 -248.6025)
		(end 172.974 -250.317)
		(width 0.17145)
		(layer "F.Cu")
		(net "SW_HDD_N5")
	)
	(segment
		(start 174.4345 -248.6025)
		(end 172.974 -248.6025)
		(width 0.17145)
		(layer "F.Cu")
		(net "SW_HDD_N5")
	)
	(segment
		(start 172.974 -250.317)
		(end 172.974 -250.6345)
		(width 0.17145)
		(layer "F.Cu")
		(net "SW_HDD_N5")
	)
	(segment
		(start 173.0375 -254.508)
		(end 173.0375 -255.524)
		(width 0.17145)
		(layer "F.Cu")
		(net "SW_HDD_N5")
	)
	(segment
		(start 172.974 -250.6345)
		(end 173.0375 -250.698)
		(width 0.17145)
		(layer "F.Cu")
		(net "SW_HDD_N5")
	)
	(segment
		(start 173.0375 -250.698)
		(end 173.0375 -254.508)
		(width 0.17145)
		(layer "F.Cu")
		(net "SW_HDD_N5")
	)
	(via
		(at 172.974 -250.317)
		(size 0.6604)
		(drill 0.3302)
		(layers "F.Cu" "B.Cu")
		(net "SW_HDD_N5")
	)
	(segment
		(start 141.5415 -250.698)
		(end 141.5415 -254.508)
		(width 0.17145)
		(layer "F.Cu")
		(net "SW_HDD_N4")
	)
	(segment
		(start 141.478 -250.317)
		(end 141.478 -250.6345)
		(width 0.17145)
		(layer "F.Cu")
		(net "SW_HDD_N4")
	)
	(segment
		(start 141.478 -248.6025)
		(end 141.478 -250.317)
		(width 0.17145)
		(layer "F.Cu")
		(net "SW_HDD_N4")
	)
	(segment
		(start 143.129 -248.793)
		(end 142.9385 -248.6025)
		(width 0.17145)
		(layer "F.Cu")
		(net "SW_HDD_N4")
	)
	(segment
		(start 142.9385 -248.6025)
		(end 141.478 -248.6025)
		(width 0.17145)
		(layer "F.Cu")
		(net "SW_HDD_N4")
	)
	(segment
		(start 141.478 -250.6345)
		(end 141.5415 -250.698)
		(width 0.17145)
		(layer "F.Cu")
		(net "SW_HDD_N4")
	)
	(segment
		(start 141.5415 -254.508)
		(end 141.5415 -255.524)
		(width 0.17145)
		(layer "F.Cu")
		(net "SW_HDD_N4")
	)
	(segment
		(start 143.002 -256.9845)
		(end 141.5415 -255.524)
		(width 0.17145)
		(layer "F.Cu")
		(net "SW_HDD_N4")
	)
	(segment
		(start 143.002 -258.318)
		(end 143.002 -256.9845)
		(width 0.17145)
		(layer "F.Cu")
		(net "SW_HDD_N4")
	)
	(via
		(at 141.478 -250.317)
		(size 0.6604)
		(drill 0.3302)
		(layers "F.Cu" "B.Cu")
		(net "SW_HDD_N4")
	)
	(segment
		(start 474.3323 -15.8877)
		(end 474.3323 -10.6934)
		(width 0.17145)
		(layer "F.Cu")
		(net "SW_HDD_N35")
	)
	(segment
		(start 473.6592 -8.6868)
		(end 474.3323 -9.3599)
		(width 0.17145)
		(layer "F.Cu")
		(net "SW_HDD_N35")
	)
	(segment
		(start 474.1545 -7.9502)
		(end 473.837 -7.6327)
		(width 0.17145)
		(layer "F.Cu")
		(net "SW_HDD_N35")
	)
	(segment
		(start 474.6752 -7.9502)
		(end 474.1545 -7.9502)
		(width 0.17145)
		(layer "F.Cu")
		(net "SW_HDD_N35")
	)
	(segment
		(start 473.0242 -8.5344)
		(end 473.1766 -8.6868)
		(width 0.17145)
		(layer "F.Cu")
		(net "SW_HDD_N35")
	)
	(segment
		(start 474.3323 -9.6774)
		(end 474.3323 -10.6934)
		(width 0.17145)
		(layer "F.Cu")
		(net "SW_HDD_N35")
	)
	(segment
		(start 471.424 -18.796)
		(end 474.3323 -15.8877)
		(width 0.17145)
		(layer "F.Cu")
		(net "SW_HDD_N35")
	)
	(segment
		(start 473.0242 -7.6327)
		(end 473.0242 -8.5344)
		(width 0.17145)
		(layer "F.Cu")
		(net "SW_HDD_N35")
	)
	(segment
		(start 471.424 -21.717)
		(end 471.424 -18.796)
		(width 0.17145)
		(layer "F.Cu")
		(net "SW_HDD_N35")
	)
	(segment
		(start 473.1766 -8.6868)
		(end 473.6592 -8.6868)
		(width 0.17145)
		(layer "F.Cu")
		(net "SW_HDD_N35")
	)
	(segment
		(start 473.837 -7.6327)
		(end 473.0242 -7.6327)
		(width 0.17145)
		(layer "F.Cu")
		(net "SW_HDD_N35")
	)
	(segment
		(start 474.3323 -9.3599)
		(end 474.3323 -9.6774)
		(width 0.17145)
		(layer "F.Cu")
		(net "SW_HDD_N35")
	)
	(via
		(at 473.1766 -8.6868)
		(size 0.6604)
		(drill 0.3302)
		(layers "F.Cu" "B.Cu")
		(net "SW_HDD_N35")
	)
	(segment
		(start 463.7151 -25.0571)
		(end 463.7151 -25.6032)
		(width 0.17145)
		(layer "F.Cu")
		(net "SW_HDD_N34")
	)
	(segment
		(start 464.693 -30.48)
		(end 464.693 -29.972)
		(width 0.17145)
		(layer "F.Cu")
		(net "SW_HDD_N34")
	)
	(segment
		(start 465.0105 -29.6545)
		(end 465.0105 -28.829)
		(width 0.17145)
		(layer "F.Cu")
		(net "SW_HDD_N34")
	)
	(segment
		(start 463.7659 -25.654)
		(end 463.7151 -25.6032)
		(width 0.17145)
		(layer "F.Cu")
		(net "SW_HDD_N34")
	)
	(segment
		(start 464.82 -25.654)
		(end 465.0105 -25.8445)
		(width 0.17145)
		(layer "F.Cu")
		(net "SW_HDD_N34")
	)
	(segment
		(start 465.0105 -27.813)
		(end 465.0105 -28.829)
		(width 0.17145)
		(layer "F.Cu")
		(net "SW_HDD_N34")
	)
	(segment
		(start 464.82 -25.654)
		(end 463.7659 -25.654)
		(width 0.17145)
		(layer "F.Cu")
		(net "SW_HDD_N34")
	)
	(segment
		(start 465.0105 -25.8445)
		(end 465.0105 -27.813)
		(width 0.17145)
		(layer "F.Cu")
		(net "SW_HDD_N34")
	)
	(segment
		(start 464.693 -29.972)
		(end 465.0105 -29.6545)
		(width 0.17145)
		(layer "F.Cu")
		(net "SW_HDD_N34")
	)
	(segment
		(start 464.2866 -24.4856)
		(end 463.7151 -25.0571)
		(width 0.17145)
		(layer "F.Cu")
		(net "SW_HDD_N34")
	)
	(segment
		(start 464.2866 -23.9776)
		(end 464.2866 -24.4856)
		(width 0.17145)
		(layer "F.Cu")
		(net "SW_HDD_N34")
	)
	(via
		(at 464.82 -25.654)
		(size 0.6604)
		(drill 0.3302)
		(layers "F.Cu" "B.Cu")
		(net "SW_HDD_N34")
	)
	(segment
		(start 433.1335 -18.8595)
		(end 433.1335 -20.447)
		(width 0.17145)
		(layer "F.Cu")
		(net "SW_HDD_N33")
	)
	(segment
		(start 433.7685 -29.591)
		(end 433.7685 -28.829)
		(width 0.17145)
		(layer "F.Cu")
		(net "SW_HDD_N33")
	)
	(segment
		(start 434.467 -20.828)
		(end 434.467 -27.1145)
		(width 0.17145)
		(layer "F.Cu")
		(net "SW_HDD_N33")
	)
	(segment
		(start 433.324 -30.48)
		(end 433.324 -30.0355)
		(width 0.17145)
		(layer "F.Cu")
		(net "SW_HDD_N33")
	)
	(segment
		(start 433.7685 -27.813)
		(end 433.7685 -28.829)
		(width 0.17145)
		(layer "F.Cu")
		(net "SW_HDD_N33")
	)
	(segment
		(start 433.07 -18.796)
		(end 433.1335 -18.8595)
		(width 0.17145)
		(layer "F.Cu")
		(net "SW_HDD_N33")
	)
	(segment
		(start 434.467 -27.1145)
		(end 433.7685 -27.813)
		(width 0.17145)
		(layer "F.Cu")
		(net "SW_HDD_N33")
	)
	(segment
		(start 434.086 -20.447)
		(end 434.467 -20.828)
		(width 0.17145)
		(layer "F.Cu")
		(net "SW_HDD_N33")
	)
	(segment
		(start 433.1335 -20.447)
		(end 434.086 -20.447)
		(width 0.17145)
		(layer "F.Cu")
		(net "SW_HDD_N33")
	)
	(segment
		(start 433.324 -30.0355)
		(end 433.7685 -29.591)
		(width 0.17145)
		(layer "F.Cu")
		(net "SW_HDD_N33")
	)
	(via
		(at 434.086 -20.447)
		(size 0.6604)
		(drill 0.3302)
		(layers "F.Cu" "B.Cu")
		(net "SW_HDD_N33")
	)
	(segment
		(start 406.117044 -17.526)
		(end 400.5072 -17.526)
		(width 0.17145)
		(layer "F.Cu")
		(net "SW_HDD_N32")
	)
	(segment
		(start 405.8666 -35.814)
		(end 407.5811 -34.0995)
		(width 0.17145)
		(layer "F.Cu")
		(net "SW_HDD_N32")
	)
	(segment
		(start 409.97505 -21.384006)
		(end 406.117044 -17.526)
		(width 0.17145)
		(layer "F.Cu")
		(net "SW_HDD_N32")
	)
	(segment
		(start 400.5072 -17.526)
		(end 398.78 -17.526)
		(width 0.17145)
		(layer "F.Cu")
		(net "SW_HDD_N32")
	)
	(segment
		(start 398.78 -17.526)
		(end 398.7165 -17.5895)
		(width 0.17145)
		(layer "F.Cu")
		(net "SW_HDD_N32")
	)
	(segment
		(start 407.5811 -33.782)
		(end 407.5811 -32.766)
		(width 0.17145)
		(layer "F.Cu")
		(net "SW_HDD_N32")
	)
	(segment
		(start 408.5336 -32.766)
		(end 409.97505 -31.32455)
		(width 0.17145)
		(layer "F.Cu")
		(net "SW_HDD_N32")
	)
	(segment
		(start 398.7165 -17.5895)
		(end 397.129 -17.5895)
		(width 0.17145)
		(layer "F.Cu")
		(net "SW_HDD_N32")
	)
	(segment
		(start 409.97505 -31.32455)
		(end 409.97505 -21.384006)
		(width 0.17145)
		(layer "F.Cu")
		(net "SW_HDD_N32")
	)
	(segment
		(start 403.9616 -35.814)
		(end 405.8666 -35.814)
		(width 0.17145)
		(layer "F.Cu")
		(net "SW_HDD_N32")
	)
	(segment
		(start 407.5811 -34.0995)
		(end 407.5811 -33.782)
		(width 0.17145)
		(layer "F.Cu")
		(net "SW_HDD_N32")
	)
	(segment
		(start 407.5811 -32.766)
		(end 408.5336 -32.766)
		(width 0.17145)
		(layer "F.Cu")
		(net "SW_HDD_N32")
	)
	(via
		(at 400.5072 -17.526)
		(size 0.6604)
		(drill 0.3302)
		(layers "F.Cu" "B.Cu")
		(net "SW_HDD_N32")
	)
	(segment
		(start 369.951 -18.796)
		(end 370.0145 -18.8595)
		(width 0.17145)
		(layer "F.Cu")
		(net "SW_HDD_N31")
	)
	(segment
		(start 370.205 -30.0355)
		(end 370.6495 -29.591)
		(width 0.17145)
		(layer "F.Cu")
		(net "SW_HDD_N31")
	)
	(segment
		(start 370.6495 -27.813)
		(end 370.6495 -28.829)
		(width 0.17145)
		(layer "F.Cu")
		(net "SW_HDD_N31")
	)
	(segment
		(start 370.967 -20.447)
		(end 371.348 -20.828)
		(width 0.17145)
		(layer "F.Cu")
		(net "SW_HDD_N31")
	)
	(segment
		(start 370.0145 -20.447)
		(end 370.967 -20.447)
		(width 0.17145)
		(layer "F.Cu")
		(net "SW_HDD_N31")
	)
	(segment
		(start 371.348 -27.1145)
		(end 370.6495 -27.813)
		(width 0.17145)
		(layer "F.Cu")
		(net "SW_HDD_N31")
	)
	(segment
		(start 370.0145 -18.8595)
		(end 370.0145 -20.447)
		(width 0.17145)
		(layer "F.Cu")
		(net "SW_HDD_N31")
	)
	(segment
		(start 371.348 -20.828)
		(end 371.348 -27.1145)
		(width 0.17145)
		(layer "F.Cu")
		(net "SW_HDD_N31")
	)
	(segment
		(start 370.205 -30.48)
		(end 370.205 -30.0355)
		(width 0.17145)
		(layer "F.Cu")
		(net "SW_HDD_N31")
	)
	(segment
		(start 370.6495 -29.591)
		(end 370.6495 -28.829)
		(width 0.17145)
		(layer "F.Cu")
		(net "SW_HDD_N31")
	)
	(via
		(at 370.967 -20.447)
		(size 0.6604)
		(drill 0.3302)
		(layers "F.Cu" "B.Cu")
		(net "SW_HDD_N31")
	)
	(segment
		(start 334.7466 -18.201894)
		(end 334.7466 -17.5006)
		(width 0.17145)
		(layer "F.Cu")
		(net "SW_HDD_N30")
	)
	(segment
		(start 338.8995 -27.813)
		(end 338.8995 -26.4922)
		(width 0.17145)
		(layer "F.Cu")
		(net "SW_HDD_N30")
	)
	(segment
		(start 338.8995 -27.813)
		(end 338.8995 -28.829)
		(width 0.17145)
		(layer "F.Cu")
		(net "SW_HDD_N30")
	)
	(segment
		(start 334.088486 -17.5006)
		(end 334.024986 -17.5641)
		(width 0.17145)
		(layer "F.Cu")
		(net "SW_HDD_N30")
	)
	(segment
		(start 338.8995 -26.4922)
		(end 338.8995 -22.354794)
		(width 0.17145)
		(layer "F.Cu")
		(net "SW_HDD_N30")
	)
	(segment
		(start 338.582 -29.6545)
		(end 338.8995 -29.337)
		(width 0.17145)
		(layer "F.Cu")
		(net "SW_HDD_N30")
	)
	(segment
		(start 334.024986 -17.5641)
		(end 333.1718 -17.5641)
		(width 0.17145)
		(layer "F.Cu")
		(net "SW_HDD_N30")
	)
	(segment
		(start 334.7466 -17.5006)
		(end 334.088486 -17.5006)
		(width 0.17145)
		(layer "F.Cu")
		(net "SW_HDD_N30")
	)
	(segment
		(start 338.8995 -22.354794)
		(end 334.7466 -18.201894)
		(width 0.17145)
		(layer "F.Cu")
		(net "SW_HDD_N30")
	)
	(segment
		(start 338.8995 -29.337)
		(end 338.8995 -28.829)
		(width 0.17145)
		(layer "F.Cu")
		(net "SW_HDD_N30")
	)
	(segment
		(start 338.582 -30.48)
		(end 338.582 -29.6545)
		(width 0.17145)
		(layer "F.Cu")
		(net "SW_HDD_N30")
	)
	(via
		(at 338.8995 -26.4922)
		(size 0.6604)
		(drill 0.3302)
		(layers "F.Cu" "B.Cu")
		(net "SW_HDD_N30")
	)
	(segment
		(start 109.855 -248.6025)
		(end 109.855 -250.317)
		(width 0.17145)
		(layer "F.Cu")
		(net "SW_HDD_N3")
	)
	(segment
		(start 111.379 -256.9845)
		(end 109.9185 -255.524)
		(width 0.17145)
		(layer "F.Cu")
		(net "SW_HDD_N3")
	)
	(segment
		(start 111.379 -258.318)
		(end 111.379 -256.9845)
		(width 0.17145)
		(layer "F.Cu")
		(net "SW_HDD_N3")
	)
	(segment
		(start 109.9185 -250.698)
		(end 109.9185 -254.508)
		(width 0.17145)
		(layer "F.Cu")
		(net "SW_HDD_N3")
	)
	(segment
		(start 111.506 -248.793)
		(end 111.3155 -248.6025)
		(width 0.17145)
		(layer "F.Cu")
		(net "SW_HDD_N3")
	)
	(segment
		(start 111.3155 -248.6025)
		(end 109.855 -248.6025)
		(width 0.17145)
		(layer "F.Cu")
		(net "SW_HDD_N3")
	)
	(segment
		(start 109.855 -250.317)
		(end 109.855 -250.6345)
		(width 0.17145)
		(layer "F.Cu")
		(net "SW_HDD_N3")
	)
	(segment
		(start 109.9185 -254.508)
		(end 109.9185 -255.524)
		(width 0.17145)
		(layer "F.Cu")
		(net "SW_HDD_N3")
	)
	(segment
		(start 109.855 -250.6345)
		(end 109.9185 -250.698)
		(width 0.17145)
		(layer "F.Cu")
		(net "SW_HDD_N3")
	)
	(via
		(at 109.855 -250.317)
		(size 0.6604)
		(drill 0.3302)
		(layers "F.Cu" "B.Cu")
		(net "SW_HDD_N3")
	)
	(segment
		(start 178.1175 -10.795)
		(end 177.6984 -10.3759)
		(width 0.17145)
		(layer "F.Cu")
		(net "SW_HDD_N29")
	)
	(segment
		(start 174.117 -20.701)
		(end 174.6758 -20.1422)
		(width 0.17145)
		(layer "F.Cu")
		(net "SW_HDD_N29")
	)
	(segment
		(start 176.6824 -16.011144)
		(end 174.6758 -18.017744)
		(width 0.17145)
		(layer "F.Cu")
		(net "SW_HDD_N29")
	)
	(segment
		(start 179.197 -13.0302)
		(end 178.5112 -13.0302)
		(width 0.17145)
		(layer "F.Cu")
		(net "SW_HDD_N29")
	)
	(segment
		(start 178.1175 -11.4427)
		(end 178.1175 -10.795)
		(width 0.17145)
		(layer "F.Cu")
		(net "SW_HDD_N29")
	)
	(segment
		(start 178.5112 -13.0302)
		(end 178.1175 -12.6365)
		(width 0.17145)
		(layer "F.Cu")
		(net "SW_HDD_N29")
	)
	(segment
		(start 174.117 -21.844)
		(end 174.117 -20.701)
		(width 0.17145)
		(layer "F.Cu")
		(net "SW_HDD_N29")
	)
	(segment
		(start 174.6758 -18.017744)
		(end 174.6758 -20.1422)
		(width 0.17145)
		(layer "F.Cu")
		(net "SW_HDD_N29")
	)
	(segment
		(start 177.6984 -10.3759)
		(end 176.6824 -10.3759)
		(width 0.17145)
		(layer "F.Cu")
		(net "SW_HDD_N29")
	)
	(segment
		(start 176.6824 -10.3759)
		(end 176.6824 -16.011144)
		(width 0.17145)
		(layer "F.Cu")
		(net "SW_HDD_N29")
	)
	(segment
		(start 178.1175 -12.6365)
		(end 178.1175 -11.4427)
		(width 0.17145)
		(layer "F.Cu")
		(net "SW_HDD_N29")
	)
	(via
		(at 174.6758 -20.1422)
		(size 0.6604)
		(drill 0.3302)
		(layers "F.Cu" "B.Cu")
		(net "SW_HDD_N29")
	)
	(segment
		(start 141.478 -18.6055)
		(end 141.478 -20.32)
		(width 0.17145)
		(layer "F.Cu")
		(net "SW_HDD_N28")
	)
	(segment
		(start 143.002 -28.321)
		(end 143.002 -26.9875)
		(width 0.17145)
		(layer "F.Cu")
		(net "SW_HDD_N28")
	)
	(segment
		(start 143.129 -18.796)
		(end 142.9385 -18.6055)
		(width 0.17145)
		(layer "F.Cu")
		(net "SW_HDD_N28")
	)
	(segment
		(start 142.9385 -18.6055)
		(end 141.478 -18.6055)
		(width 0.17145)
		(layer "F.Cu")
		(net "SW_HDD_N28")
	)
	(segment
		(start 141.5415 -24.511)
		(end 141.5415 -25.527)
		(width 0.17145)
		(layer "F.Cu")
		(net "SW_HDD_N28")
	)
	(segment
		(start 141.478 -20.6375)
		(end 141.5415 -20.701)
		(width 0.17145)
		(layer "F.Cu")
		(net "SW_HDD_N28")
	)
	(segment
		(start 143.002 -26.9875)
		(end 141.5415 -25.527)
		(width 0.17145)
		(layer "F.Cu")
		(net "SW_HDD_N28")
	)
	(segment
		(start 141.5415 -20.701)
		(end 141.5415 -24.511)
		(width 0.17145)
		(layer "F.Cu")
		(net "SW_HDD_N28")
	)
	(segment
		(start 141.478 -20.32)
		(end 141.478 -20.6375)
		(width 0.17145)
		(layer "F.Cu")
		(net "SW_HDD_N28")
	)
	(via
		(at 141.478 -20.32)
		(size 0.6604)
		(drill 0.3302)
		(layers "F.Cu" "B.Cu")
		(net "SW_HDD_N28")
	)
	(segment
		(start 113.6142 -9.9695)
		(end 113.8428 -10.1981)
		(width 0.17145)
		(layer "F.Cu")
		(net "SW_HDD_N27")
	)
	(segment
		(start 112.8776 -9.9695)
		(end 111.8616 -9.9695)
		(width 0.17145)
		(layer "F.Cu")
		(net "SW_HDD_N27")
	)
	(segment
		(start 112.8776 -9.9695)
		(end 113.6142 -9.9695)
		(width 0.17145)
		(layer "F.Cu")
		(net "SW_HDD_N27")
	)
	(segment
		(start 111.887 -9.9949)
		(end 111.8616 -9.9695)
		(width 0.17145)
		(layer "F.Cu")
		(net "SW_HDD_N27")
	)
	(segment
		(start 116.078 -13.081)
		(end 115.7986 -13.081)
		(width 0.17145)
		(layer "F.Cu")
		(net "SW_HDD_N27")
	)
	(segment
		(start 115.7986 -13.081)
		(end 114.7953 -12.0777)
		(width 0.17145)
		(layer "F.Cu")
		(net "SW_HDD_N27")
	)
	(segment
		(start 114.7953 -11.1506)
		(end 113.8428 -10.1981)
		(width 0.17145)
		(layer "F.Cu")
		(net "SW_HDD_N27")
	)
	(segment
		(start 114.7953 -12.0777)
		(end 114.7953 -11.303)
		(width 0.17145)
		(layer "F.Cu")
		(net "SW_HDD_N27")
	)
	(segment
		(start 114.7953 -11.303)
		(end 114.7953 -11.1506)
		(width 0.17145)
		(layer "F.Cu")
		(net "SW_HDD_N27")
	)
	(segment
		(start 111.887 -11.8364)
		(end 111.887 -9.9949)
		(width 0.17145)
		(layer "F.Cu")
		(net "SW_HDD_N27")
	)
	(via
		(at 113.8428 -10.1981)
		(size 0.6604)
		(drill 0.3302)
		(layers "F.Cu" "B.Cu")
		(net "SW_HDD_N27")
	)
	(segment
		(start 80.01 -18.796)
		(end 79.8195 -18.6055)
		(width 0.17145)
		(layer "F.Cu")
		(net "SW_HDD_N26")
	)
	(segment
		(start 79.883 -28.321)
		(end 79.883 -26.9875)
		(width 0.17145)
		(layer "F.Cu")
		(net "SW_HDD_N26")
	)
	(segment
		(start 78.359 -20.6375)
		(end 78.4225 -20.701)
		(width 0.17145)
		(layer "F.Cu")
		(net "SW_HDD_N26")
	)
	(segment
		(start 79.883 -26.9875)
		(end 78.4225 -25.527)
		(width 0.17145)
		(layer "F.Cu")
		(net "SW_HDD_N26")
	)
	(segment
		(start 78.359 -20.32)
		(end 78.359 -20.6375)
		(width 0.17145)
		(layer "F.Cu")
		(net "SW_HDD_N26")
	)
	(segment
		(start 78.359 -18.6055)
		(end 78.359 -20.32)
		(width 0.17145)
		(layer "F.Cu")
		(net "SW_HDD_N26")
	)
	(segment
		(start 78.4225 -24.511)
		(end 78.4225 -25.527)
		(width 0.17145)
		(layer "F.Cu")
		(net "SW_HDD_N26")
	)
	(segment
		(start 79.8195 -18.6055)
		(end 78.359 -18.6055)
		(width 0.17145)
		(layer "F.Cu")
		(net "SW_HDD_N26")
	)
	(segment
		(start 78.4225 -20.701)
		(end 78.4225 -24.511)
		(width 0.17145)
		(layer "F.Cu")
		(net "SW_HDD_N26")
	)
	(via
		(at 78.359 -20.32)
		(size 0.6604)
		(drill 0.3302)
		(layers "F.Cu" "B.Cu")
		(net "SW_HDD_N26")
	)
	(segment
		(start 50.4952 -10.4013)
		(end 51.5112 -10.4013)
		(width 0.17145)
		(layer "F.Cu")
		(net "SW_HDD_N25")
	)
	(segment
		(start 47.965614 -18.353786)
		(end 50.4952 -15.8242)
		(width 0.17145)
		(layer "F.Cu")
		(net "SW_HDD_N25")
	)
	(segment
		(start 47.879 -21.844)
		(end 47.879 -20.701)
		(width 0.17145)
		(layer "F.Cu")
		(net "SW_HDD_N25")
	)
	(segment
		(start 52.959 -13.0048)
		(end 52.417218 -13.0048)
		(width 0.17145)
		(layer "F.Cu")
		(net "SW_HDD_N25")
	)
	(segment
		(start 52.417218 -13.0048)
		(end 51.7525 -12.340082)
		(width 0.17145)
		(layer "F.Cu")
		(net "SW_HDD_N25")
	)
	(segment
		(start 47.965614 -20.071588)
		(end 47.965614 -18.353786)
		(width 0.17145)
		(layer "F.Cu")
		(net "SW_HDD_N25")
	)
	(segment
		(start 50.4952 -15.8242)
		(end 50.4952 -10.4013)
		(width 0.17145)
		(layer "F.Cu")
		(net "SW_HDD_N25")
	)
	(segment
		(start 47.965614 -20.614386)
		(end 47.965614 -20.071588)
		(width 0.17145)
		(layer "F.Cu")
		(net "SW_HDD_N25")
	)
	(segment
		(start 47.879 -20.701)
		(end 47.965614 -20.614386)
		(width 0.17145)
		(layer "F.Cu")
		(net "SW_HDD_N25")
	)
	(segment
		(start 51.7525 -12.340082)
		(end 51.7525 -11.4554)
		(width 0.17145)
		(layer "F.Cu")
		(net "SW_HDD_N25")
	)
	(segment
		(start 51.7525 -11.4554)
		(end 51.7525 -10.6426)
		(width 0.17145)
		(layer "F.Cu")
		(net "SW_HDD_N25")
	)
	(segment
		(start 51.7525 -10.6426)
		(end 51.5112 -10.4013)
		(width 0.17145)
		(layer "F.Cu")
		(net "SW_HDD_N25")
	)
	(via
		(at 47.965614 -20.071588)
		(size 0.6604)
		(drill 0.3302)
		(layers "F.Cu" "B.Cu")
		(net "SW_HDD_N25")
	)
	(segment
		(start 16.891 -18.796)
		(end 16.7005 -18.6055)
		(width 0.17145)
		(layer "F.Cu")
		(net "SW_HDD_N24")
	)
	(segment
		(start 16.7005 -18.6055)
		(end 15.24 -18.6055)
		(width 0.17145)
		(layer "F.Cu")
		(net "SW_HDD_N24")
	)
	(segment
		(start 15.3035 -24.511)
		(end 15.3035 -25.527)
		(width 0.17145)
		(layer "F.Cu")
		(net "SW_HDD_N24")
	)
	(segment
		(start 15.3035 -20.701)
		(end 15.3035 -24.511)
		(width 0.17145)
		(layer "F.Cu")
		(net "SW_HDD_N24")
	)
	(segment
		(start 16.764 -28.321)
		(end 16.764 -26.9875)
		(width 0.17145)
		(layer "F.Cu")
		(net "SW_HDD_N24")
	)
	(segment
		(start 15.24 -20.6375)
		(end 15.3035 -20.701)
		(width 0.17145)
		(layer "F.Cu")
		(net "SW_HDD_N24")
	)
	(segment
		(start 16.764 -26.9875)
		(end 15.3035 -25.527)
		(width 0.17145)
		(layer "F.Cu")
		(net "SW_HDD_N24")
	)
	(segment
		(start 15.24 -20.32)
		(end 15.24 -20.6375)
		(width 0.17145)
		(layer "F.Cu")
		(net "SW_HDD_N24")
	)
	(segment
		(start 15.24 -18.6055)
		(end 15.24 -20.32)
		(width 0.17145)
		(layer "F.Cu")
		(net "SW_HDD_N24")
	)
	(via
		(at 15.24 -20.32)
		(size 0.6604)
		(drill 0.3302)
		(layers "F.Cu" "B.Cu")
		(net "SW_HDD_N24")
	)
	(segment
		(start 470.3445 -139.446)
		(end 470.3445 -140.462)
		(width 0.17145)
		(layer "F.Cu")
		(net "SW_HDD_N23")
	)
	(segment
		(start 470.535 -140.462)
		(end 471.805 -141.732)
		(width 0.17145)
		(layer "F.Cu")
		(net "SW_HDD_N23")
	)
	(segment
		(start 471.805 -141.732)
		(end 471.805 -143.256)
		(width 0.17145)
		(layer "F.Cu")
		(net "SW_HDD_N23")
	)
	(segment
		(start 470.3445 -139.446)
		(end 470.3445 -138.2395)
		(width 0.17145)
		(layer "F.Cu")
		(net "SW_HDD_N23")
	)
	(segment
		(start 469.5825 -137.4775)
		(end 468.122 -137.4775)
		(width 0.17145)
		(layer "F.Cu")
		(net "SW_HDD_N23")
	)
	(segment
		(start 469.773 -137.668)
		(end 469.5825 -137.4775)
		(width 0.17145)
		(layer "F.Cu")
		(net "SW_HDD_N23")
	)
	(segment
		(start 470.3445 -140.462)
		(end 470.535 -140.462)
		(width 0.17145)
		(layer "F.Cu")
		(net "SW_HDD_N23")
	)
	(segment
		(start 470.3445 -138.2395)
		(end 469.773 -137.668)
		(width 0.17145)
		(layer "F.Cu")
		(net "SW_HDD_N23")
	)
	(via
		(at 471.805 -141.732)
		(size 0.6604)
		(drill 0.3302)
		(layers "F.Cu" "B.Cu")
		(net "SW_HDD_N23")
	)
	(segment
		(start 465.963 -142.1765)
		(end 465.2645 -142.875)
		(width 0.17145)
		(layer "F.Cu")
		(net "SW_HDD_N22")
	)
	(segment
		(start 464.566 -133.858)
		(end 464.6295 -133.9215)
		(width 0.17145)
		(layer "F.Cu")
		(net "SW_HDD_N22")
	)
	(segment
		(start 465.2645 -144.653)
		(end 465.2645 -143.891)
		(width 0.17145)
		(layer "F.Cu")
		(net "SW_HDD_N22")
	)
	(segment
		(start 465.963 -135.89)
		(end 465.963 -142.1765)
		(width 0.17145)
		(layer "F.Cu")
		(net "SW_HDD_N22")
	)
	(segment
		(start 464.6295 -133.9215)
		(end 464.6295 -135.509)
		(width 0.17145)
		(layer "F.Cu")
		(net "SW_HDD_N22")
	)
	(segment
		(start 464.82 -145.0975)
		(end 465.2645 -144.653)
		(width 0.17145)
		(layer "F.Cu")
		(net "SW_HDD_N22")
	)
	(segment
		(start 465.582 -135.509)
		(end 465.963 -135.89)
		(width 0.17145)
		(layer "F.Cu")
		(net "SW_HDD_N22")
	)
	(segment
		(start 465.2645 -142.875)
		(end 465.2645 -143.891)
		(width 0.17145)
		(layer "F.Cu")
		(net "SW_HDD_N22")
	)
	(segment
		(start 464.6295 -135.509)
		(end 465.582 -135.509)
		(width 0.17145)
		(layer "F.Cu")
		(net "SW_HDD_N22")
	)
	(segment
		(start 464.82 -145.542)
		(end 464.82 -145.0975)
		(width 0.17145)
		(layer "F.Cu")
		(net "SW_HDD_N22")
	)
	(via
		(at 465.582 -135.509)
		(size 0.6604)
		(drill 0.3302)
		(layers "F.Cu" "B.Cu")
		(net "SW_HDD_N22")
	)
	(segment
		(start 433.7685 -144.653)
		(end 433.7685 -143.891)
		(width 0.17145)
		(layer "F.Cu")
		(net "SW_HDD_N21")
	)
	(segment
		(start 434.467 -142.1765)
		(end 433.7685 -142.875)
		(width 0.17145)
		(layer "F.Cu")
		(net "SW_HDD_N21")
	)
	(segment
		(start 433.324 -145.542)
		(end 433.324 -145.0975)
		(width 0.17145)
		(layer "F.Cu")
		(net "SW_HDD_N21")
	)
	(segment
		(start 433.324 -145.0975)
		(end 433.7685 -144.653)
		(width 0.17145)
		(layer "F.Cu")
		(net "SW_HDD_N21")
	)
	(segment
		(start 434.086 -135.509)
		(end 434.467 -135.89)
		(width 0.17145)
		(layer "F.Cu")
		(net "SW_HDD_N21")
	)
	(segment
		(start 433.1335 -133.9215)
		(end 433.1335 -135.509)
		(width 0.17145)
		(layer "F.Cu")
		(net "SW_HDD_N21")
	)
	(segment
		(start 434.467 -135.89)
		(end 434.467 -142.1765)
		(width 0.17145)
		(layer "F.Cu")
		(net "SW_HDD_N21")
	)
	(segment
		(start 433.1335 -135.509)
		(end 434.086 -135.509)
		(width 0.17145)
		(layer "F.Cu")
		(net "SW_HDD_N21")
	)
	(segment
		(start 433.7685 -142.875)
		(end 433.7685 -143.891)
		(width 0.17145)
		(layer "F.Cu")
		(net "SW_HDD_N21")
	)
	(segment
		(start 433.07 -133.858)
		(end 433.1335 -133.9215)
		(width 0.17145)
		(layer "F.Cu")
		(net "SW_HDD_N21")
	)
	(via
		(at 434.086 -135.509)
		(size 0.6604)
		(drill 0.3302)
		(layers "F.Cu" "B.Cu")
		(net "SW_HDD_N21")
	)
	(segment
		(start 401.6375 -135.509)
		(end 402.59 -135.509)
		(width 0.17145)
		(layer "F.Cu")
		(net "SW_HDD_N20")
	)
	(segment
		(start 402.59 -135.509)
		(end 402.971 -135.89)
		(width 0.17145)
		(layer "F.Cu")
		(net "SW_HDD_N20")
	)
	(segment
		(start 402.971 -142.1765)
		(end 402.2725 -142.875)
		(width 0.17145)
		(layer "F.Cu")
		(net "SW_HDD_N20")
	)
	(segment
		(start 402.2725 -144.653)
		(end 402.2725 -143.891)
		(width 0.17145)
		(layer "F.Cu")
		(net "SW_HDD_N20")
	)
	(segment
		(start 401.574 -133.858)
		(end 401.6375 -133.9215)
		(width 0.17145)
		(layer "F.Cu")
		(net "SW_HDD_N20")
	)
	(segment
		(start 401.6375 -133.9215)
		(end 401.6375 -135.509)
		(width 0.17145)
		(layer "F.Cu")
		(net "SW_HDD_N20")
	)
	(segment
		(start 401.828 -145.0975)
		(end 402.2725 -144.653)
		(width 0.17145)
		(layer "F.Cu")
		(net "SW_HDD_N20")
	)
	(segment
		(start 401.828 -145.542)
		(end 401.828 -145.0975)
		(width 0.17145)
		(layer "F.Cu")
		(net "SW_HDD_N20")
	)
	(segment
		(start 402.2725 -142.875)
		(end 402.2725 -143.891)
		(width 0.17145)
		(layer "F.Cu")
		(net "SW_HDD_N20")
	)
	(segment
		(start 402.971 -135.89)
		(end 402.971 -142.1765)
		(width 0.17145)
		(layer "F.Cu")
		(net "SW_HDD_N20")
	)
	(via
		(at 402.59 -135.509)
		(size 0.6604)
		(drill 0.3302)
		(layers "F.Cu" "B.Cu")
		(net "SW_HDD_N20")
	)
	(segment
		(start 79.883 -256.9845)
		(end 78.4225 -255.524)
		(width 0.17145)
		(layer "F.Cu")
		(net "SW_HDD_N2")
	)
	(segment
		(start 78.359 -250.317)
		(end 78.359 -250.6345)
		(width 0.17145)
		(layer "F.Cu")
		(net "SW_HDD_N2")
	)
	(segment
		(start 78.4225 -250.698)
		(end 78.4225 -254.508)
		(width 0.17145)
		(layer "F.Cu")
		(net "SW_HDD_N2")
	)
	(segment
		(start 78.359 -250.6345)
		(end 78.4225 -250.698)
		(width 0.17145)
		(layer "F.Cu")
		(net "SW_HDD_N2")
	)
	(segment
		(start 79.8195 -248.6025)
		(end 78.359 -248.6025)
		(width 0.17145)
		(layer "F.Cu")
		(net "SW_HDD_N2")
	)
	(segment
		(start 78.359 -248.6025)
		(end 78.359 -250.317)
		(width 0.17145)
		(layer "F.Cu")
		(net "SW_HDD_N2")
	)
	(segment
		(start 79.883 -258.318)
		(end 79.883 -256.9845)
		(width 0.17145)
		(layer "F.Cu")
		(net "SW_HDD_N2")
	)
	(segment
		(start 80.01 -248.793)
		(end 79.8195 -248.6025)
		(width 0.17145)
		(layer "F.Cu")
		(net "SW_HDD_N2")
	)
	(segment
		(start 78.4225 -254.508)
		(end 78.4225 -255.524)
		(width 0.17145)
		(layer "F.Cu")
		(net "SW_HDD_N2")
	)
	(via
		(at 78.359 -250.317)
		(size 0.6604)
		(drill 0.3302)
		(layers "F.Cu" "B.Cu")
		(net "SW_HDD_N2")
	)
	(segment
		(start 370.967 -135.509)
		(end 371.348 -135.89)
		(width 0.17145)
		(layer "F.Cu")
		(net "SW_HDD_N19")
	)
	(segment
		(start 371.348 -142.1765)
		(end 370.6495 -142.875)
		(width 0.17145)
		(layer "F.Cu")
		(net "SW_HDD_N19")
	)
	(segment
		(start 371.348 -135.89)
		(end 371.348 -142.1765)
		(width 0.17145)
		(layer "F.Cu")
		(net "SW_HDD_N19")
	)
	(segment
		(start 369.951 -133.858)
		(end 370.0145 -133.9215)
		(width 0.17145)
		(layer "F.Cu")
		(net "SW_HDD_N19")
	)
	(segment
		(start 370.205 -145.0975)
		(end 370.6495 -144.653)
		(width 0.17145)
		(layer "F.Cu")
		(net "SW_HDD_N19")
	)
	(segment
		(start 370.205 -145.542)
		(end 370.205 -145.0975)
		(width 0.17145)
		(layer "F.Cu")
		(net "SW_HDD_N19")
	)
	(segment
		(start 370.0145 -133.9215)
		(end 370.0145 -135.509)
		(width 0.17145)
		(layer "F.Cu")
		(net "SW_HDD_N19")
	)
	(segment
		(start 370.6495 -144.653)
		(end 370.6495 -143.891)
		(width 0.17145)
		(layer "F.Cu")
		(net "SW_HDD_N19")
	)
	(segment
		(start 370.6495 -142.875)
		(end 370.6495 -143.891)
		(width 0.17145)
		(layer "F.Cu")
		(net "SW_HDD_N19")
	)
	(segment
		(start 370.0145 -135.509)
		(end 370.967 -135.509)
		(width 0.17145)
		(layer "F.Cu")
		(net "SW_HDD_N19")
	)
	(via
		(at 370.967 -135.509)
		(size 0.6604)
		(drill 0.3302)
		(layers "F.Cu" "B.Cu")
		(net "SW_HDD_N19")
	)
	(segment
		(start 339.1535 -142.875)
		(end 339.1535 -143.891)
		(width 0.17145)
		(layer "F.Cu")
		(net "SW_HDD_N18")
	)
	(segment
		(start 339.471 -135.509)
		(end 339.852 -135.89)
		(width 0.17145)
		(layer "F.Cu")
		(net "SW_HDD_N18")
	)
	(segment
		(start 338.455 -133.858)
		(end 338.5185 -133.9215)
		(width 0.17145)
		(layer "F.Cu")
		(net "SW_HDD_N18")
	)
	(segment
		(start 339.852 -142.1765)
		(end 339.1535 -142.875)
		(width 0.17145)
		(layer "F.Cu")
		(net "SW_HDD_N18")
	)
	(segment
		(start 338.5185 -133.9215)
		(end 338.5185 -135.509)
		(width 0.17145)
		(layer "F.Cu")
		(net "SW_HDD_N18")
	)
	(segment
		(start 338.709 -145.0975)
		(end 339.1535 -144.653)
		(width 0.17145)
		(layer "F.Cu")
		(net "SW_HDD_N18")
	)
	(segment
		(start 338.709 -145.542)
		(end 338.709 -145.0975)
		(width 0.17145)
		(layer "F.Cu")
		(net "SW_HDD_N18")
	)
	(segment
		(start 339.852 -135.89)
		(end 339.852 -142.1765)
		(width 0.17145)
		(layer "F.Cu")
		(net "SW_HDD_N18")
	)
	(segment
		(start 339.1535 -144.653)
		(end 339.1535 -143.891)
		(width 0.17145)
		(layer "F.Cu")
		(net "SW_HDD_N18")
	)
	(segment
		(start 338.5185 -135.509)
		(end 339.471 -135.509)
		(width 0.17145)
		(layer "F.Cu")
		(net "SW_HDD_N18")
	)
	(via
		(at 339.471 -135.509)
		(size 0.6604)
		(drill 0.3302)
		(layers "F.Cu" "B.Cu")
		(net "SW_HDD_N18")
	)
	(segment
		(start 174.498 -143.256)
		(end 174.498 -141.9225)
		(width 0.17145)
		(layer "F.Cu")
		(net "SW_HDD_N17")
	)
	(segment
		(start 174.4345 -133.5405)
		(end 172.974 -133.5405)
		(width 0.17145)
		(layer "F.Cu")
		(net "SW_HDD_N17")
	)
	(segment
		(start 172.974 -135.5725)
		(end 173.0375 -135.636)
		(width 0.17145)
		(layer "F.Cu")
		(net "SW_HDD_N17")
	)
	(segment
		(start 172.974 -133.5405)
		(end 172.974 -135.255)
		(width 0.17145)
		(layer "F.Cu")
		(net "SW_HDD_N17")
	)
	(segment
		(start 174.498 -141.9225)
		(end 173.0375 -140.462)
		(width 0.17145)
		(layer "F.Cu")
		(net "SW_HDD_N17")
	)
	(segment
		(start 173.0375 -135.636)
		(end 173.0375 -139.446)
		(width 0.17145)
		(layer "F.Cu")
		(net "SW_HDD_N17")
	)
	(segment
		(start 173.0375 -139.446)
		(end 173.0375 -140.462)
		(width 0.17145)
		(layer "F.Cu")
		(net "SW_HDD_N17")
	)
	(segment
		(start 172.974 -135.255)
		(end 172.974 -135.5725)
		(width 0.17145)
		(layer "F.Cu")
		(net "SW_HDD_N17")
	)
	(segment
		(start 174.625 -133.731)
		(end 174.4345 -133.5405)
		(width 0.17145)
		(layer "F.Cu")
		(net "SW_HDD_N17")
	)
	(via
		(at 172.974 -135.255)
		(size 0.6604)
		(drill 0.3302)
		(layers "F.Cu" "B.Cu")
		(net "SW_HDD_N17")
	)
	(segment
		(start 141.5415 -135.636)
		(end 141.5415 -139.446)
		(width 0.17145)
		(layer "F.Cu")
		(net "SW_HDD_N16")
	)
	(segment
		(start 141.478 -135.255)
		(end 141.478 -135.5725)
		(width 0.17145)
		(layer "F.Cu")
		(net "SW_HDD_N16")
	)
	(segment
		(start 143.002 -141.9225)
		(end 141.5415 -140.462)
		(width 0.17145)
		(layer "F.Cu")
		(net "SW_HDD_N16")
	)
	(segment
		(start 141.478 -133.5405)
		(end 141.478 -135.255)
		(width 0.17145)
		(layer "F.Cu")
		(net "SW_HDD_N16")
	)
	(segment
		(start 142.9385 -133.5405)
		(end 141.478 -133.5405)
		(width 0.17145)
		(layer "F.Cu")
		(net "SW_HDD_N16")
	)
	(segment
		(start 141.478 -135.5725)
		(end 141.5415 -135.636)
		(width 0.17145)
		(layer "F.Cu")
		(net "SW_HDD_N16")
	)
	(segment
		(start 141.5415 -139.446)
		(end 141.5415 -140.462)
		(width 0.17145)
		(layer "F.Cu")
		(net "SW_HDD_N16")
	)
	(segment
		(start 143.129 -133.731)
		(end 142.9385 -133.5405)
		(width 0.17145)
		(layer "F.Cu")
		(net "SW_HDD_N16")
	)
	(segment
		(start 143.002 -143.256)
		(end 143.002 -141.9225)
		(width 0.17145)
		(layer "F.Cu")
		(net "SW_HDD_N16")
	)
	(via
		(at 141.478 -135.255)
		(size 0.6604)
		(drill 0.3302)
		(layers "F.Cu" "B.Cu")
		(net "SW_HDD_N16")
	)
	(segment
		(start 111.379 -141.9225)
		(end 109.9185 -140.462)
		(width 0.17145)
		(layer "F.Cu")
		(net "SW_HDD_N15")
	)
	(segment
		(start 111.506 -133.731)
		(end 111.3155 -133.5405)
		(width 0.17145)
		(layer "F.Cu")
		(net "SW_HDD_N15")
	)
	(segment
		(start 109.855 -135.255)
		(end 109.855 -135.5725)
		(width 0.17145)
		(layer "F.Cu")
		(net "SW_HDD_N15")
	)
	(segment
		(start 109.9185 -139.446)
		(end 109.9185 -140.462)
		(width 0.17145)
		(layer "F.Cu")
		(net "SW_HDD_N15")
	)
	(segment
		(start 109.855 -133.5405)
		(end 109.855 -135.255)
		(width 0.17145)
		(layer "F.Cu")
		(net "SW_HDD_N15")
	)
	(segment
		(start 109.9185 -135.636)
		(end 109.9185 -139.446)
		(width 0.17145)
		(layer "F.Cu")
		(net "SW_HDD_N15")
	)
	(segment
		(start 111.379 -143.256)
		(end 111.379 -141.9225)
		(width 0.17145)
		(layer "F.Cu")
		(net "SW_HDD_N15")
	)
	(segment
		(start 111.3155 -133.5405)
		(end 109.855 -133.5405)
		(width 0.17145)
		(layer "F.Cu")
		(net "SW_HDD_N15")
	)
	(segment
		(start 109.855 -135.5725)
		(end 109.9185 -135.636)
		(width 0.17145)
		(layer "F.Cu")
		(net "SW_HDD_N15")
	)
	(via
		(at 109.855 -135.255)
		(size 0.6604)
		(drill 0.3302)
		(layers "F.Cu" "B.Cu")
		(net "SW_HDD_N15")
	)
	(segment
		(start 78.359 -133.5405)
		(end 78.359 -135.255)
		(width 0.17145)
		(layer "F.Cu")
		(net "SW_HDD_N14")
	)
	(segment
		(start 79.8195 -133.5405)
		(end 78.359 -133.5405)
		(width 0.17145)
		(layer "F.Cu")
		(net "SW_HDD_N14")
	)
	(segment
		(start 79.883 -143.256)
		(end 79.883 -141.9225)
		(width 0.17145)
		(layer "F.Cu")
		(net "SW_HDD_N14")
	)
	(segment
		(start 80.01 -133.731)
		(end 79.8195 -133.5405)
		(width 0.17145)
		(layer "F.Cu")
		(net "SW_HDD_N14")
	)
	(segment
		(start 79.883 -141.9225)
		(end 78.4225 -140.462)
		(width 0.17145)
		(layer "F.Cu")
		(net "SW_HDD_N14")
	)
	(segment
		(start 78.359 -135.5725)
		(end 78.4225 -135.636)
		(width 0.17145)
		(layer "F.Cu")
		(net "SW_HDD_N14")
	)
	(segment
		(start 78.4225 -139.446)
		(end 78.4225 -140.462)
		(width 0.17145)
		(layer "F.Cu")
		(net "SW_HDD_N14")
	)
	(segment
		(start 78.359 -135.255)
		(end 78.359 -135.5725)
		(width 0.17145)
		(layer "F.Cu")
		(net "SW_HDD_N14")
	)
	(segment
		(start 78.4225 -135.636)
		(end 78.4225 -139.446)
		(width 0.17145)
		(layer "F.Cu")
		(net "SW_HDD_N14")
	)
	(via
		(at 78.359 -135.255)
		(size 0.6604)
		(drill 0.3302)
		(layers "F.Cu" "B.Cu")
		(net "SW_HDD_N14")
	)
	(segment
		(start 46.736 -133.5405)
		(end 46.736 -135.255)
		(width 0.17145)
		(layer "F.Cu")
		(net "SW_HDD_N13")
	)
	(segment
		(start 46.736 -135.5725)
		(end 46.7995 -135.636)
		(width 0.17145)
		(layer "F.Cu")
		(net "SW_HDD_N13")
	)
	(segment
		(start 46.7995 -135.636)
		(end 46.7995 -139.446)
		(width 0.17145)
		(layer "F.Cu")
		(net "SW_HDD_N13")
	)
	(segment
		(start 48.26 -141.9225)
		(end 46.7995 -140.462)
		(width 0.17145)
		(layer "F.Cu")
		(net "SW_HDD_N13")
	)
	(segment
		(start 48.387 -133.731)
		(end 48.1965 -133.5405)
		(width 0.17145)
		(layer "F.Cu")
		(net "SW_HDD_N13")
	)
	(segment
		(start 48.26 -143.256)
		(end 48.26 -141.9225)
		(width 0.17145)
		(layer "F.Cu")
		(net "SW_HDD_N13")
	)
	(segment
		(start 46.7995 -139.446)
		(end 46.7995 -140.462)
		(width 0.17145)
		(layer "F.Cu")
		(net "SW_HDD_N13")
	)
	(segment
		(start 48.1965 -133.5405)
		(end 46.736 -133.5405)
		(width 0.17145)
		(layer "F.Cu")
		(net "SW_HDD_N13")
	)
	(segment
		(start 46.736 -135.255)
		(end 46.736 -135.5725)
		(width 0.17145)
		(layer "F.Cu")
		(net "SW_HDD_N13")
	)
	(via
		(at 46.736 -135.255)
		(size 0.6604)
		(drill 0.3302)
		(layers "F.Cu" "B.Cu")
		(net "SW_HDD_N13")
	)
	(segment
		(start 15.3035 -139.446)
		(end 15.3035 -140.462)
		(width 0.17145)
		(layer "F.Cu")
		(net "SW_HDD_N12")
	)
	(segment
		(start 16.891 -133.731)
		(end 16.7005 -133.5405)
		(width 0.17145)
		(layer "F.Cu")
		(net "SW_HDD_N12")
	)
	(segment
		(start 16.7005 -133.5405)
		(end 15.24 -133.5405)
		(width 0.17145)
		(layer "F.Cu")
		(net "SW_HDD_N12")
	)
	(segment
		(start 15.3035 -135.636)
		(end 15.3035 -139.446)
		(width 0.17145)
		(layer "F.Cu")
		(net "SW_HDD_N12")
	)
	(segment
		(start 15.24 -135.5725)
		(end 15.3035 -135.636)
		(width 0.17145)
		(layer "F.Cu")
		(net "SW_HDD_N12")
	)
	(segment
		(start 16.764 -141.9225)
		(end 15.3035 -140.462)
		(width 0.17145)
		(layer "F.Cu")
		(net "SW_HDD_N12")
	)
	(segment
		(start 16.764 -143.256)
		(end 16.764 -141.9225)
		(width 0.17145)
		(layer "F.Cu")
		(net "SW_HDD_N12")
	)
	(segment
		(start 15.24 -133.5405)
		(end 15.24 -135.255)
		(width 0.17145)
		(layer "F.Cu")
		(net "SW_HDD_N12")
	)
	(segment
		(start 15.24 -135.255)
		(end 15.24 -135.5725)
		(width 0.17145)
		(layer "F.Cu")
		(net "SW_HDD_N12")
	)
	(via
		(at 15.24 -135.255)
		(size 0.6604)
		(drill 0.3302)
		(layers "F.Cu" "B.Cu")
		(net "SW_HDD_N12")
	)
	(segment
		(start 470.3445 -254.508)
		(end 470.3445 -255.524)
		(width 0.17145)
		(layer "F.Cu")
		(net "SW_HDD_N11")
	)
	(segment
		(start 470.3445 -254.508)
		(end 470.3445 -253.3015)
		(width 0.17145)
		(layer "F.Cu")
		(net "SW_HDD_N11")
	)
	(segment
		(start 469.773 -252.73)
		(end 469.5825 -252.5395)
		(width 0.17145)
		(layer "F.Cu")
		(net "SW_HDD_N11")
	)
	(segment
		(start 470.789 -255.524)
		(end 470.3445 -255.524)
		(width 0.17145)
		(layer "F.Cu")
		(net "SW_HDD_N11")
	)
	(segment
		(start 470.3445 -253.3015)
		(end 469.773 -252.73)
		(width 0.17145)
		(layer "F.Cu")
		(net "SW_HDD_N11")
	)
	(segment
		(start 469.5825 -252.5395)
		(end 468.122 -252.5395)
		(width 0.17145)
		(layer "F.Cu")
		(net "SW_HDD_N11")
	)
	(segment
		(start 471.805 -256.54)
		(end 470.789 -255.524)
		(width 0.17145)
		(layer "F.Cu")
		(net "SW_HDD_N11")
	)
	(segment
		(start 471.805 -258.318)
		(end 471.805 -256.54)
		(width 0.17145)
		(layer "F.Cu")
		(net "SW_HDD_N11")
	)
	(via
		(at 471.805 -256.54)
		(size 0.6604)
		(drill 0.3302)
		(layers "F.Cu" "B.Cu")
		(net "SW_HDD_N11")
	)
	(segment
		(start 465.2645 -257.81)
		(end 465.963 -257.1115)
		(width 0.17145)
		(layer "F.Cu")
		(net "SW_HDD_N10")
	)
	(segment
		(start 465.963 -257.1115)
		(end 465.963 -250.571)
		(width 0.17145)
		(layer "F.Cu")
		(net "SW_HDD_N10")
	)
	(segment
		(start 464.6295 -248.8565)
		(end 464.6295 -250.444)
		(width 0.17145)
		(layer "F.Cu")
		(net "SW_HDD_N10")
	)
	(segment
		(start 464.82 -260.0325)
		(end 465.2645 -259.588)
		(width 0.17145)
		(layer "F.Cu")
		(net "SW_HDD_N10")
	)
	(segment
		(start 465.963 -250.571)
		(end 465.836 -250.444)
		(width 0.17145)
		(layer "F.Cu")
		(net "SW_HDD_N10")
	)
	(segment
		(start 464.566 -248.793)
		(end 464.6295 -248.8565)
		(width 0.17145)
		(layer "F.Cu")
		(net "SW_HDD_N10")
	)
	(segment
		(start 464.6295 -250.444)
		(end 465.836 -250.444)
		(width 0.17145)
		(layer "F.Cu")
		(net "SW_HDD_N10")
	)
	(segment
		(start 465.2645 -258.826)
		(end 465.2645 -257.81)
		(width 0.17145)
		(layer "F.Cu")
		(net "SW_HDD_N10")
	)
	(segment
		(start 464.82 -260.477)
		(end 464.82 -260.0325)
		(width 0.17145)
		(layer "F.Cu")
		(net "SW_HDD_N10")
	)
	(segment
		(start 465.2645 -259.588)
		(end 465.2645 -258.826)
		(width 0.17145)
		(layer "F.Cu")
		(net "SW_HDD_N10")
	)
	(via
		(at 465.836 -250.444)
		(size 0.6604)
		(drill 0.3302)
		(layers "F.Cu" "B.Cu")
		(net "SW_HDD_N10")
	)
	(segment
		(start 48.514 -248.793)
		(end 48.3235 -248.6025)
		(width 0.17145)
		(layer "F.Cu")
		(net "SW_HDD_N1")
	)
	(segment
		(start 48.387 -256.9845)
		(end 46.9265 -255.524)
		(width 0.17145)
		(layer "F.Cu")
		(net "SW_HDD_N1")
	)
	(segment
		(start 46.9265 -254.508)
		(end 46.9265 -255.524)
		(width 0.17145)
		(layer "F.Cu")
		(net "SW_HDD_N1")
	)
	(segment
		(start 46.9265 -250.698)
		(end 46.9265 -254.508)
		(width 0.17145)
		(layer "F.Cu")
		(net "SW_HDD_N1")
	)
	(segment
		(start 46.863 -248.6025)
		(end 46.863 -250.317)
		(width 0.17145)
		(layer "F.Cu")
		(net "SW_HDD_N1")
	)
	(segment
		(start 46.863 -250.6345)
		(end 46.9265 -250.698)
		(width 0.17145)
		(layer "F.Cu")
		(net "SW_HDD_N1")
	)
	(segment
		(start 46.863 -250.317)
		(end 46.863 -250.6345)
		(width 0.17145)
		(layer "F.Cu")
		(net "SW_HDD_N1")
	)
	(segment
		(start 48.3235 -248.6025)
		(end 46.863 -248.6025)
		(width 0.17145)
		(layer "F.Cu")
		(net "SW_HDD_N1")
	)
	(segment
		(start 48.387 -258.318)
		(end 48.387 -256.9845)
		(width 0.17145)
		(layer "F.Cu")
		(net "SW_HDD_N1")
	)
	(via
		(at 46.863 -250.317)
		(size 0.6604)
		(drill 0.3302)
		(layers "F.Cu" "B.Cu")
		(net "SW_HDD_N1")
	)
	(segment
		(start 430.403 -246.3165)
		(end 430.3395 -246.253)
		(width 0.17145)
		(layer "F.Cu")
		(net "SW_HDD_G9")
	)
	(segment
		(start 427.6598 -246.253)
		(end 429.133 -246.253)
		(width 0.17145)
		(layer "F.Cu")
		(net "SW_HDD_G9")
	)
	(segment
		(start 430.3395 -246.253)
		(end 429.133 -246.253)
		(width 0.17145)
		(layer "F.Cu")
		(net "SW_HDD_G9")
	)
	(via
		(at 429.133 -246.253)
		(size 0.6604)
		(drill 0.3302)
		(layers "F.Cu" "B.Cu")
		(net "SW_HDD_G9")
	)
	(segment
		(start 398.907 -246.3165)
		(end 398.8435 -246.253)
		(width 0.17145)
		(layer "F.Cu")
		(net "SW_HDD_G8")
	)
	(segment
		(start 396.1638 -246.253)
		(end 397.637 -246.253)
		(width 0.17145)
		(layer "F.Cu")
		(net "SW_HDD_G8")
	)
	(segment
		(start 398.8435 -246.253)
		(end 397.637 -246.253)
		(width 0.17145)
		(layer "F.Cu")
		(net "SW_HDD_G8")
	)
	(via
		(at 397.637 -246.253)
		(size 0.6604)
		(drill 0.3302)
		(layers "F.Cu" "B.Cu")
		(net "SW_HDD_G8")
	)
	(segment
		(start 364.5408 -246.253)
		(end 366.014 -246.253)
		(width 0.17145)
		(layer "F.Cu")
		(net "SW_HDD_G7")
	)
	(segment
		(start 367.2205 -246.253)
		(end 366.014 -246.253)
		(width 0.17145)
		(layer "F.Cu")
		(net "SW_HDD_G7")
	)
	(segment
		(start 367.284 -246.3165)
		(end 367.2205 -246.253)
		(width 0.17145)
		(layer "F.Cu")
		(net "SW_HDD_G7")
	)
	(via
		(at 366.014 -246.253)
		(size 0.6604)
		(drill 0.3302)
		(layers "F.Cu" "B.Cu")
		(net "SW_HDD_G7")
	)
	(segment
		(start 335.7245 -246.253)
		(end 334.518 -246.253)
		(width 0.17145)
		(layer "F.Cu")
		(net "SW_HDD_G6")
	)
	(segment
		(start 333.0448 -246.253)
		(end 334.518 -246.253)
		(width 0.17145)
		(layer "F.Cu")
		(net "SW_HDD_G6")
	)
	(segment
		(start 335.788 -246.3165)
		(end 335.7245 -246.253)
		(width 0.17145)
		(layer "F.Cu")
		(net "SW_HDD_G6")
	)
	(via
		(at 334.518 -246.253)
		(size 0.6604)
		(drill 0.3302)
		(layers "F.Cu" "B.Cu")
		(net "SW_HDD_G6")
	)
	(segment
		(start 178.181 -248.6152)
		(end 178.181 -247.8913)
		(width 0.17145)
		(layer "F.Cu")
		(net "SW_HDD_G5")
	)
	(segment
		(start 178.181 -247.8913)
		(end 177.3682 -247.0785)
		(width 0.17145)
		(layer "F.Cu")
		(net "SW_HDD_G5")
	)
	(segment
		(start 177.3682 -247.0785)
		(end 176.149 -247.0785)
		(width 0.17145)
		(layer "F.Cu")
		(net "SW_HDD_G5")
	)
	(via
		(at 177.3682 -247.0785)
		(size 0.6604)
		(drill 0.3302)
		(layers "F.Cu" "B.Cu")
		(net "SW_HDD_G5")
	)
	(segment
		(start 146.685 -247.8913)
		(end 145.8722 -247.0785)
		(width 0.17145)
		(layer "F.Cu")
		(net "SW_HDD_G4")
	)
	(segment
		(start 146.685 -248.6152)
		(end 146.685 -247.8913)
		(width 0.17145)
		(layer "F.Cu")
		(net "SW_HDD_G4")
	)
	(segment
		(start 145.8722 -247.0785)
		(end 144.653 -247.0785)
		(width 0.17145)
		(layer "F.Cu")
		(net "SW_HDD_G4")
	)
	(via
		(at 145.8722 -247.0785)
		(size 0.6604)
		(drill 0.3302)
		(layers "F.Cu" "B.Cu")
		(net "SW_HDD_G4")
	)
	(segment
		(start 476.885 -6.4135)
		(end 477.1644 -6.1341)
		(width 0.17145)
		(layer "F.Cu")
		(net "SW_HDD_G35")
	)
	(segment
		(start 476.2246 -6.4135)
		(end 476.885 -6.4135)
		(width 0.17145)
		(layer "F.Cu")
		(net "SW_HDD_G35")
	)
	(segment
		(start 478.409 -6.477)
		(end 478.0661 -6.1341)
		(width 0.17145)
		(layer "F.Cu")
		(net "SW_HDD_G35")
	)
	(segment
		(start 478.0661 -6.1341)
		(end 477.1644 -6.1341)
		(width 0.17145)
		(layer "F.Cu")
		(net "SW_HDD_G35")
	)
	(segment
		(start 478.409 -7.4422)
		(end 478.409 -6.477)
		(width 0.17145)
		(layer "F.Cu")
		(net "SW_HDD_G35")
	)
	(via
		(at 477.1644 -6.1341)
		(size 0.6604)
		(drill 0.3302)
		(layers "F.Cu" "B.Cu")
		(net "SW_HDD_G35")
	)
	(segment
		(start 461.264 -18.4658)
		(end 461.8736 -18.4658)
		(width 0.17145)
		(layer "F.Cu")
		(net "SW_HDD_G34")
	)
	(segment
		(start 462.896712 -20.558506)
		(end 462.896712 -19.6088)
		(width 0.17145)
		(layer "F.Cu")
		(net "SW_HDD_G34")
	)
	(segment
		(start 461.8736 -18.4658)
		(end 462.896712 -19.488912)
		(width 0.17145)
		(layer "F.Cu")
		(net "SW_HDD_G34")
	)
	(segment
		(start 462.896712 -19.488912)
		(end 462.896712 -19.6088)
		(width 0.17145)
		(layer "F.Cu")
		(net "SW_HDD_G34")
	)
	(via
		(at 462.896712 -19.6088)
		(size 0.6604)
		(drill 0.3302)
		(layers "F.Cu" "B.Cu")
		(net "SW_HDD_G34")
	)
	(segment
		(start 427.6598 -16.256)
		(end 429.133 -16.256)
		(width 0.17145)
		(layer "F.Cu")
		(net "SW_HDD_G33")
	)
	(segment
		(start 430.403 -16.3195)
		(end 430.3395 -16.256)
		(width 0.17145)
		(layer "F.Cu")
		(net "SW_HDD_G33")
	)
	(segment
		(start 430.3395 -16.256)
		(end 429.133 -16.256)
		(width 0.17145)
		(layer "F.Cu")
		(net "SW_HDD_G33")
	)
	(via
		(at 429.133 -16.256)
		(size 0.6604)
		(drill 0.3302)
		(layers "F.Cu" "B.Cu")
		(net "SW_HDD_G33")
	)
	(segment
		(start 398.0815 -12.827)
		(end 396.875 -12.827)
		(width 0.17145)
		(layer "F.Cu")
		(net "SW_HDD_G32")
	)
	(segment
		(start 398.145 -12.8905)
		(end 398.0815 -12.827)
		(width 0.17145)
		(layer "F.Cu")
		(net "SW_HDD_G32")
	)
	(segment
		(start 395.4018 -12.827)
		(end 396.875 -12.827)
		(width 0.17145)
		(layer "F.Cu")
		(net "SW_HDD_G32")
	)
	(via
		(at 396.875 -12.827)
		(size 0.6604)
		(drill 0.3302)
		(layers "F.Cu" "B.Cu")
		(net "SW_HDD_G32")
	)
	(segment
		(start 367.284 -16.3195)
		(end 367.2205 -16.256)
		(width 0.17145)
		(layer "F.Cu")
		(net "SW_HDD_G31")
	)
	(segment
		(start 367.2205 -16.256)
		(end 366.014 -16.256)
		(width 0.17145)
		(layer "F.Cu")
		(net "SW_HDD_G31")
	)
	(segment
		(start 364.5408 -16.256)
		(end 366.014 -16.256)
		(width 0.17145)
		(layer "F.Cu")
		(net "SW_HDD_G31")
	)
	(via
		(at 366.014 -16.256)
		(size 0.6604)
		(drill 0.3302)
		(layers "F.Cu" "B.Cu")
		(net "SW_HDD_G31")
	)
	(segment
		(start 332.0288 -12.827)
		(end 333.6671 -12.827)
		(width 0.17145)
		(layer "F.Cu")
		(net "SW_HDD_G30")
	)
	(segment
		(start 333.6671 -12.827)
		(end 333.6798 -12.8397)
		(width 0.17145)
		(layer "F.Cu")
		(net "SW_HDD_G30")
	)
	(segment
		(start 114.2492 -247.0785)
		(end 113.03 -247.0785)
		(width 0.17145)
		(layer "F.Cu")
		(net "SW_HDD_G3")
	)
	(segment
		(start 115.062 -247.8913)
		(end 114.2492 -247.0785)
		(width 0.17145)
		(layer "F.Cu")
		(net "SW_HDD_G3")
	)
	(segment
		(start 115.062 -248.6152)
		(end 115.062 -247.8913)
		(width 0.17145)
		(layer "F.Cu")
		(net "SW_HDD_G3")
	)
	(via
		(at 114.2492 -247.0785)
		(size 0.6604)
		(drill 0.3302)
		(layers "F.Cu" "B.Cu")
		(net "SW_HDD_G3")
	)
	(segment
		(start 178.8668 -15.1638)
		(end 179.451 -14.5796)
		(width 0.17145)
		(layer "F.Cu")
		(net "SW_HDD_G29")
	)
	(segment
		(start 179.451 -14.5796)
		(end 179.815998 -14.5796)
		(width 0.17145)
		(layer "F.Cu")
		(net "SW_HDD_G29")
	)
	(segment
		(start 179.197 -16.637)
		(end 178.8668 -16.3068)
		(width 0.17145)
		(layer "F.Cu")
		(net "SW_HDD_G29")
	)
	(segment
		(start 179.815998 -14.5796)
		(end 180.9115 -14.5796)
		(width 0.17145)
		(layer "F.Cu")
		(net "SW_HDD_G29")
	)
	(segment
		(start 179.7558 -16.637)
		(end 179.197 -16.637)
		(width 0.17145)
		(layer "F.Cu")
		(net "SW_HDD_G29")
	)
	(segment
		(start 178.8668 -16.3068)
		(end 178.8668 -15.1638)
		(width 0.17145)
		(layer "F.Cu")
		(net "SW_HDD_G29")
	)
	(via
		(at 179.815998 -14.5796)
		(size 0.6604)
		(drill 0.3302)
		(layers "F.Cu" "B.Cu")
		(net "SW_HDD_G29")
	)
	(segment
		(start 146.685 -18.6182)
		(end 146.685 -17.8943)
		(width 0.17145)
		(layer "F.Cu")
		(net "SW_HDD_G28")
	)
	(segment
		(start 145.8722 -17.0815)
		(end 144.653 -17.0815)
		(width 0.17145)
		(layer "F.Cu")
		(net "SW_HDD_G28")
	)
	(segment
		(start 146.685 -17.8943)
		(end 145.8722 -17.0815)
		(width 0.17145)
		(layer "F.Cu")
		(net "SW_HDD_G28")
	)
	(via
		(at 145.8722 -17.0815)
		(size 0.6604)
		(drill 0.3302)
		(layers "F.Cu" "B.Cu")
		(net "SW_HDD_G28")
	)
	(segment
		(start 116.586 -14.605)
		(end 117.7925 -14.605)
		(width 0.17145)
		(layer "F.Cu")
		(net "SW_HDD_G27")
	)
	(segment
		(start 115.697 -16.637)
		(end 115.3414 -16.2814)
		(width 0.17145)
		(layer "F.Cu")
		(net "SW_HDD_G27")
	)
	(segment
		(start 115.3414 -15.113)
		(end 115.8494 -14.605)
		(width 0.17145)
		(layer "F.Cu")
		(net "SW_HDD_G27")
	)
	(segment
		(start 116.2558 -16.637)
		(end 115.697 -16.637)
		(width 0.17145)
		(layer "F.Cu")
		(net "SW_HDD_G27")
	)
	(segment
		(start 115.3414 -16.2814)
		(end 115.3414 -15.113)
		(width 0.17145)
		(layer "F.Cu")
		(net "SW_HDD_G27")
	)
	(segment
		(start 115.8494 -14.605)
		(end 116.586 -14.605)
		(width 0.17145)
		(layer "F.Cu")
		(net "SW_HDD_G27")
	)
	(via
		(at 116.586 -14.605)
		(size 0.6604)
		(drill 0.3302)
		(layers "F.Cu" "B.Cu")
		(net "SW_HDD_G27")
	)
	(segment
		(start 82.7532 -17.0815)
		(end 81.534 -17.0815)
		(width 0.17145)
		(layer "F.Cu")
		(net "SW_HDD_G26")
	)
	(segment
		(start 83.566 -18.6182)
		(end 83.566 -17.8943)
		(width 0.17145)
		(layer "F.Cu")
		(net "SW_HDD_G26")
	)
	(segment
		(start 83.566 -17.8943)
		(end 82.7532 -17.0815)
		(width 0.17145)
		(layer "F.Cu")
		(net "SW_HDD_G26")
	)
	(via
		(at 82.7532 -17.0815)
		(size 0.6604)
		(drill 0.3302)
		(layers "F.Cu" "B.Cu")
		(net "SW_HDD_G26")
	)
	(segment
		(start 52.959 -16.637)
		(end 52.6034 -16.2814)
		(width 0.17145)
		(layer "F.Cu")
		(net "SW_HDD_G25")
	)
	(segment
		(start 53.594 -14.5796)
		(end 54.5719 -14.5796)
		(width 0.17145)
		(layer "F.Cu")
		(net "SW_HDD_G25")
	)
	(segment
		(start 52.6034 -14.859)
		(end 52.8828 -14.5796)
		(width 0.17145)
		(layer "F.Cu")
		(net "SW_HDD_G25")
	)
	(segment
		(start 53.5178 -16.637)
		(end 52.959 -16.637)
		(width 0.17145)
		(layer "F.Cu")
		(net "SW_HDD_G25")
	)
	(segment
		(start 52.6034 -16.2814)
		(end 52.6034 -14.859)
		(width 0.17145)
		(layer "F.Cu")
		(net "SW_HDD_G25")
	)
	(segment
		(start 52.8828 -14.5796)
		(end 53.594 -14.5796)
		(width 0.17145)
		(layer "F.Cu")
		(net "SW_HDD_G25")
	)
	(via
		(at 53.594 -14.5796)
		(size 0.6604)
		(drill 0.3302)
		(layers "F.Cu" "B.Cu")
		(net "SW_HDD_G25")
	)
	(segment
		(start 19.6342 -17.0815)
		(end 18.415 -17.0815)
		(width 0.17145)
		(layer "F.Cu")
		(net "SW_HDD_G24")
	)
	(segment
		(start 20.447 -18.6182)
		(end 20.447 -17.8943)
		(width 0.17145)
		(layer "F.Cu")
		(net "SW_HDD_G24")
	)
	(segment
		(start 20.447 -17.8943)
		(end 19.6342 -17.0815)
		(width 0.17145)
		(layer "F.Cu")
		(net "SW_HDD_G24")
	)
	(via
		(at 19.6342 -17.0815)
		(size 0.6604)
		(drill 0.3302)
		(layers "F.Cu" "B.Cu")
		(net "SW_HDD_G24")
	)
	(segment
		(start 470.7255 -132.6388)
		(end 470.7255 -133.858)
		(width 0.17145)
		(layer "F.Cu")
		(net "SW_HDD_G23")
	)
	(segment
		(start 472.2622 -131.826)
		(end 471.5383 -131.826)
		(width 0.17145)
		(layer "F.Cu")
		(net "SW_HDD_G23")
	)
	(segment
		(start 471.5383 -131.826)
		(end 470.7255 -132.6388)
		(width 0.17145)
		(layer "F.Cu")
		(net "SW_HDD_G23")
	)
	(via
		(at 470.7255 -132.6388)
		(size 0.6604)
		(drill 0.3302)
		(layers "F.Cu" "B.Cu")
		(net "SW_HDD_G23")
	)
	(segment
		(start 461.899 -131.3815)
		(end 461.8355 -131.318)
		(width 0.17145)
		(layer "F.Cu")
		(net "SW_HDD_G22")
	)
	(segment
		(start 461.8355 -131.318)
		(end 460.629 -131.318)
		(width 0.17145)
		(layer "F.Cu")
		(net "SW_HDD_G22")
	)
	(segment
		(start 459.1558 -131.318)
		(end 460.629 -131.318)
		(width 0.17145)
		(layer "F.Cu")
		(net "SW_HDD_G22")
	)
	(via
		(at 460.629 -131.318)
		(size 0.6604)
		(drill 0.3302)
		(layers "F.Cu" "B.Cu")
		(net "SW_HDD_G22")
	)
	(segment
		(start 430.403 -131.3815)
		(end 430.3395 -131.318)
		(width 0.17145)
		(layer "F.Cu")
		(net "SW_HDD_G21")
	)
	(segment
		(start 430.3395 -131.318)
		(end 429.133 -131.318)
		(width 0.17145)
		(layer "F.Cu")
		(net "SW_HDD_G21")
	)
	(segment
		(start 427.6598 -131.318)
		(end 429.133 -131.318)
		(width 0.17145)
		(layer "F.Cu")
		(net "SW_HDD_G21")
	)
	(via
		(at 429.133 -131.318)
		(size 0.6604)
		(drill 0.3302)
		(layers "F.Cu" "B.Cu")
		(net "SW_HDD_G21")
	)
	(segment
		(start 398.8435 -131.318)
		(end 397.637 -131.318)
		(width 0.17145)
		(layer "F.Cu")
		(net "SW_HDD_G20")
	)
	(segment
		(start 398.907 -131.3815)
		(end 398.8435 -131.318)
		(width 0.17145)
		(layer "F.Cu")
		(net "SW_HDD_G20")
	)
	(segment
		(start 396.1638 -131.318)
		(end 397.637 -131.318)
		(width 0.17145)
		(layer "F.Cu")
		(net "SW_HDD_G20")
	)
	(via
		(at 397.637 -131.318)
		(size 0.6604)
		(drill 0.3302)
		(layers "F.Cu" "B.Cu")
		(net "SW_HDD_G20")
	)
	(segment
		(start 83.566 -248.6152)
		(end 83.566 -247.8913)
		(width 0.17145)
		(layer "F.Cu")
		(net "SW_HDD_G2")
	)
	(segment
		(start 82.7532 -247.0785)
		(end 81.534 -247.0785)
		(width 0.17145)
		(layer "F.Cu")
		(net "SW_HDD_G2")
	)
	(segment
		(start 83.566 -247.8913)
		(end 82.7532 -247.0785)
		(width 0.17145)
		(layer "F.Cu")
		(net "SW_HDD_G2")
	)
	(via
		(at 82.7532 -247.0785)
		(size 0.6604)
		(drill 0.3302)
		(layers "F.Cu" "B.Cu")
		(net "SW_HDD_G2")
	)
	(segment
		(start 367.2205 -131.318)
		(end 366.014 -131.318)
		(width 0.17145)
		(layer "F.Cu")
		(net "SW_HDD_G19")
	)
	(segment
		(start 367.284 -131.3815)
		(end 367.2205 -131.318)
		(width 0.17145)
		(layer "F.Cu")
		(net "SW_HDD_G19")
	)
	(segment
		(start 364.5408 -131.318)
		(end 366.014 -131.318)
		(width 0.17145)
		(layer "F.Cu")
		(net "SW_HDD_G19")
	)
	(via
		(at 366.014 -131.318)
		(size 0.6604)
		(drill 0.3302)
		(layers "F.Cu" "B.Cu")
		(net "SW_HDD_G19")
	)
	(segment
		(start 335.7245 -131.318)
		(end 334.518 -131.318)
		(width 0.17145)
		(layer "F.Cu")
		(net "SW_HDD_G18")
	)
	(segment
		(start 335.788 -131.3815)
		(end 335.7245 -131.318)
		(width 0.17145)
		(layer "F.Cu")
		(net "SW_HDD_G18")
	)
	(segment
		(start 333.0448 -131.318)
		(end 334.518 -131.318)
		(width 0.17145)
		(layer "F.Cu")
		(net "SW_HDD_G18")
	)
	(via
		(at 334.518 -131.318)
		(size 0.6604)
		(drill 0.3302)
		(layers "F.Cu" "B.Cu")
		(net "SW_HDD_G18")
	)
	(segment
		(start 178.181 -133.5532)
		(end 178.181 -132.8293)
		(width 0.17145)
		(layer "F.Cu")
		(net "SW_HDD_G17")
	)
	(segment
		(start 178.181 -132.8293)
		(end 177.3682 -132.0165)
		(width 0.17145)
		(layer "F.Cu")
		(net "SW_HDD_G17")
	)
	(segment
		(start 177.3682 -132.0165)
		(end 176.149 -132.0165)
		(width 0.17145)
		(layer "F.Cu")
		(net "SW_HDD_G17")
	)
	(via
		(at 177.3682 -132.0165)
		(size 0.6604)
		(drill 0.3302)
		(layers "F.Cu" "B.Cu")
		(net "SW_HDD_G17")
	)
	(segment
		(start 145.8722 -132.0165)
		(end 144.653 -132.0165)
		(width 0.17145)
		(layer "F.Cu")
		(net "SW_HDD_G16")
	)
	(segment
		(start 146.685 -133.5532)
		(end 146.685 -132.8293)
		(width 0.17145)
		(layer "F.Cu")
		(net "SW_HDD_G16")
	)
	(segment
		(start 146.685 -132.8293)
		(end 145.8722 -132.0165)
		(width 0.17145)
		(layer "F.Cu")
		(net "SW_HDD_G16")
	)
	(via
		(at 145.8722 -132.0165)
		(size 0.6604)
		(drill 0.3302)
		(layers "F.Cu" "B.Cu")
		(net "SW_HDD_G16")
	)
	(segment
		(start 114.2492 -132.0165)
		(end 113.03 -132.0165)
		(width 0.17145)
		(layer "F.Cu")
		(net "SW_HDD_G15")
	)
	(segment
		(start 115.062 -132.8293)
		(end 114.2492 -132.0165)
		(width 0.17145)
		(layer "F.Cu")
		(net "SW_HDD_G15")
	)
	(segment
		(start 115.062 -133.5532)
		(end 115.062 -132.8293)
		(width 0.17145)
		(layer "F.Cu")
		(net "SW_HDD_G15")
	)
	(via
		(at 114.2492 -132.0165)
		(size 0.6604)
		(drill 0.3302)
		(layers "F.Cu" "B.Cu")
		(net "SW_HDD_G15")
	)
	(segment
		(start 83.566 -132.8293)
		(end 82.7532 -132.0165)
		(width 0.17145)
		(layer "F.Cu")
		(net "SW_HDD_G14")
	)
	(segment
		(start 83.566 -133.5532)
		(end 83.566 -132.8293)
		(width 0.17145)
		(layer "F.Cu")
		(net "SW_HDD_G14")
	)
	(segment
		(start 82.7532 -132.0165)
		(end 81.534 -132.0165)
		(width 0.17145)
		(layer "F.Cu")
		(net "SW_HDD_G14")
	)
	(via
		(at 82.7532 -132.0165)
		(size 0.6604)
		(drill 0.3302)
		(layers "F.Cu" "B.Cu")
		(net "SW_HDD_G14")
	)
	(segment
		(start 51.943 -132.8293)
		(end 51.1302 -132.0165)
		(width 0.17145)
		(layer "F.Cu")
		(net "SW_HDD_G13")
	)
	(segment
		(start 51.1302 -132.0165)
		(end 49.911 -132.0165)
		(width 0.17145)
		(layer "F.Cu")
		(net "SW_HDD_G13")
	)
	(segment
		(start 51.943 -133.5532)
		(end 51.943 -132.8293)
		(width 0.17145)
		(layer "F.Cu")
		(net "SW_HDD_G13")
	)
	(via
		(at 51.1302 -132.0165)
		(size 0.6604)
		(drill 0.3302)
		(layers "F.Cu" "B.Cu")
		(net "SW_HDD_G13")
	)
	(segment
		(start 19.6342 -132.0165)
		(end 18.415 -132.0165)
		(width 0.17145)
		(layer "F.Cu")
		(net "SW_HDD_G12")
	)
	(segment
		(start 20.447 -133.5532)
		(end 20.447 -132.8293)
		(width 0.17145)
		(layer "F.Cu")
		(net "SW_HDD_G12")
	)
	(segment
		(start 20.447 -132.8293)
		(end 19.6342 -132.0165)
		(width 0.17145)
		(layer "F.Cu")
		(net "SW_HDD_G12")
	)
	(via
		(at 19.6342 -132.0165)
		(size 0.6604)
		(drill 0.3302)
		(layers "F.Cu" "B.Cu")
		(net "SW_HDD_G12")
	)
	(segment
		(start 471.5383 -246.888)
		(end 470.7255 -247.7008)
		(width 0.17145)
		(layer "F.Cu")
		(net "SW_HDD_G11")
	)
	(segment
		(start 470.7255 -247.7008)
		(end 470.7255 -248.92)
		(width 0.17145)
		(layer "F.Cu")
		(net "SW_HDD_G11")
	)
	(segment
		(start 472.2622 -246.888)
		(end 471.5383 -246.888)
		(width 0.17145)
		(layer "F.Cu")
		(net "SW_HDD_G11")
	)
	(via
		(at 470.7255 -247.7008)
		(size 0.6604)
		(drill 0.3302)
		(layers "F.Cu" "B.Cu")
		(net "SW_HDD_G11")
	)
	(segment
		(start 459.1558 -246.253)
		(end 460.629 -246.253)
		(width 0.17145)
		(layer "F.Cu")
		(net "SW_HDD_G10")
	)
	(segment
		(start 461.8355 -246.253)
		(end 460.629 -246.253)
		(width 0.17145)
		(layer "F.Cu")
		(net "SW_HDD_G10")
	)
	(segment
		(start 461.899 -246.3165)
		(end 461.8355 -246.253)
		(width 0.17145)
		(layer "F.Cu")
		(net "SW_HDD_G10")
	)
	(via
		(at 460.629 -246.253)
		(size 0.6604)
		(drill 0.3302)
		(layers "F.Cu" "B.Cu")
		(net "SW_HDD_G10")
	)
	(segment
		(start 51.2572 -247.0785)
		(end 50.038 -247.0785)
		(width 0.17145)
		(layer "F.Cu")
		(net "SW_HDD_G1")
	)
	(segment
		(start 52.07 -248.6152)
		(end 52.07 -247.8913)
		(width 0.17145)
		(layer "F.Cu")
		(net "SW_HDD_G1")
	)
	(segment
		(start 52.07 -247.8913)
		(end 51.2572 -247.0785)
		(width 0.17145)
		(layer "F.Cu")
		(net "SW_HDD_G1")
	)
	(via
		(at 51.2572 -247.0785)
		(size 0.6604)
		(drill 0.3302)
		(layers "F.Cu" "B.Cu")
		(net "SW_HDD_G1")
	)
	(segment
		(start 417.082224 -244.794024)
		(end 420.436548 -244.794024)
		(width 0.127)
		(layer "F.Cu")
		(net "SAS_HDD_RX_P9")
	)
	(segment
		(start 416.564064 -244.660674)
		(end 416.948874 -244.660674)
		(width 0.127)
		(layer "F.Cu")
		(net "SAS_HDD_RX_P9")
	)
	(segment
		(start 420.563548 -244.432074)
		(end 420.690548 -244.305074)
		(width 0.127)
		(layer "F.Cu")
		(net "SAS_HDD_RX_P9")
	)
	(segment
		(start 420.436548 -244.794024)
		(end 420.563548 -244.667024)
		(width 0.127)
		(layer "F.Cu")
		(net "SAS_HDD_RX_P9")
	)
	(segment
		(start 420.563548 -244.667024)
		(end 420.563548 -244.432074)
		(width 0.127)
		(layer "F.Cu")
		(net "SAS_HDD_RX_P9")
	)
	(segment
		(start 420.690548 -244.305074)
		(end 422.025064 -244.305074)
		(width 0.127)
		(layer "F.Cu")
		(net "SAS_HDD_RX_P9")
	)
	(segment
		(start 416.948874 -244.660674)
		(end 417.082224 -244.794024)
		(width 0.127)
		(layer "F.Cu")
		(net "SAS_HDD_RX_P9")
	)
	(segment
		(start 385.013962 -244.660674)
		(end 385.402074 -244.660674)
		(width 0.127)
		(layer "F.Cu")
		(net "SAS_HDD_RX_P8")
	)
	(segment
		(start 389.140446 -244.305074)
		(end 390.474962 -244.305074)
		(width 0.127)
		(layer "F.Cu")
		(net "SAS_HDD_RX_P8")
	)
	(segment
		(start 389.013446 -244.667024)
		(end 389.013446 -244.432074)
		(width 0.127)
		(layer "F.Cu")
		(net "SAS_HDD_RX_P8")
	)
	(segment
		(start 385.402074 -244.660674)
		(end 385.535424 -244.794024)
		(width 0.127)
		(layer "F.Cu")
		(net "SAS_HDD_RX_P8")
	)
	(segment
		(start 388.886446 -244.794024)
		(end 389.013446 -244.667024)
		(width 0.127)
		(layer "F.Cu")
		(net "SAS_HDD_RX_P8")
	)
	(segment
		(start 385.535424 -244.794024)
		(end 388.886446 -244.794024)
		(width 0.127)
		(layer "F.Cu")
		(net "SAS_HDD_RX_P8")
	)
	(segment
		(start 389.013446 -244.432074)
		(end 389.140446 -244.305074)
		(width 0.127)
		(layer "F.Cu")
		(net "SAS_HDD_RX_P8")
	)
	(segment
		(start 357.336598 -244.794024)
		(end 357.463598 -244.667024)
		(width 0.127)
		(layer "F.Cu")
		(net "SAS_HDD_RX_P7")
	)
	(segment
		(start 353.464114 -244.660674)
		(end 353.829874 -244.660674)
		(width 0.127)
		(layer "F.Cu")
		(net "SAS_HDD_RX_P7")
	)
	(segment
		(start 357.590598 -244.305074)
		(end 358.925114 -244.305074)
		(width 0.127)
		(layer "F.Cu")
		(net "SAS_HDD_RX_P7")
	)
	(segment
		(start 357.463598 -244.667024)
		(end 357.463598 -244.432074)
		(width 0.127)
		(layer "F.Cu")
		(net "SAS_HDD_RX_P7")
	)
	(segment
		(start 353.963224 -244.794024)
		(end 357.336598 -244.794024)
		(width 0.127)
		(layer "F.Cu")
		(net "SAS_HDD_RX_P7")
	)
	(segment
		(start 357.463598 -244.432074)
		(end 357.590598 -244.305074)
		(width 0.127)
		(layer "F.Cu")
		(net "SAS_HDD_RX_P7")
	)
	(segment
		(start 353.829874 -244.660674)
		(end 353.963224 -244.794024)
		(width 0.127)
		(layer "F.Cu")
		(net "SAS_HDD_RX_P7")
	)
	(segment
		(start 322.467224 -244.794024)
		(end 325.786496 -244.794024)
		(width 0.127)
		(layer "F.Cu")
		(net "SAS_HDD_RX_P6")
	)
	(segment
		(start 321.914012 -244.660674)
		(end 322.333874 -244.660674)
		(width 0.127)
		(layer "F.Cu")
		(net "SAS_HDD_RX_P6")
	)
	(segment
		(start 322.333874 -244.660674)
		(end 322.467224 -244.794024)
		(width 0.127)
		(layer "F.Cu")
		(net "SAS_HDD_RX_P6")
	)
	(segment
		(start 325.913496 -244.432074)
		(end 326.040496 -244.305074)
		(width 0.127)
		(layer "F.Cu")
		(net "SAS_HDD_RX_P6")
	)
	(segment
		(start 325.786496 -244.794024)
		(end 325.913496 -244.667024)
		(width 0.127)
		(layer "F.Cu")
		(net "SAS_HDD_RX_P6")
	)
	(segment
		(start 326.040496 -244.305074)
		(end 327.375012 -244.305074)
		(width 0.127)
		(layer "F.Cu")
		(net "SAS_HDD_RX_P6")
	)
	(segment
		(start 325.913496 -244.667024)
		(end 325.913496 -244.432074)
		(width 0.127)
		(layer "F.Cu")
		(net "SAS_HDD_RX_P6")
	)
	(segment
		(start 189.236604 -244.432074)
		(end 189.109604 -244.305074)
		(width 0.127)
		(layer "F.Cu")
		(net "SAS_HDD_RX_P5")
	)
	(segment
		(start 189.236604 -244.667024)
		(end 189.236604 -244.432074)
		(width 0.127)
		(layer "F.Cu")
		(net "SAS_HDD_RX_P5")
	)
	(segment
		(start 189.363604 -244.794024)
		(end 189.236604 -244.667024)
		(width 0.127)
		(layer "F.Cu")
		(net "SAS_HDD_RX_P5")
	)
	(segment
		(start 189.469522 -244.794024)
		(end 189.363604 -244.794024)
		(width 0.127)
		(layer "F.Cu")
		(net "SAS_HDD_RX_P5")
	)
	(segment
		(start 189.934088 -244.660674)
		(end 189.602872 -244.660674)
		(width 0.127)
		(layer "F.Cu")
		(net "SAS_HDD_RX_P5")
	)
	(segment
		(start 189.602872 -244.660674)
		(end 189.469522 -244.794024)
		(width 0.127)
		(layer "F.Cu")
		(net "SAS_HDD_RX_P5")
	)
	(segment
		(start 189.109604 -244.305074)
		(end 187.775088 -244.305074)
		(width 0.127)
		(layer "F.Cu")
		(net "SAS_HDD_RX_P5")
	)
	(segment
		(start 158.05277 -244.660674)
		(end 157.91942 -244.794024)
		(width 0.127)
		(layer "F.Cu")
		(net "SAS_HDD_RX_P4")
	)
	(segment
		(start 157.813502 -244.794024)
		(end 157.686502 -244.667024)
		(width 0.127)
		(layer "F.Cu")
		(net "SAS_HDD_RX_P4")
	)
	(segment
		(start 157.686502 -244.432074)
		(end 157.559502 -244.305074)
		(width 0.127)
		(layer "F.Cu")
		(net "SAS_HDD_RX_P4")
	)
	(segment
		(start 157.91942 -244.794024)
		(end 157.813502 -244.794024)
		(width 0.127)
		(layer "F.Cu")
		(net "SAS_HDD_RX_P4")
	)
	(segment
		(start 157.559502 -244.305074)
		(end 156.224986 -244.305074)
		(width 0.127)
		(layer "F.Cu")
		(net "SAS_HDD_RX_P4")
	)
	(segment
		(start 158.383986 -244.660674)
		(end 158.05277 -244.660674)
		(width 0.127)
		(layer "F.Cu")
		(net "SAS_HDD_RX_P4")
	)
	(segment
		(start 157.686502 -244.667024)
		(end 157.686502 -244.432074)
		(width 0.127)
		(layer "F.Cu")
		(net "SAS_HDD_RX_P4")
	)
	(segment
		(start 480.205288 -14.793976)
		(end 483.536498 -14.793976)
		(width 0.127)
		(layer "F.Cu")
		(net "SAS_HDD_RX_P35")
	)
	(segment
		(start 483.663498 -14.666976)
		(end 483.663498 -14.432026)
		(width 0.127)
		(layer "F.Cu")
		(net "SAS_HDD_RX_P35")
	)
	(segment
		(start 483.536498 -14.793976)
		(end 483.663498 -14.666976)
		(width 0.127)
		(layer "F.Cu")
		(net "SAS_HDD_RX_P35")
	)
	(segment
		(start 483.790498 -14.305026)
		(end 485.125014 -14.305026)
		(width 0.127)
		(layer "F.Cu")
		(net "SAS_HDD_RX_P35")
	)
	(segment
		(start 483.663498 -14.432026)
		(end 483.790498 -14.305026)
		(width 0.127)
		(layer "F.Cu")
		(net "SAS_HDD_RX_P35")
	)
	(segment
		(start 479.664014 -14.660626)
		(end 480.071938 -14.660626)
		(width 0.127)
		(layer "F.Cu")
		(net "SAS_HDD_RX_P35")
	)
	(segment
		(start 480.071938 -14.660626)
		(end 480.205288 -14.793976)
		(width 0.127)
		(layer "F.Cu")
		(net "SAS_HDD_RX_P35")
	)
	(segment
		(start 452.113396 -14.666976)
		(end 452.113396 -14.432026)
		(width 0.127)
		(layer "F.Cu")
		(net "SAS_HDD_RX_P34")
	)
	(segment
		(start 452.240396 -14.305026)
		(end 453.574912 -14.305026)
		(width 0.127)
		(layer "F.Cu")
		(net "SAS_HDD_RX_P34")
	)
	(segment
		(start 448.525138 -14.660626)
		(end 448.658488 -14.793976)
		(width 0.127)
		(layer "F.Cu")
		(net "SAS_HDD_RX_P34")
	)
	(segment
		(start 451.986396 -14.793976)
		(end 452.113396 -14.666976)
		(width 0.127)
		(layer "F.Cu")
		(net "SAS_HDD_RX_P34")
	)
	(segment
		(start 448.658488 -14.793976)
		(end 451.986396 -14.793976)
		(width 0.127)
		(layer "F.Cu")
		(net "SAS_HDD_RX_P34")
	)
	(segment
		(start 452.113396 -14.432026)
		(end 452.240396 -14.305026)
		(width 0.127)
		(layer "F.Cu")
		(net "SAS_HDD_RX_P34")
	)
	(segment
		(start 448.113912 -14.660626)
		(end 448.525138 -14.660626)
		(width 0.127)
		(layer "F.Cu")
		(net "SAS_HDD_RX_P34")
	)
	(segment
		(start 420.563548 -14.666976)
		(end 420.563548 -14.432026)
		(width 0.127)
		(layer "F.Cu")
		(net "SAS_HDD_RX_P33")
	)
	(segment
		(start 420.436548 -14.793976)
		(end 420.563548 -14.666976)
		(width 0.127)
		(layer "F.Cu")
		(net "SAS_HDD_RX_P33")
	)
	(segment
		(start 420.690548 -14.305026)
		(end 422.025064 -14.305026)
		(width 0.127)
		(layer "F.Cu")
		(net "SAS_HDD_RX_P33")
	)
	(segment
		(start 417.053776 -14.793976)
		(end 420.436548 -14.793976)
		(width 0.127)
		(layer "F.Cu")
		(net "SAS_HDD_RX_P33")
	)
	(segment
		(start 420.563548 -14.432026)
		(end 420.690548 -14.305026)
		(width 0.127)
		(layer "F.Cu")
		(net "SAS_HDD_RX_P33")
	)
	(segment
		(start 416.564064 -14.660626)
		(end 416.920426 -14.660626)
		(width 0.127)
		(layer "F.Cu")
		(net "SAS_HDD_RX_P33")
	)
	(segment
		(start 416.920426 -14.660626)
		(end 417.053776 -14.793976)
		(width 0.127)
		(layer "F.Cu")
		(net "SAS_HDD_RX_P33")
	)
	(segment
		(start 389.013446 -14.432026)
		(end 389.140446 -14.305026)
		(width 0.127)
		(layer "F.Cu")
		(net "SAS_HDD_RX_P32")
	)
	(segment
		(start 385.382008 -14.660626)
		(end 385.515358 -14.793976)
		(width 0.127)
		(layer "F.Cu")
		(net "SAS_HDD_RX_P32")
	)
	(segment
		(start 389.140446 -14.305026)
		(end 390.474962 -14.305026)
		(width 0.127)
		(layer "F.Cu")
		(net "SAS_HDD_RX_P32")
	)
	(segment
		(start 388.886446 -14.793976)
		(end 389.013446 -14.666976)
		(width 0.127)
		(layer "F.Cu")
		(net "SAS_HDD_RX_P32")
	)
	(segment
		(start 385.515358 -14.793976)
		(end 388.886446 -14.793976)
		(width 0.127)
		(layer "F.Cu")
		(net "SAS_HDD_RX_P32")
	)
	(segment
		(start 385.013962 -14.660626)
		(end 385.382008 -14.660626)
		(width 0.127)
		(layer "F.Cu")
		(net "SAS_HDD_RX_P32")
	)
	(segment
		(start 389.013446 -14.666976)
		(end 389.013446 -14.432026)
		(width 0.127)
		(layer "F.Cu")
		(net "SAS_HDD_RX_P32")
	)
	(segment
		(start 357.463598 -14.432026)
		(end 357.590598 -14.305026)
		(width 0.127)
		(layer "F.Cu")
		(net "SAS_HDD_RX_P31")
	)
	(segment
		(start 357.463598 -14.666976)
		(end 357.463598 -14.432026)
		(width 0.127)
		(layer "F.Cu")
		(net "SAS_HDD_RX_P31")
	)
	(segment
		(start 353.979988 -14.793976)
		(end 357.336598 -14.793976)
		(width 0.127)
		(layer "F.Cu")
		(net "SAS_HDD_RX_P31")
	)
	(segment
		(start 357.336598 -14.793976)
		(end 357.463598 -14.666976)
		(width 0.127)
		(layer "F.Cu")
		(net "SAS_HDD_RX_P31")
	)
	(segment
		(start 353.464114 -14.660626)
		(end 353.846638 -14.660626)
		(width 0.127)
		(layer "F.Cu")
		(net "SAS_HDD_RX_P31")
	)
	(segment
		(start 357.590598 -14.305026)
		(end 358.925114 -14.305026)
		(width 0.127)
		(layer "F.Cu")
		(net "SAS_HDD_RX_P31")
	)
	(segment
		(start 353.846638 -14.660626)
		(end 353.979988 -14.793976)
		(width 0.127)
		(layer "F.Cu")
		(net "SAS_HDD_RX_P31")
	)
	(segment
		(start 325.786496 -14.793976)
		(end 325.913496 -14.666976)
		(width 0.127)
		(layer "F.Cu")
		(net "SAS_HDD_RX_P30")
	)
	(segment
		(start 322.406772 -14.793976)
		(end 325.786496 -14.793976)
		(width 0.127)
		(layer "F.Cu")
		(net "SAS_HDD_RX_P30")
	)
	(segment
		(start 325.913496 -14.432026)
		(end 326.040496 -14.305026)
		(width 0.127)
		(layer "F.Cu")
		(net "SAS_HDD_RX_P30")
	)
	(segment
		(start 321.914012 -14.660626)
		(end 322.273422 -14.660626)
		(width 0.127)
		(layer "F.Cu")
		(net "SAS_HDD_RX_P30")
	)
	(segment
		(start 325.913496 -14.666976)
		(end 325.913496 -14.432026)
		(width 0.127)
		(layer "F.Cu")
		(net "SAS_HDD_RX_P30")
	)
	(segment
		(start 322.273422 -14.660626)
		(end 322.406772 -14.793976)
		(width 0.127)
		(layer "F.Cu")
		(net "SAS_HDD_RX_P30")
	)
	(segment
		(start 326.040496 -14.305026)
		(end 327.375012 -14.305026)
		(width 0.127)
		(layer "F.Cu")
		(net "SAS_HDD_RX_P30")
	)
	(segment
		(start 126.1364 -244.432074)
		(end 126.0094 -244.305074)
		(width 0.127)
		(layer "F.Cu")
		(net "SAS_HDD_RX_P3")
	)
	(segment
		(start 126.369318 -244.794024)
		(end 126.2634 -244.794024)
		(width 0.127)
		(layer "F.Cu")
		(net "SAS_HDD_RX_P3")
	)
	(segment
		(start 126.833884 -244.660674)
		(end 126.502668 -244.660674)
		(width 0.127)
		(layer "F.Cu")
		(net "SAS_HDD_RX_P3")
	)
	(segment
		(start 126.1364 -244.667024)
		(end 126.1364 -244.432074)
		(width 0.127)
		(layer "F.Cu")
		(net "SAS_HDD_RX_P3")
	)
	(segment
		(start 126.502668 -244.660674)
		(end 126.369318 -244.794024)
		(width 0.127)
		(layer "F.Cu")
		(net "SAS_HDD_RX_P3")
	)
	(segment
		(start 126.2634 -244.794024)
		(end 126.1364 -244.667024)
		(width 0.127)
		(layer "F.Cu")
		(net "SAS_HDD_RX_P3")
	)
	(segment
		(start 126.0094 -244.305074)
		(end 124.674884 -244.305074)
		(width 0.127)
		(layer "F.Cu")
		(net "SAS_HDD_RX_P3")
	)
	(segment
		(start 189.934088 -14.660626)
		(end 189.602872 -14.660626)
		(width 0.127)
		(layer "F.Cu")
		(net "SAS_HDD_RX_P29")
	)
	(segment
		(start 189.602872 -14.660626)
		(end 189.469522 -14.793976)
		(width 0.127)
		(layer "F.Cu")
		(net "SAS_HDD_RX_P29")
	)
	(segment
		(start 189.236604 -14.666976)
		(end 189.236604 -14.432026)
		(width 0.127)
		(layer "F.Cu")
		(net "SAS_HDD_RX_P29")
	)
	(segment
		(start 189.363604 -14.793976)
		(end 189.236604 -14.666976)
		(width 0.127)
		(layer "F.Cu")
		(net "SAS_HDD_RX_P29")
	)
	(segment
		(start 189.109604 -14.305026)
		(end 187.775088 -14.305026)
		(width 0.127)
		(layer "F.Cu")
		(net "SAS_HDD_RX_P29")
	)
	(segment
		(start 189.236604 -14.432026)
		(end 189.109604 -14.305026)
		(width 0.127)
		(layer "F.Cu")
		(net "SAS_HDD_RX_P29")
	)
	(segment
		(start 189.469522 -14.793976)
		(end 189.363604 -14.793976)
		(width 0.127)
		(layer "F.Cu")
		(net "SAS_HDD_RX_P29")
	)
	(segment
		(start 157.686502 -14.666976)
		(end 157.686502 -14.432026)
		(width 0.127)
		(layer "F.Cu")
		(net "SAS_HDD_RX_P28")
	)
	(segment
		(start 157.91942 -14.793976)
		(end 157.813502 -14.793976)
		(width 0.127)
		(layer "F.Cu")
		(net "SAS_HDD_RX_P28")
	)
	(segment
		(start 157.813502 -14.793976)
		(end 157.686502 -14.666976)
		(width 0.127)
		(layer "F.Cu")
		(net "SAS_HDD_RX_P28")
	)
	(segment
		(start 157.686502 -14.432026)
		(end 157.559502 -14.305026)
		(width 0.127)
		(layer "F.Cu")
		(net "SAS_HDD_RX_P28")
	)
	(segment
		(start 157.559502 -14.305026)
		(end 156.224986 -14.305026)
		(width 0.127)
		(layer "F.Cu")
		(net "SAS_HDD_RX_P28")
	)
	(segment
		(start 158.05277 -14.660626)
		(end 157.91942 -14.793976)
		(width 0.127)
		(layer "F.Cu")
		(net "SAS_HDD_RX_P28")
	)
	(segment
		(start 158.383986 -14.660626)
		(end 158.05277 -14.660626)
		(width 0.127)
		(layer "F.Cu")
		(net "SAS_HDD_RX_P28")
	)
	(segment
		(start 126.502668 -14.660626)
		(end 126.369318 -14.793976)
		(width 0.127)
		(layer "F.Cu")
		(net "SAS_HDD_RX_P27")
	)
	(segment
		(start 126.369318 -14.793976)
		(end 126.2634 -14.793976)
		(width 0.127)
		(layer "F.Cu")
		(net "SAS_HDD_RX_P27")
	)
	(segment
		(start 126.0094 -14.305026)
		(end 124.674884 -14.305026)
		(width 0.127)
		(layer "F.Cu")
		(net "SAS_HDD_RX_P27")
	)
	(segment
		(start 126.2634 -14.793976)
		(end 126.1364 -14.666976)
		(width 0.127)
		(layer "F.Cu")
		(net "SAS_HDD_RX_P27")
	)
	(segment
		(start 126.1364 -14.666976)
		(end 126.1364 -14.432026)
		(width 0.127)
		(layer "F.Cu")
		(net "SAS_HDD_RX_P27")
	)
	(segment
		(start 126.833884 -14.660626)
		(end 126.502668 -14.660626)
		(width 0.127)
		(layer "F.Cu")
		(net "SAS_HDD_RX_P27")
	)
	(segment
		(start 126.1364 -14.432026)
		(end 126.0094 -14.305026)
		(width 0.127)
		(layer "F.Cu")
		(net "SAS_HDD_RX_P27")
	)
	(segment
		(start 94.81947 -14.793976)
		(end 94.713552 -14.793976)
		(width 0.127)
		(layer "F.Cu")
		(net "SAS_HDD_RX_P26")
	)
	(segment
		(start 94.95282 -14.660626)
		(end 94.81947 -14.793976)
		(width 0.127)
		(layer "F.Cu")
		(net "SAS_HDD_RX_P26")
	)
	(segment
		(start 94.586552 -14.432026)
		(end 94.459552 -14.305026)
		(width 0.127)
		(layer "F.Cu")
		(net "SAS_HDD_RX_P26")
	)
	(segment
		(start 94.459552 -14.305026)
		(end 93.125036 -14.305026)
		(width 0.127)
		(layer "F.Cu")
		(net "SAS_HDD_RX_P26")
	)
	(segment
		(start 95.284036 -14.660626)
		(end 94.95282 -14.660626)
		(width 0.127)
		(layer "F.Cu")
		(net "SAS_HDD_RX_P26")
	)
	(segment
		(start 94.713552 -14.793976)
		(end 94.586552 -14.666976)
		(width 0.127)
		(layer "F.Cu")
		(net "SAS_HDD_RX_P26")
	)
	(segment
		(start 94.586552 -14.666976)
		(end 94.586552 -14.432026)
		(width 0.127)
		(layer "F.Cu")
		(net "SAS_HDD_RX_P26")
	)
	(segment
		(start 63.269368 -14.793976)
		(end 63.16345 -14.793976)
		(width 0.127)
		(layer "F.Cu")
		(net "SAS_HDD_RX_P25")
	)
	(segment
		(start 63.16345 -14.793976)
		(end 63.03645 -14.666976)
		(width 0.127)
		(layer "F.Cu")
		(net "SAS_HDD_RX_P25")
	)
	(segment
		(start 63.402718 -14.660626)
		(end 63.269368 -14.793976)
		(width 0.127)
		(layer "F.Cu")
		(net "SAS_HDD_RX_P25")
	)
	(segment
		(start 63.03645 -14.432026)
		(end 62.90945 -14.305026)
		(width 0.127)
		(layer "F.Cu")
		(net "SAS_HDD_RX_P25")
	)
	(segment
		(start 63.733934 -14.660626)
		(end 63.402718 -14.660626)
		(width 0.127)
		(layer "F.Cu")
		(net "SAS_HDD_RX_P25")
	)
	(segment
		(start 63.03645 -14.666976)
		(end 63.03645 -14.432026)
		(width 0.127)
		(layer "F.Cu")
		(net "SAS_HDD_RX_P25")
	)
	(segment
		(start 62.90945 -14.305026)
		(end 61.574934 -14.305026)
		(width 0.127)
		(layer "F.Cu")
		(net "SAS_HDD_RX_P25")
	)
	(segment
		(start 31.486602 -14.432026)
		(end 31.359602 -14.305026)
		(width 0.127)
		(layer "F.Cu")
		(net "SAS_HDD_RX_P24")
	)
	(segment
		(start 31.85287 -14.660626)
		(end 31.71952 -14.793976)
		(width 0.127)
		(layer "F.Cu")
		(net "SAS_HDD_RX_P24")
	)
	(segment
		(start 31.71952 -14.793976)
		(end 31.613602 -14.793976)
		(width 0.127)
		(layer "F.Cu")
		(net "SAS_HDD_RX_P24")
	)
	(segment
		(start 31.486602 -14.666976)
		(end 31.486602 -14.432026)
		(width 0.127)
		(layer "F.Cu")
		(net "SAS_HDD_RX_P24")
	)
	(segment
		(start 31.359602 -14.305026)
		(end 30.025086 -14.305026)
		(width 0.127)
		(layer "F.Cu")
		(net "SAS_HDD_RX_P24")
	)
	(segment
		(start 31.613602 -14.793976)
		(end 31.486602 -14.666976)
		(width 0.127)
		(layer "F.Cu")
		(net "SAS_HDD_RX_P24")
	)
	(segment
		(start 32.184086 -14.660626)
		(end 31.85287 -14.660626)
		(width 0.127)
		(layer "F.Cu")
		(net "SAS_HDD_RX_P24")
	)
	(segment
		(start 483.663498 -129.43205)
		(end 483.790498 -129.30505)
		(width 0.127)
		(layer "F.Cu")
		(net "SAS_HDD_RX_P23")
	)
	(segment
		(start 480.159568 -129.794)
		(end 483.536498 -129.794)
		(width 0.127)
		(layer "F.Cu")
		(net "SAS_HDD_RX_P23")
	)
	(segment
		(start 483.663498 -129.667)
		(end 483.663498 -129.43205)
		(width 0.127)
		(layer "F.Cu")
		(net "SAS_HDD_RX_P23")
	)
	(segment
		(start 480.026218 -129.66065)
		(end 480.159568 -129.794)
		(width 0.127)
		(layer "F.Cu")
		(net "SAS_HDD_RX_P23")
	)
	(segment
		(start 483.536498 -129.794)
		(end 483.663498 -129.667)
		(width 0.127)
		(layer "F.Cu")
		(net "SAS_HDD_RX_P23")
	)
	(segment
		(start 483.790498 -129.30505)
		(end 485.125014 -129.30505)
		(width 0.127)
		(layer "F.Cu")
		(net "SAS_HDD_RX_P23")
	)
	(segment
		(start 479.664014 -129.66065)
		(end 480.026218 -129.66065)
		(width 0.127)
		(layer "F.Cu")
		(net "SAS_HDD_RX_P23")
	)
	(segment
		(start 451.986396 -129.794)
		(end 452.113396 -129.667)
		(width 0.127)
		(layer "F.Cu")
		(net "SAS_HDD_RX_P22")
	)
	(segment
		(start 448.113912 -129.66065)
		(end 448.470274 -129.66065)
		(width 0.127)
		(layer "F.Cu")
		(net "SAS_HDD_RX_P22")
	)
	(segment
		(start 452.113396 -129.667)
		(end 452.113396 -129.43205)
		(width 0.127)
		(layer "F.Cu")
		(net "SAS_HDD_RX_P22")
	)
	(segment
		(start 448.603624 -129.794)
		(end 451.986396 -129.794)
		(width 0.127)
		(layer "F.Cu")
		(net "SAS_HDD_RX_P22")
	)
	(segment
		(start 448.470274 -129.66065)
		(end 448.603624 -129.794)
		(width 0.127)
		(layer "F.Cu")
		(net "SAS_HDD_RX_P22")
	)
	(segment
		(start 452.113396 -129.43205)
		(end 452.240396 -129.30505)
		(width 0.127)
		(layer "F.Cu")
		(net "SAS_HDD_RX_P22")
	)
	(segment
		(start 452.240396 -129.30505)
		(end 453.574912 -129.30505)
		(width 0.127)
		(layer "F.Cu")
		(net "SAS_HDD_RX_P22")
	)
	(segment
		(start 420.436548 -129.794)
		(end 420.563548 -129.667)
		(width 0.127)
		(layer "F.Cu")
		(net "SAS_HDD_RX_P21")
	)
	(segment
		(start 416.564064 -129.66065)
		(end 416.927538 -129.66065)
		(width 0.127)
		(layer "F.Cu")
		(net "SAS_HDD_RX_P21")
	)
	(segment
		(start 416.927538 -129.66065)
		(end 417.060888 -129.794)
		(width 0.127)
		(layer "F.Cu")
		(net "SAS_HDD_RX_P21")
	)
	(segment
		(start 420.563548 -129.667)
		(end 420.563548 -129.43205)
		(width 0.127)
		(layer "F.Cu")
		(net "SAS_HDD_RX_P21")
	)
	(segment
		(start 417.060888 -129.794)
		(end 420.436548 -129.794)
		(width 0.127)
		(layer "F.Cu")
		(net "SAS_HDD_RX_P21")
	)
	(segment
		(start 420.690548 -129.30505)
		(end 422.025064 -129.30505)
		(width 0.127)
		(layer "F.Cu")
		(net "SAS_HDD_RX_P21")
	)
	(segment
		(start 420.563548 -129.43205)
		(end 420.690548 -129.30505)
		(width 0.127)
		(layer "F.Cu")
		(net "SAS_HDD_RX_P21")
	)
	(segment
		(start 385.013962 -129.66065)
		(end 385.38531 -129.66065)
		(width 0.127)
		(layer "F.Cu")
		(net "SAS_HDD_RX_P20")
	)
	(segment
		(start 385.51866 -129.794)
		(end 388.886446 -129.794)
		(width 0.127)
		(layer "F.Cu")
		(net "SAS_HDD_RX_P20")
	)
	(segment
		(start 389.013446 -129.43205)
		(end 389.140446 -129.30505)
		(width 0.127)
		(layer "F.Cu")
		(net "SAS_HDD_RX_P20")
	)
	(segment
		(start 389.140446 -129.30505)
		(end 390.474962 -129.30505)
		(width 0.127)
		(layer "F.Cu")
		(net "SAS_HDD_RX_P20")
	)
	(segment
		(start 389.013446 -129.667)
		(end 389.013446 -129.43205)
		(width 0.127)
		(layer "F.Cu")
		(net "SAS_HDD_RX_P20")
	)
	(segment
		(start 385.38531 -129.66065)
		(end 385.51866 -129.794)
		(width 0.127)
		(layer "F.Cu")
		(net "SAS_HDD_RX_P20")
	)
	(segment
		(start 388.886446 -129.794)
		(end 389.013446 -129.667)
		(width 0.127)
		(layer "F.Cu")
		(net "SAS_HDD_RX_P20")
	)
	(segment
		(start 94.586552 -244.432074)
		(end 94.459552 -244.305074)
		(width 0.127)
		(layer "F.Cu")
		(net "SAS_HDD_RX_P2")
	)
	(segment
		(start 94.81947 -244.794024)
		(end 94.713552 -244.794024)
		(width 0.127)
		(layer "F.Cu")
		(net "SAS_HDD_RX_P2")
	)
	(segment
		(start 94.95282 -244.660674)
		(end 94.81947 -244.794024)
		(width 0.127)
		(layer "F.Cu")
		(net "SAS_HDD_RX_P2")
	)
	(segment
		(start 94.713552 -244.794024)
		(end 94.586552 -244.667024)
		(width 0.127)
		(layer "F.Cu")
		(net "SAS_HDD_RX_P2")
	)
	(segment
		(start 95.284036 -244.660674)
		(end 94.95282 -244.660674)
		(width 0.127)
		(layer "F.Cu")
		(net "SAS_HDD_RX_P2")
	)
	(segment
		(start 94.586552 -244.667024)
		(end 94.586552 -244.432074)
		(width 0.127)
		(layer "F.Cu")
		(net "SAS_HDD_RX_P2")
	)
	(segment
		(start 94.459552 -244.305074)
		(end 93.125036 -244.305074)
		(width 0.127)
		(layer "F.Cu")
		(net "SAS_HDD_RX_P2")
	)
	(segment
		(start 357.590598 -129.30505)
		(end 358.925114 -129.30505)
		(width 0.127)
		(layer "F.Cu")
		(net "SAS_HDD_RX_P19")
	)
	(segment
		(start 353.464114 -129.66065)
		(end 353.949 -129.66065)
		(width 0.127)
		(layer "F.Cu")
		(net "SAS_HDD_RX_P19")
	)
	(segment
		(start 353.949 -129.66065)
		(end 354.08235 -129.794)
		(width 0.127)
		(layer "F.Cu")
		(net "SAS_HDD_RX_P19")
	)
	(segment
		(start 354.08235 -129.794)
		(end 357.336598 -129.794)
		(width 0.127)
		(layer "F.Cu")
		(net "SAS_HDD_RX_P19")
	)
	(segment
		(start 357.463598 -129.43205)
		(end 357.590598 -129.30505)
		(width 0.127)
		(layer "F.Cu")
		(net "SAS_HDD_RX_P19")
	)
	(segment
		(start 357.463598 -129.667)
		(end 357.463598 -129.43205)
		(width 0.127)
		(layer "F.Cu")
		(net "SAS_HDD_RX_P19")
	)
	(segment
		(start 357.336598 -129.794)
		(end 357.463598 -129.667)
		(width 0.127)
		(layer "F.Cu")
		(net "SAS_HDD_RX_P19")
	)
	(segment
		(start 325.913496 -129.43205)
		(end 326.040496 -129.30505)
		(width 0.127)
		(layer "F.Cu")
		(net "SAS_HDD_RX_P18")
	)
	(segment
		(start 326.040496 -129.30505)
		(end 327.375012 -129.30505)
		(width 0.127)
		(layer "F.Cu")
		(net "SAS_HDD_RX_P18")
	)
	(segment
		(start 322.5546 -129.66065)
		(end 322.686426 -129.792476)
		(width 0.127)
		(layer "F.Cu")
		(net "SAS_HDD_RX_P18")
	)
	(segment
		(start 325.913496 -129.667)
		(end 325.913496 -129.43205)
		(width 0.127)
		(layer "F.Cu")
		(net "SAS_HDD_RX_P18")
	)
	(segment
		(start 322.686426 -129.792476)
		(end 325.78802 -129.792476)
		(width 0.127)
		(layer "F.Cu")
		(net "SAS_HDD_RX_P18")
	)
	(segment
		(start 321.914012 -129.66065)
		(end 322.5546 -129.66065)
		(width 0.127)
		(layer "F.Cu")
		(net "SAS_HDD_RX_P18")
	)
	(segment
		(start 325.78802 -129.792476)
		(end 325.913496 -129.667)
		(width 0.127)
		(layer "F.Cu")
		(net "SAS_HDD_RX_P18")
	)
	(segment
		(start 189.469522 -129.794)
		(end 189.363604 -129.794)
		(width 0.127)
		(layer "F.Cu")
		(net "SAS_HDD_RX_P17")
	)
	(segment
		(start 189.236604 -129.667)
		(end 189.236604 -129.43205)
		(width 0.127)
		(layer "F.Cu")
		(net "SAS_HDD_RX_P17")
	)
	(segment
		(start 189.363604 -129.794)
		(end 189.236604 -129.667)
		(width 0.127)
		(layer "F.Cu")
		(net "SAS_HDD_RX_P17")
	)
	(segment
		(start 189.236604 -129.43205)
		(end 189.109604 -129.30505)
		(width 0.127)
		(layer "F.Cu")
		(net "SAS_HDD_RX_P17")
	)
	(segment
		(start 189.602872 -129.66065)
		(end 189.469522 -129.794)
		(width 0.127)
		(layer "F.Cu")
		(net "SAS_HDD_RX_P17")
	)
	(segment
		(start 189.934088 -129.66065)
		(end 189.602872 -129.66065)
		(width 0.127)
		(layer "F.Cu")
		(net "SAS_HDD_RX_P17")
	)
	(segment
		(start 189.109604 -129.30505)
		(end 187.775088 -129.30505)
		(width 0.127)
		(layer "F.Cu")
		(net "SAS_HDD_RX_P17")
	)
	(segment
		(start 157.686502 -129.667)
		(end 157.686502 -129.43205)
		(width 0.127)
		(layer "F.Cu")
		(net "SAS_HDD_RX_P16")
	)
	(segment
		(start 157.686502 -129.43205)
		(end 157.559502 -129.30505)
		(width 0.127)
		(layer "F.Cu")
		(net "SAS_HDD_RX_P16")
	)
	(segment
		(start 157.813502 -129.794)
		(end 157.686502 -129.667)
		(width 0.127)
		(layer "F.Cu")
		(net "SAS_HDD_RX_P16")
	)
	(segment
		(start 158.05277 -129.66065)
		(end 157.91942 -129.794)
		(width 0.127)
		(layer "F.Cu")
		(net "SAS_HDD_RX_P16")
	)
	(segment
		(start 157.91942 -129.794)
		(end 157.813502 -129.794)
		(width 0.127)
		(layer "F.Cu")
		(net "SAS_HDD_RX_P16")
	)
	(segment
		(start 157.559502 -129.30505)
		(end 156.224986 -129.30505)
		(width 0.127)
		(layer "F.Cu")
		(net "SAS_HDD_RX_P16")
	)
	(segment
		(start 158.383986 -129.66065)
		(end 158.05277 -129.66065)
		(width 0.127)
		(layer "F.Cu")
		(net "SAS_HDD_RX_P16")
	)
	(segment
		(start 126.502668 -129.66065)
		(end 126.369318 -129.794)
		(width 0.127)
		(layer "F.Cu")
		(net "SAS_HDD_RX_P15")
	)
	(segment
		(start 126.2634 -129.794)
		(end 126.1364 -129.667)
		(width 0.127)
		(layer "F.Cu")
		(net "SAS_HDD_RX_P15")
	)
	(segment
		(start 126.1364 -129.667)
		(end 126.1364 -129.43205)
		(width 0.127)
		(layer "F.Cu")
		(net "SAS_HDD_RX_P15")
	)
	(segment
		(start 126.833884 -129.66065)
		(end 126.502668 -129.66065)
		(width 0.127)
		(layer "F.Cu")
		(net "SAS_HDD_RX_P15")
	)
	(segment
		(start 126.369318 -129.794)
		(end 126.2634 -129.794)
		(width 0.127)
		(layer "F.Cu")
		(net "SAS_HDD_RX_P15")
	)
	(segment
		(start 126.0094 -129.30505)
		(end 124.674884 -129.30505)
		(width 0.127)
		(layer "F.Cu")
		(net "SAS_HDD_RX_P15")
	)
	(segment
		(start 126.1364 -129.43205)
		(end 126.0094 -129.30505)
		(width 0.127)
		(layer "F.Cu")
		(net "SAS_HDD_RX_P15")
	)
	(segment
		(start 94.586552 -129.667)
		(end 94.586552 -129.43205)
		(width 0.127)
		(layer "F.Cu")
		(net "SAS_HDD_RX_P14")
	)
	(segment
		(start 94.586552 -129.43205)
		(end 94.459552 -129.30505)
		(width 0.127)
		(layer "F.Cu")
		(net "SAS_HDD_RX_P14")
	)
	(segment
		(start 94.95282 -129.66065)
		(end 94.81947 -129.794)
		(width 0.127)
		(layer "F.Cu")
		(net "SAS_HDD_RX_P14")
	)
	(segment
		(start 94.81947 -129.794)
		(end 94.713552 -129.794)
		(width 0.127)
		(layer "F.Cu")
		(net "SAS_HDD_RX_P14")
	)
	(segment
		(start 94.459552 -129.30505)
		(end 93.125036 -129.30505)
		(width 0.127)
		(layer "F.Cu")
		(net "SAS_HDD_RX_P14")
	)
	(segment
		(start 94.713552 -129.794)
		(end 94.586552 -129.667)
		(width 0.127)
		(layer "F.Cu")
		(net "SAS_HDD_RX_P14")
	)
	(segment
		(start 95.284036 -129.66065)
		(end 94.95282 -129.66065)
		(width 0.127)
		(layer "F.Cu")
		(net "SAS_HDD_RX_P14")
	)
	(segment
		(start 63.16345 -129.794)
		(end 63.03645 -129.667)
		(width 0.127)
		(layer "F.Cu")
		(net "SAS_HDD_RX_P13")
	)
	(segment
		(start 62.90945 -129.30505)
		(end 61.574934 -129.30505)
		(width 0.127)
		(layer "F.Cu")
		(net "SAS_HDD_RX_P13")
	)
	(segment
		(start 63.402718 -129.66065)
		(end 63.269368 -129.794)
		(width 0.127)
		(layer "F.Cu")
		(net "SAS_HDD_RX_P13")
	)
	(segment
		(start 63.03645 -129.667)
		(end 63.03645 -129.43205)
		(width 0.127)
		(layer "F.Cu")
		(net "SAS_HDD_RX_P13")
	)
	(segment
		(start 63.03645 -129.43205)
		(end 62.90945 -129.30505)
		(width 0.127)
		(layer "F.Cu")
		(net "SAS_HDD_RX_P13")
	)
	(segment
		(start 63.733934 -129.66065)
		(end 63.402718 -129.66065)
		(width 0.127)
		(layer "F.Cu")
		(net "SAS_HDD_RX_P13")
	)
	(segment
		(start 63.269368 -129.794)
		(end 63.16345 -129.794)
		(width 0.127)
		(layer "F.Cu")
		(net "SAS_HDD_RX_P13")
	)
	(segment
		(start 31.85287 -129.66065)
		(end 31.71952 -129.794)
		(width 0.127)
		(layer "F.Cu")
		(net "SAS_HDD_RX_P12")
	)
	(segment
		(start 31.359602 -129.30505)
		(end 30.025086 -129.30505)
		(width 0.127)
		(layer "F.Cu")
		(net "SAS_HDD_RX_P12")
	)
	(segment
		(start 31.71952 -129.794)
		(end 31.613602 -129.794)
		(width 0.127)
		(layer "F.Cu")
		(net "SAS_HDD_RX_P12")
	)
	(segment
		(start 31.486602 -129.43205)
		(end 31.359602 -129.30505)
		(width 0.127)
		(layer "F.Cu")
		(net "SAS_HDD_RX_P12")
	)
	(segment
		(start 31.613602 -129.794)
		(end 31.486602 -129.667)
		(width 0.127)
		(layer "F.Cu")
		(net "SAS_HDD_RX_P12")
	)
	(segment
		(start 32.184086 -129.66065)
		(end 31.85287 -129.66065)
		(width 0.127)
		(layer "F.Cu")
		(net "SAS_HDD_RX_P12")
	)
	(segment
		(start 31.486602 -129.667)
		(end 31.486602 -129.43205)
		(width 0.127)
		(layer "F.Cu")
		(net "SAS_HDD_RX_P12")
	)
	(segment
		(start 479.664014 -244.660674)
		(end 480.067874 -244.660674)
		(width 0.127)
		(layer "F.Cu")
		(net "SAS_HDD_RX_P11")
	)
	(segment
		(start 483.663498 -244.432074)
		(end 483.790498 -244.305074)
		(width 0.127)
		(layer "F.Cu")
		(net "SAS_HDD_RX_P11")
	)
	(segment
		(start 483.790498 -244.305074)
		(end 485.125014 -244.305074)
		(width 0.127)
		(layer "F.Cu")
		(net "SAS_HDD_RX_P11")
	)
	(segment
		(start 480.067874 -244.660674)
		(end 480.201224 -244.794024)
		(width 0.127)
		(layer "F.Cu")
		(net "SAS_HDD_RX_P11")
	)
	(segment
		(start 483.663498 -244.667024)
		(end 483.663498 -244.432074)
		(width 0.127)
		(layer "F.Cu")
		(net "SAS_HDD_RX_P11")
	)
	(segment
		(start 483.536498 -244.794024)
		(end 483.663498 -244.667024)
		(width 0.127)
		(layer "F.Cu")
		(net "SAS_HDD_RX_P11")
	)
	(segment
		(start 480.201224 -244.794024)
		(end 483.536498 -244.794024)
		(width 0.127)
		(layer "F.Cu")
		(net "SAS_HDD_RX_P11")
	)
	(segment
		(start 452.113396 -244.432074)
		(end 452.240396 -244.305074)
		(width 0.127)
		(layer "F.Cu")
		(net "SAS_HDD_RX_P10")
	)
	(segment
		(start 452.240396 -244.305074)
		(end 453.574912 -244.305074)
		(width 0.127)
		(layer "F.Cu")
		(net "SAS_HDD_RX_P10")
	)
	(segment
		(start 448.113912 -244.660674)
		(end 448.470274 -244.660674)
		(width 0.127)
		(layer "F.Cu")
		(net "SAS_HDD_RX_P10")
	)
	(segment
		(start 448.603624 -244.794024)
		(end 451.986396 -244.794024)
		(width 0.127)
		(layer "F.Cu")
		(net "SAS_HDD_RX_P10")
	)
	(segment
		(start 452.113396 -244.667024)
		(end 452.113396 -244.432074)
		(width 0.127)
		(layer "F.Cu")
		(net "SAS_HDD_RX_P10")
	)
	(segment
		(start 451.986396 -244.794024)
		(end 452.113396 -244.667024)
		(width 0.127)
		(layer "F.Cu")
		(net "SAS_HDD_RX_P10")
	)
	(segment
		(start 448.470274 -244.660674)
		(end 448.603624 -244.794024)
		(width 0.127)
		(layer "F.Cu")
		(net "SAS_HDD_RX_P10")
	)
	(segment
		(start 62.90945 -244.305074)
		(end 61.574934 -244.305074)
		(width 0.127)
		(layer "F.Cu")
		(net "SAS_HDD_RX_P1")
	)
	(segment
		(start 63.16345 -244.794024)
		(end 63.03645 -244.667024)
		(width 0.127)
		(layer "F.Cu")
		(net "SAS_HDD_RX_P1")
	)
	(segment
		(start 63.269368 -244.794024)
		(end 63.16345 -244.794024)
		(width 0.127)
		(layer "F.Cu")
		(net "SAS_HDD_RX_P1")
	)
	(segment
		(start 63.733934 -244.660674)
		(end 63.402718 -244.660674)
		(width 0.127)
		(layer "F.Cu")
		(net "SAS_HDD_RX_P1")
	)
	(segment
		(start 63.03645 -244.667024)
		(end 63.03645 -244.432074)
		(width 0.127)
		(layer "F.Cu")
		(net "SAS_HDD_RX_P1")
	)
	(segment
		(start 63.03645 -244.432074)
		(end 62.90945 -244.305074)
		(width 0.127)
		(layer "F.Cu")
		(net "SAS_HDD_RX_P1")
	)
	(segment
		(start 63.402718 -244.660674)
		(end 63.269368 -244.794024)
		(width 0.127)
		(layer "F.Cu")
		(net "SAS_HDD_RX_P1")
	)
	(segment
		(start 31.486602 -244.432074)
		(end 31.359602 -244.305074)
		(width 0.127)
		(layer "F.Cu")
		(net "SAS_HDD_RX_P0")
	)
	(segment
		(start 31.486602 -244.667024)
		(end 31.486602 -244.432074)
		(width 0.127)
		(layer "F.Cu")
		(net "SAS_HDD_RX_P0")
	)
	(segment
		(start 31.359602 -244.305074)
		(end 30.025086 -244.305074)
		(width 0.127)
		(layer "F.Cu")
		(net "SAS_HDD_RX_P0")
	)
	(segment
		(start 31.613602 -244.794024)
		(end 31.486602 -244.667024)
		(width 0.127)
		(layer "F.Cu")
		(net "SAS_HDD_RX_P0")
	)
	(segment
		(start 32.184086 -244.660674)
		(end 31.85287 -244.660674)
		(width 0.127)
		(layer "F.Cu")
		(net "SAS_HDD_RX_P0")
	)
	(segment
		(start 31.85287 -244.660674)
		(end 31.71952 -244.794024)
		(width 0.127)
		(layer "F.Cu")
		(net "SAS_HDD_RX_P0")
	)
	(segment
		(start 31.71952 -244.794024)
		(end 31.613602 -244.794024)
		(width 0.127)
		(layer "F.Cu")
		(net "SAS_HDD_RX_P0")
	)
	(segment
		(start 416.933126 -245.219474)
		(end 417.066476 -245.086124)
		(width 0.127)
		(layer "F.Cu")
		(net "SAS_HDD_RX_N9")
	)
	(segment
		(start 420.563548 -245.213124)
		(end 420.563548 -245.448074)
		(width 0.127)
		(layer "F.Cu")
		(net "SAS_HDD_RX_N9")
	)
	(segment
		(start 420.690548 -245.575074)
		(end 422.025064 -245.575074)
		(width 0.127)
		(layer "F.Cu")
		(net "SAS_HDD_RX_N9")
	)
	(segment
		(start 416.564064 -245.219474)
		(end 416.933126 -245.219474)
		(width 0.127)
		(layer "F.Cu")
		(net "SAS_HDD_RX_N9")
	)
	(segment
		(start 420.563548 -245.448074)
		(end 420.690548 -245.575074)
		(width 0.127)
		(layer "F.Cu")
		(net "SAS_HDD_RX_N9")
	)
	(segment
		(start 417.066476 -245.086124)
		(end 420.436548 -245.086124)
		(width 0.127)
		(layer "F.Cu")
		(net "SAS_HDD_RX_N9")
	)
	(segment
		(start 420.436548 -245.086124)
		(end 420.563548 -245.213124)
		(width 0.127)
		(layer "F.Cu")
		(net "SAS_HDD_RX_N9")
	)
	(segment
		(start 389.013446 -245.448074)
		(end 389.140446 -245.575074)
		(width 0.127)
		(layer "F.Cu")
		(net "SAS_HDD_RX_N8")
	)
	(segment
		(start 385.386326 -245.219474)
		(end 385.519676 -245.086124)
		(width 0.127)
		(layer "F.Cu")
		(net "SAS_HDD_RX_N8")
	)
	(segment
		(start 385.013962 -245.219474)
		(end 385.386326 -245.219474)
		(width 0.127)
		(layer "F.Cu")
		(net "SAS_HDD_RX_N8")
	)
	(segment
		(start 389.013446 -245.213124)
		(end 389.013446 -245.448074)
		(width 0.127)
		(layer "F.Cu")
		(net "SAS_HDD_RX_N8")
	)
	(segment
		(start 388.886446 -245.086124)
		(end 389.013446 -245.213124)
		(width 0.127)
		(layer "F.Cu")
		(net "SAS_HDD_RX_N8")
	)
	(segment
		(start 385.519676 -245.086124)
		(end 388.886446 -245.086124)
		(width 0.127)
		(layer "F.Cu")
		(net "SAS_HDD_RX_N8")
	)
	(segment
		(start 389.140446 -245.575074)
		(end 390.474962 -245.575074)
		(width 0.127)
		(layer "F.Cu")
		(net "SAS_HDD_RX_N8")
	)
	(segment
		(start 353.972876 -245.086124)
		(end 357.336598 -245.086124)
		(width 0.127)
		(layer "F.Cu")
		(net "SAS_HDD_RX_N7")
	)
	(segment
		(start 357.336598 -245.086124)
		(end 357.463598 -245.213124)
		(width 0.127)
		(layer "F.Cu")
		(net "SAS_HDD_RX_N7")
	)
	(segment
		(start 357.463598 -245.448074)
		(end 357.590598 -245.575074)
		(width 0.127)
		(layer "F.Cu")
		(net "SAS_HDD_RX_N7")
	)
	(segment
		(start 357.590598 -245.575074)
		(end 358.925114 -245.575074)
		(width 0.127)
		(layer "F.Cu")
		(net "SAS_HDD_RX_N7")
	)
	(segment
		(start 353.464114 -245.219474)
		(end 353.839526 -245.219474)
		(width 0.127)
		(layer "F.Cu")
		(net "SAS_HDD_RX_N7")
	)
	(segment
		(start 353.839526 -245.219474)
		(end 353.972876 -245.086124)
		(width 0.127)
		(layer "F.Cu")
		(net "SAS_HDD_RX_N7")
	)
	(segment
		(start 357.463598 -245.213124)
		(end 357.463598 -245.448074)
		(width 0.127)
		(layer "F.Cu")
		(net "SAS_HDD_RX_N7")
	)
	(segment
		(start 326.040496 -245.575074)
		(end 327.375012 -245.575074)
		(width 0.127)
		(layer "F.Cu")
		(net "SAS_HDD_RX_N6")
	)
	(segment
		(start 325.913496 -245.213124)
		(end 325.913496 -245.448074)
		(width 0.127)
		(layer "F.Cu")
		(net "SAS_HDD_RX_N6")
	)
	(segment
		(start 325.913496 -245.448074)
		(end 326.040496 -245.575074)
		(width 0.127)
		(layer "F.Cu")
		(net "SAS_HDD_RX_N6")
	)
	(segment
		(start 322.292726 -245.219474)
		(end 322.426076 -245.086124)
		(width 0.127)
		(layer "F.Cu")
		(net "SAS_HDD_RX_N6")
	)
	(segment
		(start 321.914012 -245.219474)
		(end 322.292726 -245.219474)
		(width 0.127)
		(layer "F.Cu")
		(net "SAS_HDD_RX_N6")
	)
	(segment
		(start 325.786496 -245.086124)
		(end 325.913496 -245.213124)
		(width 0.127)
		(layer "F.Cu")
		(net "SAS_HDD_RX_N6")
	)
	(segment
		(start 322.426076 -245.086124)
		(end 325.786496 -245.086124)
		(width 0.127)
		(layer "F.Cu")
		(net "SAS_HDD_RX_N6")
	)
	(segment
		(start 189.109604 -245.575074)
		(end 187.775088 -245.575074)
		(width 0.127)
		(layer "F.Cu")
		(net "SAS_HDD_RX_N5")
	)
	(segment
		(start 189.363604 -245.086124)
		(end 189.236604 -245.213124)
		(width 0.127)
		(layer "F.Cu")
		(net "SAS_HDD_RX_N5")
	)
	(segment
		(start 189.602872 -245.219474)
		(end 189.469522 -245.086124)
		(width 0.127)
		(layer "F.Cu")
		(net "SAS_HDD_RX_N5")
	)
	(segment
		(start 189.236604 -245.448074)
		(end 189.109604 -245.575074)
		(width 0.127)
		(layer "F.Cu")
		(net "SAS_HDD_RX_N5")
	)
	(segment
		(start 189.469522 -245.086124)
		(end 189.363604 -245.086124)
		(width 0.127)
		(layer "F.Cu")
		(net "SAS_HDD_RX_N5")
	)
	(segment
		(start 189.236604 -245.213124)
		(end 189.236604 -245.448074)
		(width 0.127)
		(layer "F.Cu")
		(net "SAS_HDD_RX_N5")
	)
	(segment
		(start 189.934088 -245.219474)
		(end 189.602872 -245.219474)
		(width 0.127)
		(layer "F.Cu")
		(net "SAS_HDD_RX_N5")
	)
	(segment
		(start 157.91942 -245.086124)
		(end 157.813502 -245.086124)
		(width 0.127)
		(layer "F.Cu")
		(net "SAS_HDD_RX_N4")
	)
	(segment
		(start 157.686502 -245.213124)
		(end 157.686502 -245.448074)
		(width 0.127)
		(layer "F.Cu")
		(net "SAS_HDD_RX_N4")
	)
	(segment
		(start 158.05277 -245.219474)
		(end 157.91942 -245.086124)
		(width 0.127)
		(layer "F.Cu")
		(net "SAS_HDD_RX_N4")
	)
	(segment
		(start 157.813502 -245.086124)
		(end 157.686502 -245.213124)
		(width 0.127)
		(layer "F.Cu")
		(net "SAS_HDD_RX_N4")
	)
	(segment
		(start 158.383986 -245.219474)
		(end 158.05277 -245.219474)
		(width 0.127)
		(layer "F.Cu")
		(net "SAS_HDD_RX_N4")
	)
	(segment
		(start 157.686502 -245.448074)
		(end 157.559502 -245.575074)
		(width 0.127)
		(layer "F.Cu")
		(net "SAS_HDD_RX_N4")
	)
	(segment
		(start 157.559502 -245.575074)
		(end 156.224986 -245.575074)
		(width 0.127)
		(layer "F.Cu")
		(net "SAS_HDD_RX_N4")
	)
	(segment
		(start 483.663498 -15.448026)
		(end 483.790498 -15.575026)
		(width 0.127)
		(layer "F.Cu")
		(net "SAS_HDD_RX_N35")
	)
	(segment
		(start 480.072446 -15.219426)
		(end 480.205796 -15.086076)
		(width 0.127)
		(layer "F.Cu")
		(net "SAS_HDD_RX_N35")
	)
	(segment
		(start 483.790498 -15.575026)
		(end 485.125014 -15.575026)
		(width 0.127)
		(layer "F.Cu")
		(net "SAS_HDD_RX_N35")
	)
	(segment
		(start 480.205796 -15.086076)
		(end 483.536498 -15.086076)
		(width 0.127)
		(layer "F.Cu")
		(net "SAS_HDD_RX_N35")
	)
	(segment
		(start 483.663498 -15.213076)
		(end 483.663498 -15.448026)
		(width 0.127)
		(layer "F.Cu")
		(net "SAS_HDD_RX_N35")
	)
	(segment
		(start 479.664014 -15.219426)
		(end 480.072446 -15.219426)
		(width 0.127)
		(layer "F.Cu")
		(net "SAS_HDD_RX_N35")
	)
	(segment
		(start 483.536498 -15.086076)
		(end 483.663498 -15.213076)
		(width 0.127)
		(layer "F.Cu")
		(net "SAS_HDD_RX_N35")
	)
	(segment
		(start 452.240396 -15.575026)
		(end 453.574912 -15.575026)
		(width 0.127)
		(layer "F.Cu")
		(net "SAS_HDD_RX_N34")
	)
	(segment
		(start 448.679316 -15.086076)
		(end 451.986396 -15.086076)
		(width 0.127)
		(layer "F.Cu")
		(net "SAS_HDD_RX_N34")
	)
	(segment
		(start 451.986396 -15.086076)
		(end 452.113396 -15.213076)
		(width 0.127)
		(layer "F.Cu")
		(net "SAS_HDD_RX_N34")
	)
	(segment
		(start 452.113396 -15.448026)
		(end 452.240396 -15.575026)
		(width 0.127)
		(layer "F.Cu")
		(net "SAS_HDD_RX_N34")
	)
	(segment
		(start 448.113912 -15.219426)
		(end 448.545966 -15.219426)
		(width 0.127)
		(layer "F.Cu")
		(net "SAS_HDD_RX_N34")
	)
	(segment
		(start 452.113396 -15.213076)
		(end 452.113396 -15.448026)
		(width 0.127)
		(layer "F.Cu")
		(net "SAS_HDD_RX_N34")
	)
	(segment
		(start 448.545966 -15.219426)
		(end 448.679316 -15.086076)
		(width 0.127)
		(layer "F.Cu")
		(net "SAS_HDD_RX_N34")
	)
	(segment
		(start 420.563548 -15.213076)
		(end 420.563548 -15.448026)
		(width 0.127)
		(layer "F.Cu")
		(net "SAS_HDD_RX_N33")
	)
	(segment
		(start 417.069524 -15.086076)
		(end 420.436548 -15.086076)
		(width 0.127)
		(layer "F.Cu")
		(net "SAS_HDD_RX_N33")
	)
	(segment
		(start 420.563548 -15.448026)
		(end 420.690548 -15.575026)
		(width 0.127)
		(layer "F.Cu")
		(net "SAS_HDD_RX_N33")
	)
	(segment
		(start 420.690548 -15.575026)
		(end 422.025064 -15.575026)
		(width 0.127)
		(layer "F.Cu")
		(net "SAS_HDD_RX_N33")
	)
	(segment
		(start 416.936174 -15.219426)
		(end 417.069524 -15.086076)
		(width 0.127)
		(layer "F.Cu")
		(net "SAS_HDD_RX_N33")
	)
	(segment
		(start 416.564064 -15.219426)
		(end 416.936174 -15.219426)
		(width 0.127)
		(layer "F.Cu")
		(net "SAS_HDD_RX_N33")
	)
	(segment
		(start 420.436548 -15.086076)
		(end 420.563548 -15.213076)
		(width 0.127)
		(layer "F.Cu")
		(net "SAS_HDD_RX_N33")
	)
	(segment
		(start 385.54025 -15.086076)
		(end 388.886446 -15.086076)
		(width 0.127)
		(layer "F.Cu")
		(net "SAS_HDD_RX_N32")
	)
	(segment
		(start 389.013446 -15.213076)
		(end 389.013446 -15.448026)
		(width 0.127)
		(layer "F.Cu")
		(net "SAS_HDD_RX_N32")
	)
	(segment
		(start 385.4069 -15.219426)
		(end 385.54025 -15.086076)
		(width 0.127)
		(layer "F.Cu")
		(net "SAS_HDD_RX_N32")
	)
	(segment
		(start 388.886446 -15.086076)
		(end 389.013446 -15.213076)
		(width 0.127)
		(layer "F.Cu")
		(net "SAS_HDD_RX_N32")
	)
	(segment
		(start 389.140446 -15.575026)
		(end 390.474962 -15.575026)
		(width 0.127)
		(layer "F.Cu")
		(net "SAS_HDD_RX_N32")
	)
	(segment
		(start 389.013446 -15.448026)
		(end 389.140446 -15.575026)
		(width 0.127)
		(layer "F.Cu")
		(net "SAS_HDD_RX_N32")
	)
	(segment
		(start 385.013962 -15.219426)
		(end 385.4069 -15.219426)
		(width 0.127)
		(layer "F.Cu")
		(net "SAS_HDD_RX_N32")
	)
	(segment
		(start 357.463598 -15.448026)
		(end 357.590598 -15.575026)
		(width 0.127)
		(layer "F.Cu")
		(net "SAS_HDD_RX_N31")
	)
	(segment
		(start 353.82835 -15.219426)
		(end 353.9617 -15.086076)
		(width 0.127)
		(layer "F.Cu")
		(net "SAS_HDD_RX_N31")
	)
	(segment
		(start 357.590598 -15.575026)
		(end 358.925114 -15.575026)
		(width 0.127)
		(layer "F.Cu")
		(net "SAS_HDD_RX_N31")
	)
	(segment
		(start 353.464114 -15.219426)
		(end 353.82835 -15.219426)
		(width 0.127)
		(layer "F.Cu")
		(net "SAS_HDD_RX_N31")
	)
	(segment
		(start 357.336598 -15.086076)
		(end 357.463598 -15.213076)
		(width 0.127)
		(layer "F.Cu")
		(net "SAS_HDD_RX_N31")
	)
	(segment
		(start 357.463598 -15.213076)
		(end 357.463598 -15.448026)
		(width 0.127)
		(layer "F.Cu")
		(net "SAS_HDD_RX_N31")
	)
	(segment
		(start 353.9617 -15.086076)
		(end 357.336598 -15.086076)
		(width 0.127)
		(layer "F.Cu")
		(net "SAS_HDD_RX_N31")
	)
	(segment
		(start 325.913496 -15.448026)
		(end 326.040496 -15.575026)
		(width 0.127)
		(layer "F.Cu")
		(net "SAS_HDD_RX_N30")
	)
	(segment
		(start 325.913496 -15.213076)
		(end 325.913496 -15.448026)
		(width 0.127)
		(layer "F.Cu")
		(net "SAS_HDD_RX_N30")
	)
	(segment
		(start 322.4149 -15.086076)
		(end 325.786496 -15.086076)
		(width 0.127)
		(layer "F.Cu")
		(net "SAS_HDD_RX_N30")
	)
	(segment
		(start 325.786496 -15.086076)
		(end 325.913496 -15.213076)
		(width 0.127)
		(layer "F.Cu")
		(net "SAS_HDD_RX_N30")
	)
	(segment
		(start 326.040496 -15.575026)
		(end 327.375012 -15.575026)
		(width 0.127)
		(layer "F.Cu")
		(net "SAS_HDD_RX_N30")
	)
	(segment
		(start 322.28155 -15.219426)
		(end 322.4149 -15.086076)
		(width 0.127)
		(layer "F.Cu")
		(net "SAS_HDD_RX_N30")
	)
	(segment
		(start 321.914012 -15.219426)
		(end 322.28155 -15.219426)
		(width 0.127)
		(layer "F.Cu")
		(net "SAS_HDD_RX_N30")
	)
	(segment
		(start 126.1364 -245.213124)
		(end 126.1364 -245.448074)
		(width 0.127)
		(layer "F.Cu")
		(net "SAS_HDD_RX_N3")
	)
	(segment
		(start 126.833884 -245.219474)
		(end 126.502668 -245.219474)
		(width 0.127)
		(layer "F.Cu")
		(net "SAS_HDD_RX_N3")
	)
	(segment
		(start 126.502668 -245.219474)
		(end 126.369318 -245.086124)
		(width 0.127)
		(layer "F.Cu")
		(net "SAS_HDD_RX_N3")
	)
	(segment
		(start 126.2634 -245.086124)
		(end 126.1364 -245.213124)
		(width 0.127)
		(layer "F.Cu")
		(net "SAS_HDD_RX_N3")
	)
	(segment
		(start 126.0094 -245.575074)
		(end 124.674884 -245.575074)
		(width 0.127)
		(layer "F.Cu")
		(net "SAS_HDD_RX_N3")
	)
	(segment
		(start 126.1364 -245.448074)
		(end 126.0094 -245.575074)
		(width 0.127)
		(layer "F.Cu")
		(net "SAS_HDD_RX_N3")
	)
	(segment
		(start 126.369318 -245.086124)
		(end 126.2634 -245.086124)
		(width 0.127)
		(layer "F.Cu")
		(net "SAS_HDD_RX_N3")
	)
	(segment
		(start 189.363604 -15.086076)
		(end 189.236604 -15.213076)
		(width 0.127)
		(layer "F.Cu")
		(net "SAS_HDD_RX_N29")
	)
	(segment
		(start 189.934088 -15.219426)
		(end 189.602872 -15.219426)
		(width 0.127)
		(layer "F.Cu")
		(net "SAS_HDD_RX_N29")
	)
	(segment
		(start 189.602872 -15.219426)
		(end 189.469522 -15.086076)
		(width 0.127)
		(layer "F.Cu")
		(net "SAS_HDD_RX_N29")
	)
	(segment
		(start 189.109604 -15.575026)
		(end 187.775088 -15.575026)
		(width 0.127)
		(layer "F.Cu")
		(net "SAS_HDD_RX_N29")
	)
	(segment
		(start 189.236604 -15.213076)
		(end 189.236604 -15.448026)
		(width 0.127)
		(layer "F.Cu")
		(net "SAS_HDD_RX_N29")
	)
	(segment
		(start 189.236604 -15.448026)
		(end 189.109604 -15.575026)
		(width 0.127)
		(layer "F.Cu")
		(net "SAS_HDD_RX_N29")
	)
	(segment
		(start 189.469522 -15.086076)
		(end 189.363604 -15.086076)
		(width 0.127)
		(layer "F.Cu")
		(net "SAS_HDD_RX_N29")
	)
	(segment
		(start 157.91942 -15.086076)
		(end 157.813502 -15.086076)
		(width 0.127)
		(layer "F.Cu")
		(net "SAS_HDD_RX_N28")
	)
	(segment
		(start 157.686502 -15.448026)
		(end 157.559502 -15.575026)
		(width 0.127)
		(layer "F.Cu")
		(net "SAS_HDD_RX_N28")
	)
	(segment
		(start 157.559502 -15.575026)
		(end 156.224986 -15.575026)
		(width 0.127)
		(layer "F.Cu")
		(net "SAS_HDD_RX_N28")
	)
	(segment
		(start 158.383986 -15.219426)
		(end 158.05277 -15.219426)
		(width 0.127)
		(layer "F.Cu")
		(net "SAS_HDD_RX_N28")
	)
	(segment
		(start 157.686502 -15.213076)
		(end 157.686502 -15.448026)
		(width 0.127)
		(layer "F.Cu")
		(net "SAS_HDD_RX_N28")
	)
	(segment
		(start 157.813502 -15.086076)
		(end 157.686502 -15.213076)
		(width 0.127)
		(layer "F.Cu")
		(net "SAS_HDD_RX_N28")
	)
	(segment
		(start 158.05277 -15.219426)
		(end 157.91942 -15.086076)
		(width 0.127)
		(layer "F.Cu")
		(net "SAS_HDD_RX_N28")
	)
	(segment
		(start 126.502668 -15.219426)
		(end 126.369318 -15.086076)
		(width 0.127)
		(layer "F.Cu")
		(net "SAS_HDD_RX_N27")
	)
	(segment
		(start 126.1364 -15.448026)
		(end 126.0094 -15.575026)
		(width 0.127)
		(layer "F.Cu")
		(net "SAS_HDD_RX_N27")
	)
	(segment
		(start 126.0094 -15.575026)
		(end 124.674884 -15.575026)
		(width 0.127)
		(layer "F.Cu")
		(net "SAS_HDD_RX_N27")
	)
	(segment
		(start 126.833884 -15.219426)
		(end 126.502668 -15.219426)
		(width 0.127)
		(layer "F.Cu")
		(net "SAS_HDD_RX_N27")
	)
	(segment
		(start 126.369318 -15.086076)
		(end 126.2634 -15.086076)
		(width 0.127)
		(layer "F.Cu")
		(net "SAS_HDD_RX_N27")
	)
	(segment
		(start 126.2634 -15.086076)
		(end 126.1364 -15.213076)
		(width 0.127)
		(layer "F.Cu")
		(net "SAS_HDD_RX_N27")
	)
	(segment
		(start 126.1364 -15.213076)
		(end 126.1364 -15.448026)
		(width 0.127)
		(layer "F.Cu")
		(net "SAS_HDD_RX_N27")
	)
	(segment
		(start 94.81947 -15.086076)
		(end 94.713552 -15.086076)
		(width 0.127)
		(layer "F.Cu")
		(net "SAS_HDD_RX_N26")
	)
	(segment
		(start 94.95282 -15.219426)
		(end 94.81947 -15.086076)
		(width 0.127)
		(layer "F.Cu")
		(net "SAS_HDD_RX_N26")
	)
	(segment
		(start 94.713552 -15.086076)
		(end 94.586552 -15.213076)
		(width 0.127)
		(layer "F.Cu")
		(net "SAS_HDD_RX_N26")
	)
	(segment
		(start 94.586552 -15.448026)
		(end 94.459552 -15.575026)
		(width 0.127)
		(layer "F.Cu")
		(net "SAS_HDD_RX_N26")
	)
	(segment
		(start 94.586552 -15.213076)
		(end 94.586552 -15.448026)
		(width 0.127)
		(layer "F.Cu")
		(net "SAS_HDD_RX_N26")
	)
	(segment
		(start 94.459552 -15.575026)
		(end 93.125036 -15.575026)
		(width 0.127)
		(layer "F.Cu")
		(net "SAS_HDD_RX_N26")
	)
	(segment
		(start 95.284036 -15.219426)
		(end 94.95282 -15.219426)
		(width 0.127)
		(layer "F.Cu")
		(net "SAS_HDD_RX_N26")
	)
	(segment
		(start 63.402718 -15.219426)
		(end 63.269368 -15.086076)
		(width 0.127)
		(layer "F.Cu")
		(net "SAS_HDD_RX_N25")
	)
	(segment
		(start 63.03645 -15.448026)
		(end 62.90945 -15.575026)
		(width 0.127)
		(layer "F.Cu")
		(net "SAS_HDD_RX_N25")
	)
	(segment
		(start 63.269368 -15.086076)
		(end 63.16345 -15.086076)
		(width 0.127)
		(layer "F.Cu")
		(net "SAS_HDD_RX_N25")
	)
	(segment
		(start 63.03645 -15.213076)
		(end 63.03645 -15.448026)
		(width 0.127)
		(layer "F.Cu")
		(net "SAS_HDD_RX_N25")
	)
	(segment
		(start 62.90945 -15.575026)
		(end 61.574934 -15.575026)
		(width 0.127)
		(layer "F.Cu")
		(net "SAS_HDD_RX_N25")
	)
	(segment
		(start 63.16345 -15.086076)
		(end 63.03645 -15.213076)
		(width 0.127)
		(layer "F.Cu")
		(net "SAS_HDD_RX_N25")
	)
	(segment
		(start 63.733934 -15.219426)
		(end 63.402718 -15.219426)
		(width 0.127)
		(layer "F.Cu")
		(net "SAS_HDD_RX_N25")
	)
	(segment
		(start 31.85287 -15.219426)
		(end 31.71952 -15.086076)
		(width 0.127)
		(layer "F.Cu")
		(net "SAS_HDD_RX_N24")
	)
	(segment
		(start 31.71952 -15.086076)
		(end 31.613602 -15.086076)
		(width 0.127)
		(layer "F.Cu")
		(net "SAS_HDD_RX_N24")
	)
	(segment
		(start 31.613602 -15.086076)
		(end 31.486602 -15.213076)
		(width 0.127)
		(layer "F.Cu")
		(net "SAS_HDD_RX_N24")
	)
	(segment
		(start 31.486602 -15.213076)
		(end 31.486602 -15.448026)
		(width 0.127)
		(layer "F.Cu")
		(net "SAS_HDD_RX_N24")
	)
	(segment
		(start 31.359602 -15.575026)
		(end 30.025086 -15.575026)
		(width 0.127)
		(layer "F.Cu")
		(net "SAS_HDD_RX_N24")
	)
	(segment
		(start 31.486602 -15.448026)
		(end 31.359602 -15.575026)
		(width 0.127)
		(layer "F.Cu")
		(net "SAS_HDD_RX_N24")
	)
	(segment
		(start 32.184086 -15.219426)
		(end 31.85287 -15.219426)
		(width 0.127)
		(layer "F.Cu")
		(net "SAS_HDD_RX_N24")
	)
	(segment
		(start 483.536498 -130.0861)
		(end 483.663498 -130.2131)
		(width 0.127)
		(layer "F.Cu")
		(net "SAS_HDD_RX_N23")
	)
	(segment
		(start 480.210114 -130.0861)
		(end 483.536498 -130.0861)
		(width 0.127)
		(layer "F.Cu")
		(net "SAS_HDD_RX_N23")
	)
	(segment
		(start 479.664014 -130.21945)
		(end 480.076764 -130.21945)
		(width 0.127)
		(layer "F.Cu")
		(net "SAS_HDD_RX_N23")
	)
	(segment
		(start 483.790498 -130.57505)
		(end 485.125014 -130.57505)
		(width 0.127)
		(layer "F.Cu")
		(net "SAS_HDD_RX_N23")
	)
	(segment
		(start 483.663498 -130.44805)
		(end 483.790498 -130.57505)
		(width 0.127)
		(layer "F.Cu")
		(net "SAS_HDD_RX_N23")
	)
	(segment
		(start 483.663498 -130.2131)
		(end 483.663498 -130.44805)
		(width 0.127)
		(layer "F.Cu")
		(net "SAS_HDD_RX_N23")
	)
	(segment
		(start 480.076764 -130.21945)
		(end 480.210114 -130.0861)
		(width 0.127)
		(layer "F.Cu")
		(net "SAS_HDD_RX_N23")
	)
	(segment
		(start 452.240396 -130.57505)
		(end 453.574912 -130.57505)
		(width 0.127)
		(layer "F.Cu")
		(net "SAS_HDD_RX_N22")
	)
	(segment
		(start 448.113912 -130.21945)
		(end 448.492118 -130.21945)
		(width 0.127)
		(layer "F.Cu")
		(net "SAS_HDD_RX_N22")
	)
	(segment
		(start 452.113396 -130.44805)
		(end 452.240396 -130.57505)
		(width 0.127)
		(layer "F.Cu")
		(net "SAS_HDD_RX_N22")
	)
	(segment
		(start 452.113396 -130.2131)
		(end 452.113396 -130.44805)
		(width 0.127)
		(layer "F.Cu")
		(net "SAS_HDD_RX_N22")
	)
	(segment
		(start 448.625468 -130.0861)
		(end 451.986396 -130.0861)
		(width 0.127)
		(layer "F.Cu")
		(net "SAS_HDD_RX_N22")
	)
	(segment
		(start 451.986396 -130.0861)
		(end 452.113396 -130.2131)
		(width 0.127)
		(layer "F.Cu")
		(net "SAS_HDD_RX_N22")
	)
	(segment
		(start 448.492118 -130.21945)
		(end 448.625468 -130.0861)
		(width 0.127)
		(layer "F.Cu")
		(net "SAS_HDD_RX_N22")
	)
	(segment
		(start 420.690548 -130.57505)
		(end 422.025064 -130.57505)
		(width 0.127)
		(layer "F.Cu")
		(net "SAS_HDD_RX_N21")
	)
	(segment
		(start 417.062666 -130.0861)
		(end 420.436548 -130.0861)
		(width 0.127)
		(layer "F.Cu")
		(net "SAS_HDD_RX_N21")
	)
	(segment
		(start 416.564064 -130.21945)
		(end 416.929316 -130.21945)
		(width 0.127)
		(layer "F.Cu")
		(net "SAS_HDD_RX_N21")
	)
	(segment
		(start 420.563548 -130.44805)
		(end 420.690548 -130.57505)
		(width 0.127)
		(layer "F.Cu")
		(net "SAS_HDD_RX_N21")
	)
	(segment
		(start 420.563548 -130.2131)
		(end 420.563548 -130.44805)
		(width 0.127)
		(layer "F.Cu")
		(net "SAS_HDD_RX_N21")
	)
	(segment
		(start 420.436548 -130.0861)
		(end 420.563548 -130.2131)
		(width 0.127)
		(layer "F.Cu")
		(net "SAS_HDD_RX_N21")
	)
	(segment
		(start 416.929316 -130.21945)
		(end 417.062666 -130.0861)
		(width 0.127)
		(layer "F.Cu")
		(net "SAS_HDD_RX_N21")
	)
	(segment
		(start 385.013962 -130.21945)
		(end 385.377944 -130.21945)
		(width 0.127)
		(layer "F.Cu")
		(net "SAS_HDD_RX_N20")
	)
	(segment
		(start 389.013446 -130.44805)
		(end 389.140446 -130.57505)
		(width 0.127)
		(layer "F.Cu")
		(net "SAS_HDD_RX_N20")
	)
	(segment
		(start 385.377944 -130.21945)
		(end 385.511294 -130.0861)
		(width 0.127)
		(layer "F.Cu")
		(net "SAS_HDD_RX_N20")
	)
	(segment
		(start 389.140446 -130.57505)
		(end 390.474962 -130.57505)
		(width 0.127)
		(layer "F.Cu")
		(net "SAS_HDD_RX_N20")
	)
	(segment
		(start 385.511294 -130.0861)
		(end 388.886446 -130.0861)
		(width 0.127)
		(layer "F.Cu")
		(net "SAS_HDD_RX_N20")
	)
	(segment
		(start 388.886446 -130.0861)
		(end 389.013446 -130.2131)
		(width 0.127)
		(layer "F.Cu")
		(net "SAS_HDD_RX_N20")
	)
	(segment
		(start 389.013446 -130.2131)
		(end 389.013446 -130.44805)
		(width 0.127)
		(layer "F.Cu")
		(net "SAS_HDD_RX_N20")
	)
	(segment
		(start 94.586552 -245.213124)
		(end 94.586552 -245.448074)
		(width 0.127)
		(layer "F.Cu")
		(net "SAS_HDD_RX_N2")
	)
	(segment
		(start 94.586552 -245.448074)
		(end 94.459552 -245.575074)
		(width 0.127)
		(layer "F.Cu")
		(net "SAS_HDD_RX_N2")
	)
	(segment
		(start 95.284036 -245.219474)
		(end 94.95282 -245.219474)
		(width 0.127)
		(layer "F.Cu")
		(net "SAS_HDD_RX_N2")
	)
	(segment
		(start 94.713552 -245.086124)
		(end 94.586552 -245.213124)
		(width 0.127)
		(layer "F.Cu")
		(net "SAS_HDD_RX_N2")
	)
	(segment
		(start 94.459552 -245.575074)
		(end 93.125036 -245.575074)
		(width 0.127)
		(layer "F.Cu")
		(net "SAS_HDD_RX_N2")
	)
	(segment
		(start 94.81947 -245.086124)
		(end 94.713552 -245.086124)
		(width 0.127)
		(layer "F.Cu")
		(net "SAS_HDD_RX_N2")
	)
	(segment
		(start 94.95282 -245.219474)
		(end 94.81947 -245.086124)
		(width 0.127)
		(layer "F.Cu")
		(net "SAS_HDD_RX_N2")
	)
	(segment
		(start 353.464114 -130.21945)
		(end 353.89185 -130.21945)
		(width 0.127)
		(layer "F.Cu")
		(net "SAS_HDD_RX_N19")
	)
	(segment
		(start 353.89185 -130.21945)
		(end 354.0252 -130.0861)
		(width 0.127)
		(layer "F.Cu")
		(net "SAS_HDD_RX_N19")
	)
	(segment
		(start 357.463598 -130.44805)
		(end 357.590598 -130.57505)
		(width 0.127)
		(layer "F.Cu")
		(net "SAS_HDD_RX_N19")
	)
	(segment
		(start 354.0252 -130.0861)
		(end 357.336598 -130.0861)
		(width 0.127)
		(layer "F.Cu")
		(net "SAS_HDD_RX_N19")
	)
	(segment
		(start 357.590598 -130.57505)
		(end 358.925114 -130.57505)
		(width 0.127)
		(layer "F.Cu")
		(net "SAS_HDD_RX_N19")
	)
	(segment
		(start 357.463598 -130.2131)
		(end 357.463598 -130.44805)
		(width 0.127)
		(layer "F.Cu")
		(net "SAS_HDD_RX_N19")
	)
	(segment
		(start 357.336598 -130.0861)
		(end 357.463598 -130.2131)
		(width 0.127)
		(layer "F.Cu")
		(net "SAS_HDD_RX_N19")
	)
	(segment
		(start 325.913496 -130.2131)
		(end 325.913496 -130.44805)
		(width 0.127)
		(layer "F.Cu")
		(net "SAS_HDD_RX_N18")
	)
	(segment
		(start 326.040496 -130.57505)
		(end 327.375012 -130.57505)
		(width 0.127)
		(layer "F.Cu")
		(net "SAS_HDD_RX_N18")
	)
	(segment
		(start 322.509388 -130.21945)
		(end 322.644262 -130.084576)
		(width 0.127)
		(layer "F.Cu")
		(net "SAS_HDD_RX_N18")
	)
	(segment
		(start 325.913496 -130.44805)
		(end 326.040496 -130.57505)
		(width 0.127)
		(layer "F.Cu")
		(net "SAS_HDD_RX_N18")
	)
	(segment
		(start 321.914012 -130.21945)
		(end 322.509388 -130.21945)
		(width 0.127)
		(layer "F.Cu")
		(net "SAS_HDD_RX_N18")
	)
	(segment
		(start 322.644262 -130.084576)
		(end 325.784972 -130.084576)
		(width 0.127)
		(layer "F.Cu")
		(net "SAS_HDD_RX_N18")
	)
	(segment
		(start 325.784972 -130.084576)
		(end 325.913496 -130.2131)
		(width 0.127)
		(layer "F.Cu")
		(net "SAS_HDD_RX_N18")
	)
	(segment
		(start 189.109604 -130.57505)
		(end 187.775088 -130.57505)
		(width 0.127)
		(layer "F.Cu")
		(net "SAS_HDD_RX_N17")
	)
	(segment
		(start 189.469522 -130.0861)
		(end 189.363604 -130.0861)
		(width 0.127)
		(layer "F.Cu")
		(net "SAS_HDD_RX_N17")
	)
	(segment
		(start 189.236604 -130.44805)
		(end 189.109604 -130.57505)
		(width 0.127)
		(layer "F.Cu")
		(net "SAS_HDD_RX_N17")
	)
	(segment
		(start 189.236604 -130.2131)
		(end 189.236604 -130.44805)
		(width 0.127)
		(layer "F.Cu")
		(net "SAS_HDD_RX_N17")
	)
	(segment
		(start 189.602872 -130.21945)
		(end 189.469522 -130.0861)
		(width 0.127)
		(layer "F.Cu")
		(net "SAS_HDD_RX_N17")
	)
	(segment
		(start 189.934088 -130.21945)
		(end 189.602872 -130.21945)
		(width 0.127)
		(layer "F.Cu")
		(net "SAS_HDD_RX_N17")
	)
	(segment
		(start 189.363604 -130.0861)
		(end 189.236604 -130.2131)
		(width 0.127)
		(layer "F.Cu")
		(net "SAS_HDD_RX_N17")
	)
	(segment
		(start 157.559502 -130.57505)
		(end 156.224986 -130.57505)
		(width 0.127)
		(layer "F.Cu")
		(net "SAS_HDD_RX_N16")
	)
	(segment
		(start 158.05277 -130.21945)
		(end 157.91942 -130.0861)
		(width 0.127)
		(layer "F.Cu")
		(net "SAS_HDD_RX_N16")
	)
	(segment
		(start 157.686502 -130.2131)
		(end 157.686502 -130.44805)
		(width 0.127)
		(layer "F.Cu")
		(net "SAS_HDD_RX_N16")
	)
	(segment
		(start 157.813502 -130.0861)
		(end 157.686502 -130.2131)
		(width 0.127)
		(layer "F.Cu")
		(net "SAS_HDD_RX_N16")
	)
	(segment
		(start 157.91942 -130.0861)
		(end 157.813502 -130.0861)
		(width 0.127)
		(layer "F.Cu")
		(net "SAS_HDD_RX_N16")
	)
	(segment
		(start 158.383986 -130.21945)
		(end 158.05277 -130.21945)
		(width 0.127)
		(layer "F.Cu")
		(net "SAS_HDD_RX_N16")
	)
	(segment
		(start 157.686502 -130.44805)
		(end 157.559502 -130.57505)
		(width 0.127)
		(layer "F.Cu")
		(net "SAS_HDD_RX_N16")
	)
	(segment
		(start 126.0094 -130.57505)
		(end 124.674884 -130.57505)
		(width 0.127)
		(layer "F.Cu")
		(net "SAS_HDD_RX_N15")
	)
	(segment
		(start 126.1364 -130.44805)
		(end 126.0094 -130.57505)
		(width 0.127)
		(layer "F.Cu")
		(net "SAS_HDD_RX_N15")
	)
	(segment
		(start 126.502668 -130.21945)
		(end 126.369318 -130.0861)
		(width 0.127)
		(layer "F.Cu")
		(net "SAS_HDD_RX_N15")
	)
	(segment
		(start 126.833884 -130.21945)
		(end 126.502668 -130.21945)
		(width 0.127)
		(layer "F.Cu")
		(net "SAS_HDD_RX_N15")
	)
	(segment
		(start 126.369318 -130.0861)
		(end 126.2634 -130.0861)
		(width 0.127)
		(layer "F.Cu")
		(net "SAS_HDD_RX_N15")
	)
	(segment
		(start 126.1364 -130.2131)
		(end 126.1364 -130.44805)
		(width 0.127)
		(layer "F.Cu")
		(net "SAS_HDD_RX_N15")
	)
	(segment
		(start 126.2634 -130.0861)
		(end 126.1364 -130.2131)
		(width 0.127)
		(layer "F.Cu")
		(net "SAS_HDD_RX_N15")
	)
	(segment
		(start 94.713552 -130.0861)
		(end 94.586552 -130.2131)
		(width 0.127)
		(layer "F.Cu")
		(net "SAS_HDD_RX_N14")
	)
	(segment
		(start 95.284036 -130.21945)
		(end 94.95282 -130.21945)
		(width 0.127)
		(layer "F.Cu")
		(net "SAS_HDD_RX_N14")
	)
	(segment
		(start 94.81947 -130.0861)
		(end 94.713552 -130.0861)
		(width 0.127)
		(layer "F.Cu")
		(net "SAS_HDD_RX_N14")
	)
	(segment
		(start 94.586552 -130.2131)
		(end 94.586552 -130.44805)
		(width 0.127)
		(layer "F.Cu")
		(net "SAS_HDD_RX_N14")
	)
	(segment
		(start 94.95282 -130.21945)
		(end 94.81947 -130.0861)
		(width 0.127)
		(layer "F.Cu")
		(net "SAS_HDD_RX_N14")
	)
	(segment
		(start 94.586552 -130.44805)
		(end 94.459552 -130.57505)
		(width 0.127)
		(layer "F.Cu")
		(net "SAS_HDD_RX_N14")
	)
	(segment
		(start 94.459552 -130.57505)
		(end 93.125036 -130.57505)
		(width 0.127)
		(layer "F.Cu")
		(net "SAS_HDD_RX_N14")
	)
	(segment
		(start 63.269368 -130.0861)
		(end 63.16345 -130.0861)
		(width 0.127)
		(layer "F.Cu")
		(net "SAS_HDD_RX_N13")
	)
	(segment
		(start 62.90945 -130.57505)
		(end 61.574934 -130.57505)
		(width 0.127)
		(layer "F.Cu")
		(net "SAS_HDD_RX_N13")
	)
	(segment
		(start 63.733934 -130.21945)
		(end 63.402718 -130.21945)
		(width 0.127)
		(layer "F.Cu")
		(net "SAS_HDD_RX_N13")
	)
	(segment
		(start 63.16345 -130.0861)
		(end 63.03645 -130.2131)
		(width 0.127)
		(layer "F.Cu")
		(net "SAS_HDD_RX_N13")
	)
	(segment
		(start 63.03645 -130.2131)
		(end 63.03645 -130.44805)
		(width 0.127)
		(layer "F.Cu")
		(net "SAS_HDD_RX_N13")
	)
	(segment
		(start 63.402718 -130.21945)
		(end 63.269368 -130.0861)
		(width 0.127)
		(layer "F.Cu")
		(net "SAS_HDD_RX_N13")
	)
	(segment
		(start 63.03645 -130.44805)
		(end 62.90945 -130.57505)
		(width 0.127)
		(layer "F.Cu")
		(net "SAS_HDD_RX_N13")
	)
	(segment
		(start 31.359602 -130.57505)
		(end 30.025086 -130.57505)
		(width 0.127)
		(layer "F.Cu")
		(net "SAS_HDD_RX_N12")
	)
	(segment
		(start 32.184086 -130.21945)
		(end 31.85287 -130.21945)
		(width 0.127)
		(layer "F.Cu")
		(net "SAS_HDD_RX_N12")
	)
	(segment
		(start 31.486602 -130.44805)
		(end 31.359602 -130.57505)
		(width 0.127)
		(layer "F.Cu")
		(net "SAS_HDD_RX_N12")
	)
	(segment
		(start 31.85287 -130.21945)
		(end 31.71952 -130.0861)
		(width 0.127)
		(layer "F.Cu")
		(net "SAS_HDD_RX_N12")
	)
	(segment
		(start 31.71952 -130.0861)
		(end 31.613602 -130.0861)
		(width 0.127)
		(layer "F.Cu")
		(net "SAS_HDD_RX_N12")
	)
	(segment
		(start 31.486602 -130.2131)
		(end 31.486602 -130.44805)
		(width 0.127)
		(layer "F.Cu")
		(net "SAS_HDD_RX_N12")
	)
	(segment
		(start 31.613602 -130.0861)
		(end 31.486602 -130.2131)
		(width 0.127)
		(layer "F.Cu")
		(net "SAS_HDD_RX_N12")
	)
	(segment
		(start 480.102926 -245.219474)
		(end 480.236276 -245.086124)
		(width 0.127)
		(layer "F.Cu")
		(net "SAS_HDD_RX_N11")
	)
	(segment
		(start 479.664014 -245.219474)
		(end 480.102926 -245.219474)
		(width 0.127)
		(layer "F.Cu")
		(net "SAS_HDD_RX_N11")
	)
	(segment
		(start 483.663498 -245.213124)
		(end 483.663498 -245.448074)
		(width 0.127)
		(layer "F.Cu")
		(net "SAS_HDD_RX_N11")
	)
	(segment
		(start 480.236276 -245.086124)
		(end 483.536498 -245.086124)
		(width 0.127)
		(layer "F.Cu")
		(net "SAS_HDD_RX_N11")
	)
	(segment
		(start 483.790498 -245.575074)
		(end 485.125014 -245.575074)
		(width 0.127)
		(layer "F.Cu")
		(net "SAS_HDD_RX_N11")
	)
	(segment
		(start 483.663498 -245.448074)
		(end 483.790498 -245.575074)
		(width 0.127)
		(layer "F.Cu")
		(net "SAS_HDD_RX_N11")
	)
	(segment
		(start 483.536498 -245.086124)
		(end 483.663498 -245.213124)
		(width 0.127)
		(layer "F.Cu")
		(net "SAS_HDD_RX_N11")
	)
	(segment
		(start 452.113396 -245.448074)
		(end 452.240396 -245.575074)
		(width 0.127)
		(layer "F.Cu")
		(net "SAS_HDD_RX_N10")
	)
	(segment
		(start 448.613276 -245.086124)
		(end 451.986396 -245.086124)
		(width 0.127)
		(layer "F.Cu")
		(net "SAS_HDD_RX_N10")
	)
	(segment
		(start 448.113912 -245.219474)
		(end 448.479926 -245.219474)
		(width 0.127)
		(layer "F.Cu")
		(net "SAS_HDD_RX_N10")
	)
	(segment
		(start 448.479926 -245.219474)
		(end 448.613276 -245.086124)
		(width 0.127)
		(layer "F.Cu")
		(net "SAS_HDD_RX_N10")
	)
	(segment
		(start 452.113396 -245.213124)
		(end 452.113396 -245.448074)
		(width 0.127)
		(layer "F.Cu")
		(net "SAS_HDD_RX_N10")
	)
	(segment
		(start 451.986396 -245.086124)
		(end 452.113396 -245.213124)
		(width 0.127)
		(layer "F.Cu")
		(net "SAS_HDD_RX_N10")
	)
	(segment
		(start 452.240396 -245.575074)
		(end 453.574912 -245.575074)
		(width 0.127)
		(layer "F.Cu")
		(net "SAS_HDD_RX_N10")
	)
	(segment
		(start 63.03645 -245.448074)
		(end 62.90945 -245.575074)
		(width 0.127)
		(layer "F.Cu")
		(net "SAS_HDD_RX_N1")
	)
	(segment
		(start 63.269368 -245.086124)
		(end 63.16345 -245.086124)
		(width 0.127)
		(layer "F.Cu")
		(net "SAS_HDD_RX_N1")
	)
	(segment
		(start 62.90945 -245.575074)
		(end 61.574934 -245.575074)
		(width 0.127)
		(layer "F.Cu")
		(net "SAS_HDD_RX_N1")
	)
	(segment
		(start 63.03645 -245.213124)
		(end 63.03645 -245.448074)
		(width 0.127)
		(layer "F.Cu")
		(net "SAS_HDD_RX_N1")
	)
	(segment
		(start 63.16345 -245.086124)
		(end 63.03645 -245.213124)
		(width 0.127)
		(layer "F.Cu")
		(net "SAS_HDD_RX_N1")
	)
	(segment
		(start 63.733934 -245.219474)
		(end 63.402718 -245.219474)
		(width 0.127)
		(layer "F.Cu")
		(net "SAS_HDD_RX_N1")
	)
	(segment
		(start 63.402718 -245.219474)
		(end 63.269368 -245.086124)
		(width 0.127)
		(layer "F.Cu")
		(net "SAS_HDD_RX_N1")
	)
	(segment
		(start 31.85287 -245.219474)
		(end 31.71952 -245.086124)
		(width 0.127)
		(layer "F.Cu")
		(net "SAS_HDD_RX_N0")
	)
	(segment
		(start 32.184086 -245.219474)
		(end 31.85287 -245.219474)
		(width 0.127)
		(layer "F.Cu")
		(net "SAS_HDD_RX_N0")
	)
	(segment
		(start 31.613602 -245.086124)
		(end 31.486602 -245.213124)
		(width 0.127)
		(layer "F.Cu")
		(net "SAS_HDD_RX_N0")
	)
	(segment
		(start 31.486602 -245.448074)
		(end 31.359602 -245.575074)
		(width 0.127)
		(layer "F.Cu")
		(net "SAS_HDD_RX_N0")
	)
	(segment
		(start 31.71952 -245.086124)
		(end 31.613602 -245.086124)
		(width 0.127)
		(layer "F.Cu")
		(net "SAS_HDD_RX_N0")
	)
	(segment
		(start 31.486602 -245.213124)
		(end 31.486602 -245.448074)
		(width 0.127)
		(layer "F.Cu")
		(net "SAS_HDD_RX_N0")
	)
	(segment
		(start 31.359602 -245.575074)
		(end 30.025086 -245.575074)
		(width 0.127)
		(layer "F.Cu")
		(net "SAS_HDD_RX_N0")
	)
	(segment
		(start 286.1945 -328.0918)
		(end 286.1945 -327.29678)
		(width 0.254)
		(layer "F.Cu")
		(net "PWM_OUT_FAN3")
	)
	(segment
		(start 286.1945 -327.29678)
		(end 286.21228 -327.279)
		(width 0.254)
		(layer "F.Cu")
		(net "PWM_OUT_FAN3")
	)
	(segment
		(start 419.73754 -367.818416)
		(end 419.584124 -367.665)
		(width 0.254)
		(layer "F.Cu")
		(net "PWM_OUT_FAN3")
	)
	(segment
		(start 419.73754 -369.1255)
		(end 419.73754 -367.818416)
		(width 0.254)
		(layer "F.Cu")
		(net "PWM_OUT_FAN3")
	)
	(segment
		(start 286.11195 -328.17435)
		(end 286.1945 -328.0918)
		(width 0.254)
		(layer "F.Cu")
		(net "PWM_OUT_FAN3")
	)
	(segment
		(start 283.4894 -328.17435)
		(end 286.11195 -328.17435)
		(width 0.254)
		(layer "F.Cu")
		(net "PWM_OUT_FAN3")
	)
	(segment
		(start 419.584124 -362.959142)
		(end 419.584124 -367.665)
		(width 0.254)
		(layer "F.Cu")
		(net "PWM_OUT_FAN3")
	)
	(via
		(at 419.584124 -362.959142)
		(size 0.5588)
		(drill 0.3048)
		(layers "F.Cu" "B.Cu")
		(net "PWM_OUT_FAN3")
	)
	(via
		(at 419.584124 -367.665)
		(size 0.6604)
		(drill 0.3302)
		(layers "F.Cu" "B.Cu")
		(net "PWM_OUT_FAN3")
	)
	(via
		(at 286.21228 -327.279)
		(size 0.5588)
		(drill 0.3048)
		(layers "F.Cu" "B.Cu")
		(net "PWM_OUT_FAN3")
	)
	(segment
		(start 320.4718 -360.426)
		(end 323.9008 -360.426)
		(width 0.254)
		(layer "B.Cu")
		(net "PWM_OUT_FAN3")
	)
	(segment
		(start 302.9966 -330.835)
		(end 313.534806 -341.373206)
		(width 0.254)
		(layer "B.Cu")
		(net "PWM_OUT_FAN3")
	)
	(segment
		(start 286.21228 -327.279)
		(end 286.31388 -327.3806)
		(width 0.254)
		(layer "B.Cu")
		(net "PWM_OUT_FAN3")
	)
	(segment
		(start 341.2998 -362.6612)
		(end 342.6714 -361.2896)
		(width 0.254)
		(layer "B.Cu")
		(net "PWM_OUT_FAN3")
	)
	(segment
		(start 286.31388 -327.3806)
		(end 288.604452 -327.3806)
		(width 0.254)
		(layer "B.Cu")
		(net "PWM_OUT_FAN3")
	)
	(segment
		(start 342.6714 -361.2896)
		(end 417.785804 -361.2896)
		(width 0.254)
		(layer "B.Cu")
		(net "PWM_OUT_FAN3")
	)
	(segment
		(start 326.136 -362.6612)
		(end 341.2998 -362.6612)
		(width 0.254)
		(layer "B.Cu")
		(net "PWM_OUT_FAN3")
	)
	(segment
		(start 313.534806 -341.373206)
		(end 313.534806 -353.489006)
		(width 0.254)
		(layer "B.Cu")
		(net "PWM_OUT_FAN3")
	)
	(segment
		(start 323.9008 -360.426)
		(end 326.136 -362.6612)
		(width 0.254)
		(layer "B.Cu")
		(net "PWM_OUT_FAN3")
	)
	(segment
		(start 419.455346 -362.959142)
		(end 419.584124 -362.959142)
		(width 0.254)
		(layer "B.Cu")
		(net "PWM_OUT_FAN3")
	)
	(segment
		(start 313.534806 -353.489006)
		(end 320.4718 -360.426)
		(width 0.254)
		(layer "B.Cu")
		(net "PWM_OUT_FAN3")
	)
	(segment
		(start 417.785804 -361.2896)
		(end 419.455346 -362.959142)
		(width 0.254)
		(layer "B.Cu")
		(net "PWM_OUT_FAN3")
	)
	(segment
		(start 288.604452 -327.3806)
		(end 292.058852 -330.835)
		(width 0.254)
		(layer "B.Cu")
		(net "PWM_OUT_FAN3")
	)
	(segment
		(start 292.058852 -330.835)
		(end 302.9966 -330.835)
		(width 0.254)
		(layer "B.Cu")
		(net "PWM_OUT_FAN3")
	)
	(segment
		(start 274.65655 -329.4126)
		(end 274.0279 -330.04125)
		(width 0.254)
		(layer "F.Cu")
		(net "PWM_OUT_FAN2")
	)
	(segment
		(start 275.82495 -330.1238)
		(end 275.11375 -329.4126)
		(width 0.254)
		(layer "F.Cu")
		(net "PWM_OUT_FAN2")
	)
	(segment
		(start 275.11375 -329.4126)
		(end 274.65655 -329.4126)
		(width 0.254)
		(layer "F.Cu")
		(net "PWM_OUT_FAN2")
	)
	(segment
		(start 324.427596 -373.761)
		(end 323.563996 -372.8974)
		(width 0.254)
		(layer "F.Cu")
		(net "PWM_OUT_FAN2")
	)
	(segment
		(start 323.563996 -372.8974)
		(end 323.563996 -361.442)
		(width 0.254)
		(layer "F.Cu")
		(net "PWM_OUT_FAN2")
	)
	(segment
		(start 324.988936 -373.761)
		(end 326.294496 -373.761)
		(width 0.254)
		(layer "F.Cu")
		(net "PWM_OUT_FAN2")
	)
	(segment
		(start 324.988936 -373.761)
		(end 324.427596 -373.761)
		(width 0.254)
		(layer "F.Cu")
		(net "PWM_OUT_FAN2")
	)
	(segment
		(start 277.8506 -330.1238)
		(end 275.82495 -330.1238)
		(width 0.254)
		(layer "F.Cu")
		(net "PWM_OUT_FAN2")
	)
	(segment
		(start 274.0279 -330.04125)
		(end 274.84832 -330.04125)
		(width 0.254)
		(layer "F.Cu")
		(net "PWM_OUT_FAN2")
	)
	(via
		(at 274.84832 -330.04125)
		(size 0.5588)
		(drill 0.3048)
		(layers "F.Cu" "B.Cu")
		(net "PWM_OUT_FAN2")
	)
	(via
		(at 324.988936 -373.761)
		(size 0.6604)
		(drill 0.3302)
		(layers "F.Cu" "B.Cu")
		(net "PWM_OUT_FAN2")
	)
	(via
		(at 323.563996 -361.442)
		(size 0.5588)
		(drill 0.3048)
		(layers "F.Cu" "B.Cu")
		(net "PWM_OUT_FAN2")
	)
	(segment
		(start 285.75 -328.8538)
		(end 276.03577 -328.8538)
		(width 0.254)
		(layer "B.Cu")
		(net "PWM_OUT_FAN2")
	)
	(segment
		(start 294.924734 -338.028534)
		(end 285.75 -328.8538)
		(width 0.254)
		(layer "B.Cu")
		(net "PWM_OUT_FAN2")
	)
	(segment
		(start 309.021734 -338.028534)
		(end 294.924734 -338.028534)
		(width 0.254)
		(layer "B.Cu")
		(net "PWM_OUT_FAN2")
	)
	(segment
		(start 312.300366 -353.575366)
		(end 312.300366 -341.307166)
		(width 0.254)
		(layer "B.Cu")
		(net "PWM_OUT_FAN2")
	)
	(segment
		(start 320.167 -361.442)
		(end 312.300366 -353.575366)
		(width 0.254)
		(layer "B.Cu")
		(net "PWM_OUT_FAN2")
	)
	(segment
		(start 323.563996 -361.442)
		(end 320.167 -361.442)
		(width 0.254)
		(layer "B.Cu")
		(net "PWM_OUT_FAN2")
	)
	(segment
		(start 276.03577 -328.8538)
		(end 274.84832 -330.04125)
		(width 0.254)
		(layer "B.Cu")
		(net "PWM_OUT_FAN2")
	)
	(segment
		(start 312.300366 -341.307166)
		(end 309.021734 -338.028534)
		(width 0.254)
		(layer "B.Cu")
		(net "PWM_OUT_FAN2")
	)
	(segment
		(start 274.40763 -330.962)
		(end 275.66112 -330.962)
		(width 0.254)
		(layer "F.Cu")
		(net "PWM_OUT_FAN1")
	)
	(segment
		(start 277.8506 -331.42428)
		(end 276.1234 -331.42428)
		(width 0.254)
		(layer "F.Cu")
		(net "PWM_OUT_FAN1")
	)
	(segment
		(start 275.1074 -331.6224)
		(end 274.30857 -331.6224)
		(width 0.254)
		(layer "F.Cu")
		(net "PWM_OUT_FAN1")
	)
	(segment
		(start 274.30857 -331.6224)
		(end 274.0279 -331.34173)
		(width 0.254)
		(layer "F.Cu")
		(net "PWM_OUT_FAN1")
	)
	(segment
		(start 275.66112 -330.962)
		(end 276.1234 -331.42428)
		(width 0.254)
		(layer "F.Cu")
		(net "PWM_OUT_FAN1")
	)
	(segment
		(start 161.6075 -371.983)
		(end 161.6075 -372.999)
		(width 0.254)
		(layer "F.Cu")
		(net "PWM_OUT_FAN1")
	)
	(segment
		(start 274.0279 -331.34173)
		(end 274.40763 -330.962)
		(width 0.254)
		(layer "F.Cu")
		(net "PWM_OUT_FAN1")
	)
	(via
		(at 275.1074 -331.6224)
		(size 0.5588)
		(drill 0.3048)
		(layers "F.Cu" "B.Cu")
		(net "PWM_OUT_FAN1")
	)
	(via
		(at 276.1234 -331.42428)
		(size 0.6604)
		(drill 0.3302)
		(layers "F.Cu" "B.Cu")
		(net "PWM_OUT_FAN1")
	)
	(via
		(at 161.6075 -372.999)
		(size 0.5588)
		(drill 0.3048)
		(layers "F.Cu" "B.Cu")
		(net "PWM_OUT_FAN1")
	)
	(segment
		(start 182.656226 -371.760496)
		(end 182.656226 -370.496846)
		(width 0.254)
		(layer "In5.Cu")
		(net "PWM_OUT_FAN1")
	)
	(segment
		(start 182.656226 -370.496846)
		(end 183.837072 -369.316)
		(width 0.254)
		(layer "In5.Cu")
		(net "PWM_OUT_FAN1")
	)
	(segment
		(start 161.6075 -372.999)
		(end 161.6075 -373.6975)
		(width 0.254)
		(layer "In5.Cu")
		(net "PWM_OUT_FAN1")
	)
	(segment
		(start 263.27735 -372.247414)
		(end 268.411198 -367.113566)
		(width 0.254)
		(layer "In5.Cu")
		(net "PWM_OUT_FAN1")
	)
	(segment
		(start 202.91044 -367.945162)
		(end 208.167478 -373.2022)
		(width 0.254)
		(layer "In5.Cu")
		(net "PWM_OUT_FAN1")
	)
	(segment
		(start 268.411198 -367.113566)
		(end 268.411198 -357.89235)
		(width 0.254)
		(layer "In5.Cu")
		(net "PWM_OUT_FAN1")
	)
	(segment
		(start 177.038 -374.269)
		(end 180.147722 -374.269)
		(width 0.254)
		(layer "In5.Cu")
		(net "PWM_OUT_FAN1")
	)
	(segment
		(start 238.540544 -373.2022)
		(end 239.64138 -374.303036)
		(width 0.254)
		(layer "In5.Cu")
		(net "PWM_OUT_FAN1")
	)
	(segment
		(start 186.944 -369.316)
		(end 188.314838 -367.945162)
		(width 0.254)
		(layer "In5.Cu")
		(net "PWM_OUT_FAN1")
	)
	(segment
		(start 262.2042 -372.247414)
		(end 263.27735 -372.247414)
		(width 0.254)
		(layer "In5.Cu")
		(net "PWM_OUT_FAN1")
	)
	(segment
		(start 239.64138 -374.303036)
		(end 260.148578 -374.303036)
		(width 0.254)
		(layer "In5.Cu")
		(net "PWM_OUT_FAN1")
	)
	(segment
		(start 208.167478 -373.2022)
		(end 238.540544 -373.2022)
		(width 0.254)
		(layer "In5.Cu")
		(net "PWM_OUT_FAN1")
	)
	(segment
		(start 275.40712 -350.896428)
		(end 275.40712 -331.92212)
		(width 0.254)
		(layer "In5.Cu")
		(net "PWM_OUT_FAN1")
	)
	(segment
		(start 183.837072 -369.316)
		(end 186.944 -369.316)
		(width 0.254)
		(layer "In5.Cu")
		(net "PWM_OUT_FAN1")
	)
	(segment
		(start 180.147722 -374.269)
		(end 182.656226 -371.760496)
		(width 0.254)
		(layer "In5.Cu")
		(net "PWM_OUT_FAN1")
	)
	(segment
		(start 188.314838 -367.945162)
		(end 202.91044 -367.945162)
		(width 0.254)
		(layer "In5.Cu")
		(net "PWM_OUT_FAN1")
	)
	(segment
		(start 176.120552 -375.186448)
		(end 177.038 -374.269)
		(width 0.254)
		(layer "In5.Cu")
		(net "PWM_OUT_FAN1")
	)
	(segment
		(start 268.411198 -357.89235)
		(end 275.40712 -350.896428)
		(width 0.254)
		(layer "In5.Cu")
		(net "PWM_OUT_FAN1")
	)
	(segment
		(start 161.6075 -373.6975)
		(end 163.096448 -375.186448)
		(width 0.254)
		(layer "In5.Cu")
		(net "PWM_OUT_FAN1")
	)
	(segment
		(start 163.096448 -375.186448)
		(end 176.120552 -375.186448)
		(width 0.254)
		(layer "In5.Cu")
		(net "PWM_OUT_FAN1")
	)
	(segment
		(start 275.40712 -331.92212)
		(end 275.1074 -331.6224)
		(width 0.254)
		(layer "In5.Cu")
		(net "PWM_OUT_FAN1")
	)
	(segment
		(start 260.148578 -374.303036)
		(end 262.2042 -372.247414)
		(width 0.254)
		(layer "In5.Cu")
		(net "PWM_OUT_FAN1")
	)
	(via
		(at 427.482 -263.779)
		(size 0.6604)
		(drill 0.3302)
		(layers "F.Cu" "B.Cu")
		(net "P5V_HDD9")
	)
	(via
		(at 395.986 -263.779)
		(size 0.6604)
		(drill 0.3302)
		(layers "F.Cu" "B.Cu")
		(net "P5V_HDD8")
	)
	(via
		(at 364.363 -263.779)
		(size 0.6604)
		(drill 0.3302)
		(layers "F.Cu" "B.Cu")
		(net "P5V_HDD7")
	)
	(via
		(at 332.867 -263.779)
		(size 0.6604)
		(drill 0.3302)
		(layers "F.Cu" "B.Cu")
		(net "P5V_HDD6")
	)
	(via
		(at 179.7812 -263.7028)
		(size 0.6604)
		(drill 0.3302)
		(layers "F.Cu" "B.Cu")
		(net "P5V_HDD5")
	)
	(via
		(at 148.2344 -263.779)
		(size 0.6604)
		(drill 0.3302)
		(layers "F.Cu" "B.Cu")
		(net "P5V_HDD4")
	)
	(via
		(at 477.1644 -33.6804)
		(size 0.6604)
		(drill 0.3302)
		(layers "F.Cu" "B.Cu")
		(net "P5V_HDD35")
	)
	(via
		(at 458.978 -33.782)
		(size 0.6604)
		(drill 0.3302)
		(layers "F.Cu" "B.Cu")
		(net "P5V_HDD34")
	)
	(via
		(at 427.482 -33.782)
		(size 0.6604)
		(drill 0.3302)
		(layers "F.Cu" "B.Cu")
		(net "P5V_HDD33")
	)
	(via
		(at 395.986 -33.782)
		(size 0.6604)
		(drill 0.3302)
		(layers "F.Cu" "B.Cu")
		(net "P5V_HDD32")
	)
	(via
		(at 364.363 -33.782)
		(size 0.6604)
		(drill 0.3302)
		(layers "F.Cu" "B.Cu")
		(net "P5V_HDD31")
	)
	(via
		(at 332.867 -33.782)
		(size 0.6604)
		(drill 0.3302)
		(layers "F.Cu" "B.Cu")
		(net "P5V_HDD30")
	)
	(via
		(at 116.6114 -263.7536)
		(size 0.6604)
		(drill 0.3302)
		(layers "F.Cu" "B.Cu")
		(net "P5V_HDD3")
	)
	(via
		(at 179.815998 -33.7312)
		(size 0.6604)
		(drill 0.3302)
		(layers "F.Cu" "B.Cu")
		(net "P5V_HDD29")
	)
	(via
		(at 148.265896 -33.7566)
		(size 0.6604)
		(drill 0.3302)
		(layers "F.Cu" "B.Cu")
		(net "P5V_HDD28")
	)
	(via
		(at 116.6876 -33.8074)
		(size 0.6604)
		(drill 0.3302)
		(layers "F.Cu" "B.Cu")
		(net "P5V_HDD27")
	)
	(via
		(at 85.165946 -33.782)
		(size 0.6604)
		(drill 0.3302)
		(layers "F.Cu" "B.Cu")
		(net "P5V_HDD26")
	)
	(via
		(at 53.58384 -33.7312)
		(size 0.6604)
		(drill 0.3302)
		(layers "F.Cu" "B.Cu")
		(net "P5V_HDD25")
	)
	(via
		(at 22.0218 -33.782)
		(size 0.6604)
		(drill 0.3302)
		(layers "F.Cu" "B.Cu")
		(net "P5V_HDD24")
	)
	(via
		(at 477.1644 -148.6154)
		(size 0.6604)
		(drill 0.3302)
		(layers "F.Cu" "B.Cu")
		(net "P5V_HDD23")
	)
	(via
		(at 458.978 -148.844)
		(size 0.6604)
		(drill 0.3302)
		(layers "F.Cu" "B.Cu")
		(net "P5V_HDD22")
	)
	(via
		(at 427.482 -148.844)
		(size 0.6604)
		(drill 0.3302)
		(layers "F.Cu" "B.Cu")
		(net "P5V_HDD21")
	)
	(via
		(at 395.986 -148.844)
		(size 0.6604)
		(drill 0.3302)
		(layers "F.Cu" "B.Cu")
		(net "P5V_HDD20")
	)
	(via
		(at 85.1154 -263.779)
		(size 0.6604)
		(drill 0.3302)
		(layers "F.Cu" "B.Cu")
		(net "P5V_HDD2")
	)
	(via
		(at 364.363 -148.844)
		(size 0.6604)
		(drill 0.3302)
		(layers "F.Cu" "B.Cu")
		(net "P5V_HDD19")
	)
	(via
		(at 332.867 -148.844)
		(size 0.6604)
		(drill 0.3302)
		(layers "F.Cu" "B.Cu")
		(net "P5V_HDD18")
	)
	(via
		(at 179.8066 -148.6408)
		(size 0.6604)
		(drill 0.3302)
		(layers "F.Cu" "B.Cu")
		(net "P5V_HDD17")
	)
	(via
		(at 148.2344 -148.6408)
		(size 0.6604)
		(drill 0.3302)
		(layers "F.Cu" "B.Cu")
		(net "P5V_HDD16")
	)
	(via
		(at 116.713 -148.6916)
		(size 0.6604)
		(drill 0.3302)
		(layers "F.Cu" "B.Cu")
		(net "P5V_HDD15")
	)
	(via
		(at 85.16366 -148.6662)
		(size 0.6604)
		(drill 0.3302)
		(layers "F.Cu" "B.Cu")
		(net "P5V_HDD14")
	)
	(via
		(at 53.594 -148.7424)
		(size 0.6604)
		(drill 0.3302)
		(layers "F.Cu" "B.Cu")
		(net "P5V_HDD13")
	)
	(via
		(at 21.971 -148.6916)
		(size 0.6604)
		(drill 0.3302)
		(layers "F.Cu" "B.Cu")
		(net "P5V_HDD12")
	)
	(via
		(at 477.0882 -263.7282)
		(size 0.6604)
		(drill 0.3302)
		(layers "F.Cu" "B.Cu")
		(net "P5V_HDD11")
	)
	(via
		(at 458.978 -263.779)
		(size 0.6604)
		(drill 0.3302)
		(layers "F.Cu" "B.Cu")
		(net "P5V_HDD10")
	)
	(via
		(at 53.594 -263.7028)
		(size 0.6604)
		(drill 0.3302)
		(layers "F.Cu" "B.Cu")
		(net "P5V_HDD1")
	)
	(via
		(at 433.451 -271.526)
		(size 0.6604)
		(drill 0.3302)
		(layers "F.Cu" "B.Cu")
		(net "P12V_HDD9")
	)
	(via
		(at 401.955 -271.526)
		(size 0.6604)
		(drill 0.3302)
		(layers "F.Cu" "B.Cu")
		(net "P12V_HDD8")
	)
	(via
		(at 370.332 -271.526)
		(size 0.6604)
		(drill 0.3302)
		(layers "F.Cu" "B.Cu")
		(net "P12V_HDD7")
	)
	(via
		(at 338.836 -271.526)
		(size 0.6604)
		(drill 0.3302)
		(layers "F.Cu" "B.Cu")
		(net "P12V_HDD6")
	)
	(via
		(at 175.26 -267.589)
		(size 0.6604)
		(drill 0.3302)
		(layers "F.Cu" "B.Cu")
		(net "P12V_HDD5")
	)
	(via
		(at 143.764 -267.589)
		(size 0.6604)
		(drill 0.3302)
		(layers "F.Cu" "B.Cu")
		(net "P12V_HDD4")
	)
	(via
		(at 472.567 -37.465)
		(size 0.6604)
		(drill 0.3302)
		(layers "F.Cu" "B.Cu")
		(net "P12V_HDD35")
	)
	(via
		(at 464.947 -41.529)
		(size 0.6604)
		(drill 0.3302)
		(layers "F.Cu" "B.Cu")
		(net "P12V_HDD34")
	)
	(via
		(at 433.451 -41.529)
		(size 0.6604)
		(drill 0.3302)
		(layers "F.Cu" "B.Cu")
		(net "P12V_HDD33")
	)
	(via
		(at 398.5006 -37.7698)
		(size 0.6604)
		(drill 0.3302)
		(layers "F.Cu" "B.Cu")
		(net "P12V_HDD32")
	)
	(via
		(at 370.332 -41.529)
		(size 0.6604)
		(drill 0.3302)
		(layers "F.Cu" "B.Cu")
		(net "P12V_HDD31")
	)
	(via
		(at 336.5246 -39.1414)
		(size 0.6604)
		(drill 0.3302)
		(layers "F.Cu" "B.Cu")
		(net "P12V_HDD30")
	)
	(via
		(at 112.141 -267.589)
		(size 0.6604)
		(drill 0.3302)
		(layers "F.Cu" "B.Cu")
		(net "P12V_HDD3")
	)
	(via
		(at 175.26 -37.592)
		(size 0.6604)
		(drill 0.3302)
		(layers "F.Cu" "B.Cu")
		(net "P12V_HDD29")
	)
	(via
		(at 143.764 -37.592)
		(size 0.6604)
		(drill 0.3302)
		(layers "F.Cu" "B.Cu")
		(net "P12V_HDD28")
	)
	(via
		(at 110.109 -34.163)
		(size 0.5588)
		(drill 0.3048)
		(layers "F.Cu" "B.Cu")
		(net "P12V_HDD27")
	)
	(via
		(at 112.141 -34.163)
		(size 0.5588)
		(drill 0.3048)
		(layers "F.Cu" "B.Cu")
		(net "P12V_HDD27")
	)
	(via
		(at 108.077 -18.4404)
		(size 0.5588)
		(drill 0.3048)
		(layers "F.Cu" "B.Cu")
		(net "P12V_HDD27")
	)
	(via
		(at 110.617 -18.4404)
		(size 0.5588)
		(drill 0.3048)
		(layers "F.Cu" "B.Cu")
		(net "P12V_HDD27")
	)
	(via
		(at 111.887 -18.4404)
		(size 0.5588)
		(drill 0.3048)
		(layers "F.Cu" "B.Cu")
		(net "P12V_HDD27")
	)
	(via
		(at 109.347 -18.4404)
		(size 0.5588)
		(drill 0.3048)
		(layers "F.Cu" "B.Cu")
		(net "P12V_HDD27")
	)
	(via
		(at 112.141 -37.592)
		(size 0.6604)
		(drill 0.3302)
		(layers "F.Cu" "B.Cu")
		(net "P12V_HDD27")
	)
	(via
		(at 111.125 -34.163)
		(size 0.5588)
		(drill 0.3048)
		(layers "F.Cu" "B.Cu")
		(net "P12V_HDD27")
	)
	(via
		(at 80.645 -37.592)
		(size 0.6604)
		(drill 0.3302)
		(layers "F.Cu" "B.Cu")
		(net "P12V_HDD26")
	)
	(via
		(at 49.022 -37.592)
		(size 0.6604)
		(drill 0.3302)
		(layers "F.Cu" "B.Cu")
		(net "P12V_HDD25")
	)
	(via
		(at 17.526 -37.592)
		(size 0.6604)
		(drill 0.3302)
		(layers "F.Cu" "B.Cu")
		(net "P12V_HDD24")
	)
	(via
		(at 472.567 -152.527)
		(size 0.6604)
		(drill 0.3302)
		(layers "F.Cu" "B.Cu")
		(net "P12V_HDD23")
	)
	(via
		(at 464.947 -156.591)
		(size 0.6604)
		(drill 0.3302)
		(layers "F.Cu" "B.Cu")
		(net "P12V_HDD22")
	)
	(via
		(at 433.451 -156.591)
		(size 0.6604)
		(drill 0.3302)
		(layers "F.Cu" "B.Cu")
		(net "P12V_HDD21")
	)
	(via
		(at 401.955 -156.591)
		(size 0.6604)
		(drill 0.3302)
		(layers "F.Cu" "B.Cu")
		(net "P12V_HDD20")
	)
	(via
		(at 80.645 -267.589)
		(size 0.6604)
		(drill 0.3302)
		(layers "F.Cu" "B.Cu")
		(net "P12V_HDD2")
	)
	(via
		(at 370.332 -156.591)
		(size 0.6604)
		(drill 0.3302)
		(layers "F.Cu" "B.Cu")
		(net "P12V_HDD19")
	)
	(via
		(at 338.836 -156.591)
		(size 0.6604)
		(drill 0.3302)
		(layers "F.Cu" "B.Cu")
		(net "P12V_HDD18")
	)
	(via
		(at 175.26 -152.527)
		(size 0.6604)
		(drill 0.3302)
		(layers "F.Cu" "B.Cu")
		(net "P12V_HDD17")
	)
	(via
		(at 143.764 -152.527)
		(size 0.6604)
		(drill 0.3302)
		(layers "F.Cu" "B.Cu")
		(net "P12V_HDD16")
	)
	(via
		(at 112.141 -152.527)
		(size 0.6604)
		(drill 0.3302)
		(layers "F.Cu" "B.Cu")
		(net "P12V_HDD15")
	)
	(via
		(at 80.645 -152.527)
		(size 0.6604)
		(drill 0.3302)
		(layers "F.Cu" "B.Cu")
		(net "P12V_HDD14")
	)
	(via
		(at 49.022 -152.527)
		(size 0.6604)
		(drill 0.3302)
		(layers "F.Cu" "B.Cu")
		(net "P12V_HDD13")
	)
	(via
		(at 17.526 -152.527)
		(size 0.6604)
		(drill 0.3302)
		(layers "F.Cu" "B.Cu")
		(net "P12V_HDD12")
	)
	(via
		(at 472.567 -267.589)
		(size 0.6604)
		(drill 0.3302)
		(layers "F.Cu" "B.Cu")
		(net "P12V_HDD11")
	)
	(via
		(at 464.947 -271.526)
		(size 0.6604)
		(drill 0.3302)
		(layers "F.Cu" "B.Cu")
		(net "P12V_HDD10")
	)
	(via
		(at 49.149 -267.589)
		(size 0.6604)
		(drill 0.3302)
		(layers "F.Cu" "B.Cu")
		(net "P12V_HDD1")
	)
	(segment
		(start 443.199774 -372.599966)
		(end 443.199774 -374.238774)
		(width 0.508)
		(layer "F.Cu")
		(net "P12V_FAN3")
	)
	(segment
		(start 443.199774 -365.461042)
		(end 443.199774 -367.09985)
		(width 0.508)
		(layer "F.Cu")
		(net "P12V_FAN3")
	)
	(segment
		(start 443.199774 -372.599966)
		(end 444.838582 -372.599966)
		(width 0.508)
		(layer "F.Cu")
		(net "P12V_FAN3")
	)
	(segment
		(start 443.199774 -370.961158)
		(end 443.199774 -372.599966)
		(width 0.508)
		(layer "F.Cu")
		(net "P12V_FAN3")
	)
	(segment
		(start 441.560966 -367.09985)
		(end 443.199774 -367.09985)
		(width 0.508)
		(layer "F.Cu")
		(net "P12V_FAN3")
	)
	(segment
		(start 443.199774 -367.09985)
		(end 444.838582 -367.09985)
		(width 0.508)
		(layer "F.Cu")
		(net "P12V_FAN3")
	)
	(segment
		(start 443.199774 -367.09985)
		(end 443.199774 -368.738658)
		(width 0.508)
		(layer "F.Cu")
		(net "P12V_FAN3")
	)
	(segment
		(start 441.560966 -372.599966)
		(end 443.199774 -372.599966)
		(width 0.508)
		(layer "F.Cu")
		(net "P12V_FAN3")
	)
	(via
		(at 444.024004 -358.521)
		(size 0.6604)
		(drill 0.3302)
		(layers "F.Cu" "B.Cu")
		(net "P12V_FAN3")
	)
	(segment
		(start 346.599764 -372.599966)
		(end 348.238572 -372.599966)
		(width 0.508)
		(layer "F.Cu")
		(net "P12V_FAN2")
	)
	(segment
		(start 346.599764 -367.09985)
		(end 348.238572 -367.09985)
		(width 0.508)
		(layer "F.Cu")
		(net "P12V_FAN2")
	)
	(segment
		(start 346.599764 -370.961158)
		(end 346.599764 -372.599966)
		(width 0.508)
		(layer "F.Cu")
		(net "P12V_FAN2")
	)
	(segment
		(start 344.960956 -372.599966)
		(end 346.599764 -372.599966)
		(width 0.508)
		(layer "F.Cu")
		(net "P12V_FAN2")
	)
	(segment
		(start 346.599764 -372.599966)
		(end 346.599764 -374.238774)
		(width 0.508)
		(layer "F.Cu")
		(net "P12V_FAN2")
	)
	(segment
		(start 346.599764 -365.461042)
		(end 346.599764 -367.09985)
		(width 0.508)
		(layer "F.Cu")
		(net "P12V_FAN2")
	)
	(segment
		(start 346.599764 -367.09985)
		(end 346.599764 -368.738658)
		(width 0.508)
		(layer "F.Cu")
		(net "P12V_FAN2")
	)
	(segment
		(start 344.960956 -367.09985)
		(end 346.599764 -367.09985)
		(width 0.508)
		(layer "F.Cu")
		(net "P12V_FAN2")
	)
	(via
		(at 346.804996 -358.775)
		(size 0.6604)
		(drill 0.3302)
		(layers "F.Cu" "B.Cu")
		(net "P12V_FAN2")
	)
	(segment
		(start 151.799798 -370.961158)
		(end 151.799798 -372.599966)
		(width 0.508)
		(layer "F.Cu")
		(net "P12V_FAN1")
	)
	(segment
		(start 150.16099 -372.599966)
		(end 151.799798 -372.599966)
		(width 0.508)
		(layer "F.Cu")
		(net "P12V_FAN1")
	)
	(segment
		(start 151.799798 -367.09985)
		(end 151.799798 -368.738658)
		(width 0.508)
		(layer "F.Cu")
		(net "P12V_FAN1")
	)
	(segment
		(start 150.16099 -367.09985)
		(end 151.799798 -367.09985)
		(width 0.508)
		(layer "F.Cu")
		(net "P12V_FAN1")
	)
	(segment
		(start 151.799798 -372.599966)
		(end 153.438606 -372.599966)
		(width 0.508)
		(layer "F.Cu")
		(net "P12V_FAN1")
	)
	(segment
		(start 151.799798 -367.09985)
		(end 153.438606 -367.09985)
		(width 0.508)
		(layer "F.Cu")
		(net "P12V_FAN1")
	)
	(segment
		(start 151.799798 -365.461042)
		(end 151.799798 -367.09985)
		(width 0.508)
		(layer "F.Cu")
		(net "P12V_FAN1")
	)
	(segment
		(start 151.799798 -372.599966)
		(end 151.799798 -374.238774)
		(width 0.508)
		(layer "F.Cu")
		(net "P12V_FAN1")
	)
	(via
		(at 138.988292 -360.8324)
		(size 0.6604)
		(drill 0.3302)
		(layers "F.Cu" "B.Cu")
		(net "P12V_FAN1")
	)
	(segment
		(start 175.0695 -363.22)
		(end 175.0695 -364.109)
		(width 0.254)
		(layer "F.Cu")
		(net "MB0_VCAP_R")
	)
	(segment
		(start 172.52188 -363.22)
		(end 172.39488 -363.093)
		(width 0.254)
		(layer "F.Cu")
		(net "MB0_VCAP_R")
	)
	(segment
		(start 174.010066 -366.161066)
		(end 173.0375 -365.1885)
		(width 0.254)
		(layer "F.Cu")
		(net "MB0_VCAP_R")
	)
	(segment
		(start 170.82008 -364.451392)
		(end 171.186856 -364.451392)
		(width 0.254)
		(layer "F.Cu")
		(net "MB0_VCAP_R")
	)
	(segment
		(start 171.831 -363.093)
		(end 171.831 -364.197138)
		(width 0.254)
		(layer "F.Cu")
		(net "MB0_VCAP_R")
	)
	(segment
		(start 173.0375 -363.22)
		(end 172.52188 -363.22)
		(width 0.254)
		(layer "F.Cu")
		(net "MB0_VCAP_R")
	)
	(segment
		(start 171.831 -364.197138)
		(end 171.576746 -364.451392)
		(width 0.254)
		(layer "F.Cu")
		(net "MB0_VCAP_R")
	)
	(segment
		(start 174.010066 -366.7125)
		(end 174.010066 -366.161066)
		(width 0.254)
		(layer "F.Cu")
		(net "MB0_VCAP_R")
	)
	(segment
		(start 170.6245 -363.22)
		(end 170.6245 -364.255812)
		(width 0.254)
		(layer "F.Cu")
		(net "MB0_VCAP_R")
	)
	(segment
		(start 173.0375 -364.109)
		(end 173.0375 -363.22)
		(width 0.254)
		(layer "F.Cu")
		(net "MB0_VCAP_R")
	)
	(segment
		(start 173.0375 -365.1885)
		(end 173.0375 -364.109)
		(width 0.254)
		(layer "F.Cu")
		(net "MB0_VCAP_R")
	)
	(segment
		(start 171.576746 -364.451392)
		(end 171.186856 -364.451392)
		(width 0.254)
		(layer "F.Cu")
		(net "MB0_VCAP_R")
	)
	(segment
		(start 172.39488 -363.093)
		(end 171.831 -363.093)
		(width 0.254)
		(layer "F.Cu")
		(net "MB0_VCAP_R")
	)
	(segment
		(start 170.6245 -364.255812)
		(end 170.82008 -364.451392)
		(width 0.254)
		(layer "F.Cu")
		(net "MB0_VCAP_R")
	)
	(via
		(at 173.0375 -364.109)
		(size 0.5588)
		(drill 0.3048)
		(layers "F.Cu" "B.Cu")
		(net "MB0_VCAP_R")
	)
	(via
		(at 171.186856 -364.451392)
		(size 0.6604)
		(drill 0.3302)
		(layers "F.Cu" "B.Cu")
		(net "MB0_VCAP_R")
	)
	(via
		(at 175.0695 -364.109)
		(size 0.5588)
		(drill 0.3048)
		(layers "F.Cu" "B.Cu")
		(net "MB0_VCAP_R")
	)
	(segment
		(start 173.0375 -364.109)
		(end 175.0695 -364.109)
		(width 0.254)
		(layer "In5.Cu")
		(net "MB0_VCAP_R")
	)
	(segment
		(start 177.419 -364.236)
		(end 177.419 -363.474)
		(width 0.254)
		(layer "F.Cu")
		(net "MB0_TIME_R")
	)
	(segment
		(start 177.419 -362.1405)
		(end 177.419 -363.474)
		(width 0.254)
		(layer "F.Cu")
		(net "MB0_TIME_R")
	)
	(segment
		(start 175.509936 -366.145064)
		(end 177.419 -364.236)
		(width 0.254)
		(layer "F.Cu")
		(net "MB0_TIME_R")
	)
	(segment
		(start 175.509936 -366.7125)
		(end 175.509936 -366.145064)
		(width 0.254)
		(layer "F.Cu")
		(net "MB0_TIME_R")
	)
	(via
		(at 177.419 -363.474)
		(size 0.6604)
		(drill 0.3302)
		(layers "F.Cu" "B.Cu")
		(net "MB0_TIME_R")
	)
	(segment
		(start 171.831 -371.348)
		(end 171.831 -373.9261)
		(width 0.254)
		(layer "F.Cu")
		(net "MB0_TEMP")
	)
	(segment
		(start 172.7073 -370.93906)
		(end 172.23994 -370.93906)
		(width 0.254)
		(layer "F.Cu")
		(net "MB0_TEMP")
	)
	(segment
		(start 172.23994 -370.93906)
		(end 171.831 -371.348)
		(width 0.254)
		(layer "F.Cu")
		(net "MB0_TEMP")
	)
	(segment
		(start 171.831 -374.9675)
		(end 171.831 -373.9261)
		(width 0.254)
		(layer "F.Cu")
		(net "MB0_TEMP")
	)
	(via
		(at 171.831 -373.9261)
		(size 0.6604)
		(drill 0.3302)
		(layers "F.Cu" "B.Cu")
		(net "MB0_TEMP")
	)
	(segment
		(start 177.8127 -367.43894)
		(end 179.14112 -367.43894)
		(width 0.254)
		(layer "F.Cu")
		(net "MB0_SPISS_PD")
	)
	(segment
		(start 180.4035 -366.649)
		(end 179.93106 -366.649)
		(width 0.254)
		(layer "F.Cu")
		(net "MB0_SPISS_PD")
	)
	(segment
		(start 179.93106 -366.649)
		(end 179.29606 -367.284)
		(width 0.254)
		(layer "F.Cu")
		(net "MB0_SPISS_PD")
	)
	(segment
		(start 179.14112 -367.43894)
		(end 179.29606 -367.284)
		(width 0.254)
		(layer "F.Cu")
		(net "MB0_SPISS_PD")
	)
	(via
		(at 179.29606 -367.284)
		(size 0.6604)
		(drill 0.3302)
		(layers "F.Cu" "B.Cu")
		(net "MB0_SPISS_PD")
	)
	(segment
		(start 178.2572 -373.3292)
		(end 177.01006 -372.08206)
		(width 0.254)
		(layer "F.Cu")
		(net "MB0_RETRY_R")
	)
	(segment
		(start 178.816 -373.3292)
		(end 178.2572 -373.3292)
		(width 0.254)
		(layer "F.Cu")
		(net "MB0_RETRY_R")
	)
	(segment
		(start 179.6034 -372.6942)
		(end 178.9684 -373.3292)
		(width 0.254)
		(layer "F.Cu")
		(net "MB0_RETRY_R")
	)
	(segment
		(start 177.01006 -372.08206)
		(end 177.01006 -371.7417)
		(width 0.254)
		(layer "F.Cu")
		(net "MB0_RETRY_R")
	)
	(segment
		(start 178.9684 -373.3292)
		(end 178.816 -373.3292)
		(width 0.254)
		(layer "F.Cu")
		(net "MB0_RETRY_R")
	)
	(segment
		(start 180.8607 -372.6942)
		(end 179.6034 -372.6942)
		(width 0.254)
		(layer "F.Cu")
		(net "MB0_RETRY_R")
	)
	(via
		(at 178.816 -373.3292)
		(size 0.6604)
		(drill 0.3302)
		(layers "F.Cu" "B.Cu")
		(net "MB0_RETRY_R")
	)
	(segment
		(start 168.468802 -362.998512)
		(end 168.468802 -362.623862)
		(width 0.254)
		(layer "F.Cu")
		(net "MB0_PSET_R")
	)
	(segment
		(start 169.7355 -364.444788)
		(end 169.7355 -363.22)
		(width 0.254)
		(layer "F.Cu")
		(net "MB0_PSET_R")
	)
	(segment
		(start 171.649644 -365.070644)
		(end 170.361356 -365.070644)
		(width 0.254)
		(layer "F.Cu")
		(net "MB0_PSET_R")
	)
	(segment
		(start 168.69029 -363.22)
		(end 168.468802 -362.998512)
		(width 0.254)
		(layer "F.Cu")
		(net "MB0_PSET_R")
	)
	(segment
		(start 168.699688 -362.1405)
		(end 168.468802 -362.371386)
		(width 0.254)
		(layer "F.Cu")
		(net "MB0_PSET_R")
	)
	(segment
		(start 168.468802 -362.371386)
		(end 168.468802 -362.623862)
		(width 0.254)
		(layer "F.Cu")
		(net "MB0_PSET_R")
	)
	(segment
		(start 173.2153 -366.6363)
		(end 171.649644 -365.070644)
		(width 0.254)
		(layer "F.Cu")
		(net "MB0_PSET_R")
	)
	(segment
		(start 170.688 -362.1405)
		(end 169.672 -362.1405)
		(width 0.254)
		(layer "F.Cu")
		(net "MB0_PSET_R")
	)
	(segment
		(start 170.361356 -365.070644)
		(end 169.7355 -364.444788)
		(width 0.254)
		(layer "F.Cu")
		(net "MB0_PSET_R")
	)
	(segment
		(start 169.672 -362.1405)
		(end 168.699688 -362.1405)
		(width 0.254)
		(layer "F.Cu")
		(net "MB0_PSET_R")
	)
	(segment
		(start 169.7355 -363.22)
		(end 168.69029 -363.22)
		(width 0.254)
		(layer "F.Cu")
		(net "MB0_PSET_R")
	)
	(segment
		(start 173.50994 -366.6363)
		(end 173.2153 -366.6363)
		(width 0.254)
		(layer "F.Cu")
		(net "MB0_PSET_R")
	)
	(via
		(at 168.468802 -362.623862)
		(size 0.6604)
		(drill 0.3302)
		(layers "F.Cu" "B.Cu")
		(net "MB0_PSET_R")
	)
	(segment
		(start 173.863 -374.9675)
		(end 173.9265 -374.904)
		(width 0.254)
		(layer "F.Cu")
		(net "MB0_P12V_PWGIN_R")
	)
	(segment
		(start 175.010064 -371.6655)
		(end 175.010064 -373.553736)
		(width 0.254)
		(layer "F.Cu")
		(net "MB0_P12V_PWGIN_R")
	)
	(segment
		(start 172.847 -374.9675)
		(end 173.863 -374.9675)
		(width 0.254)
		(layer "F.Cu")
		(net "MB0_P12V_PWGIN_R")
	)
	(segment
		(start 173.9265 -374.904)
		(end 173.9265 -374.6373)
		(width 0.254)
		(layer "F.Cu")
		(net "MB0_P12V_PWGIN_R")
	)
	(segment
		(start 173.9265 -374.6373)
		(end 174.7266 -373.8372)
		(width 0.254)
		(layer "F.Cu")
		(net "MB0_P12V_PWGIN_R")
	)
	(segment
		(start 175.010064 -373.553736)
		(end 174.7266 -373.8372)
		(width 0.254)
		(layer "F.Cu")
		(net "MB0_P12V_PWGIN_R")
	)
	(via
		(at 174.7266 -373.8372)
		(size 0.6604)
		(drill 0.3302)
		(layers "F.Cu" "B.Cu")
		(net "MB0_P12V_PWGIN_R")
	)
	(segment
		(start 169.672 -367.919)
		(end 171.069 -367.919)
		(width 0.3048)
		(layer "F.Cu")
		(net "MB0_P12V_HS")
	)
	(segment
		(start 168.9735 -366.776)
		(end 169.672 -367.4745)
		(width 0.508)
		(layer "F.Cu")
		(net "MB0_P12V_HS")
	)
	(segment
		(start 171.99737 -368.438938)
		(end 171.477432 -367.919)
		(width 0.3048)
		(layer "F.Cu")
		(net "MB0_P12V_HS")
	)
	(segment
		(start 172.7835 -368.438938)
		(end 171.99737 -368.438938)
		(width 0.3048)
		(layer "F.Cu")
		(net "MB0_P12V_HS")
	)
	(segment
		(start 171.477432 -367.919)
		(end 171.069 -367.919)
		(width 0.3048)
		(layer "F.Cu")
		(net "MB0_P12V_HS")
	)
	(segment
		(start 169.672 -367.4745)
		(end 169.672 -367.919)
		(width 0.508)
		(layer "F.Cu")
		(net "MB0_P12V_HS")
	)
	(via
		(at 171.069 -367.919)
		(size 0.6604)
		(drill 0.3302)
		(layers "F.Cu" "B.Cu")
		(net "MB0_P12V_HS")
	)
	(segment
		(start 176.022 -362.1405)
		(end 175.006 -362.1405)
		(width 0.254)
		(layer "F.Cu")
		(net "MB0_ISTART_R")
	)
	(segment
		(start 175.9585 -363.22)
		(end 175.9585 -362.204)
		(width 0.254)
		(layer "F.Cu")
		(net "MB0_ISTART_R")
	)
	(segment
		(start 175.9585 -364.617)
		(end 175.9585 -363.22)
		(width 0.254)
		(layer "F.Cu")
		(net "MB0_ISTART_R")
	)
	(segment
		(start 175.010064 -365.565436)
		(end 175.9585 -364.617)
		(width 0.254)
		(layer "F.Cu")
		(net "MB0_ISTART_R")
	)
	(segment
		(start 175.010064 -366.7125)
		(end 175.010064 -365.565436)
		(width 0.254)
		(layer "F.Cu")
		(net "MB0_ISTART_R")
	)
	(segment
		(start 175.9585 -362.204)
		(end 176.022 -362.1405)
		(width 0.254)
		(layer "F.Cu")
		(net "MB0_ISTART_R")
	)
	(via
		(at 175.9585 -364.617)
		(size 0.6604)
		(drill 0.3302)
		(layers "F.Cu" "B.Cu")
		(net "MB0_ISTART_R")
	)
	(segment
		(start 173.9265 -363.22)
		(end 173.9265 -362.204)
		(width 0.254)
		(layer "F.Cu")
		(net "MB0_ISET_R")
	)
	(segment
		(start 174.509938 -365.644938)
		(end 173.9265 -365.0615)
		(width 0.254)
		(layer "F.Cu")
		(net "MB0_ISET_R")
	)
	(segment
		(start 173.9265 -365.0615)
		(end 173.9265 -364.5535)
		(width 0.254)
		(layer "F.Cu")
		(net "MB0_ISET_R")
	)
	(segment
		(start 173.9265 -362.204)
		(end 173.99 -362.1405)
		(width 0.254)
		(layer "F.Cu")
		(net "MB0_ISET_R")
	)
	(segment
		(start 173.99 -362.1405)
		(end 172.974 -362.1405)
		(width 0.254)
		(layer "F.Cu")
		(net "MB0_ISET_R")
	)
	(segment
		(start 174.509938 -366.7125)
		(end 174.509938 -365.644938)
		(width 0.254)
		(layer "F.Cu")
		(net "MB0_ISET_R")
	)
	(segment
		(start 173.9265 -364.5535)
		(end 173.9265 -363.22)
		(width 0.254)
		(layer "F.Cu")
		(net "MB0_ISET_R")
	)
	(via
		(at 173.9265 -364.5535)
		(size 0.6604)
		(drill 0.3302)
		(layers "F.Cu" "B.Cu")
		(net "MB0_ISET_R")
	)
	(segment
		(start 179.324 -369.189)
		(end 180.5305 -369.189)
		(width 0.254)
		(layer "F.Cu")
		(net "MB0_HS_ENABLE")
	)
	(segment
		(start 180.5305 -369.189)
		(end 180.5305 -368.2238)
		(width 0.254)
		(layer "F.Cu")
		(net "MB0_HS_ENABLE")
	)
	(segment
		(start 179.074064 -368.939064)
		(end 179.324 -369.189)
		(width 0.254)
		(layer "F.Cu")
		(net "MB0_HS_ENABLE")
	)
	(segment
		(start 177.7365 -368.939064)
		(end 179.074064 -368.939064)
		(width 0.254)
		(layer "F.Cu")
		(net "MB0_HS_ENABLE")
	)
	(via
		(at 179.324 -369.189)
		(size 0.6604)
		(drill 0.3302)
		(layers "F.Cu" "B.Cu")
		(net "MB0_HS_ENABLE")
	)
	(segment
		(start 220.963998 -354.578158)
		(end 220.963998 -355.679248)
		(width 0.254)
		(layer "F.Cu")
		(net "MB0_CM_VOUT_R")
	)
	(segment
		(start 175.8315 -374.904)
		(end 175.8315 -373.737124)
		(width 0.254)
		(layer "F.Cu")
		(net "MB0_CM_VOUT_R")
	)
	(segment
		(start 175.8315 -373.737124)
		(end 175.768 -373.673624)
		(width 0.254)
		(layer "F.Cu")
		(net "MB0_CM_VOUT_R")
	)
	(segment
		(start 175.768 -372.491)
		(end 175.768 -373.673624)
		(width 0.254)
		(layer "F.Cu")
		(net "MB0_CM_VOUT_R")
	)
	(segment
		(start 220.963998 -353.156266)
		(end 220.963998 -354.578158)
		(width 0.254)
		(layer "F.Cu")
		(net "MB0_CM_VOUT_R")
	)
	(segment
		(start 175.509936 -372.232936)
		(end 175.768 -372.491)
		(width 0.254)
		(layer "F.Cu")
		(net "MB0_CM_VOUT_R")
	)
	(segment
		(start 175.509936 -371.6655)
		(end 175.509936 -372.232936)
		(width 0.254)
		(layer "F.Cu")
		(net "MB0_CM_VOUT_R")
	)
	(via
		(at 220.963998 -354.578158)
		(size 0.6604)
		(drill 0.3302)
		(layers "F.Cu" "B.Cu")
		(net "MB0_CM_VOUT_R")
	)
	(via
		(at 175.768 -373.673624)
		(size 0.5588)
		(drill 0.3048)
		(layers "F.Cu" "B.Cu")
		(net "MB0_CM_VOUT_R")
	)
	(via
		(at 220.963998 -355.679248)
		(size 0.5588)
		(drill 0.3048)
		(layers "F.Cu" "B.Cu")
		(net "MB0_CM_VOUT_R")
	)
	(segment
		(start 181.00421 -370.352574)
		(end 181.00421 -370.93017)
		(width 0.254)
		(layer "In5.Cu")
		(net "MB0_CM_VOUT_R")
	)
	(segment
		(start 214.712042 -366.191038)
		(end 185.165746 -366.191038)
		(width 0.254)
		(layer "In5.Cu")
		(net "MB0_CM_VOUT_R")
	)
	(segment
		(start 185.165746 -366.191038)
		(end 181.00421 -370.352574)
		(width 0.254)
		(layer "In5.Cu")
		(net "MB0_CM_VOUT_R")
	)
	(segment
		(start 178.70678 -373.2276)
		(end 176.214024 -373.2276)
		(width 0.254)
		(layer "In5.Cu")
		(net "MB0_CM_VOUT_R")
	)
	(segment
		(start 220.963998 -359.939082)
		(end 214.712042 -366.191038)
		(width 0.254)
		(layer "In5.Cu")
		(net "MB0_CM_VOUT_R")
	)
	(segment
		(start 220.963998 -355.679248)
		(end 220.963998 -359.939082)
		(width 0.254)
		(layer "In5.Cu")
		(net "MB0_CM_VOUT_R")
	)
	(segment
		(start 176.214024 -373.2276)
		(end 175.768 -373.673624)
		(width 0.254)
		(layer "In5.Cu")
		(net "MB0_CM_VOUT_R")
	)
	(segment
		(start 181.00421 -370.93017)
		(end 178.70678 -373.2276)
		(width 0.254)
		(layer "In5.Cu")
		(net "MB0_CM_VOUT_R")
	)
	(segment
		(start 172.194982 -367.939066)
		(end 170.43146 -366.175544)
		(width 0.254)
		(layer "F.Cu")
		(net "MB0_CM_UV_R")
	)
	(segment
		(start 165.42893 -366.120426)
		(end 166.25443 -366.120426)
		(width 0.254)
		(layer "F.Cu")
		(net "MB0_CM_UV_R")
	)
	(segment
		(start 164.34943 -366.120426)
		(end 165.42893 -366.120426)
		(width 0.254)
		(layer "F.Cu")
		(net "MB0_CM_UV_R")
	)
	(segment
		(start 168.085516 -365.488982)
		(end 167.771572 -365.802926)
		(width 0.254)
		(layer "F.Cu")
		(net "MB0_CM_UV_R")
	)
	(segment
		(start 170.43146 -366.175544)
		(end 169.272966 -366.175544)
		(width 0.254)
		(layer "F.Cu")
		(net "MB0_CM_UV_R")
	)
	(segment
		(start 169.272966 -366.175544)
		(end 168.586404 -365.488982)
		(width 0.254)
		(layer "F.Cu")
		(net "MB0_CM_UV_R")
	)
	(segment
		(start 168.586404 -365.488982)
		(end 168.085516 -365.488982)
		(width 0.254)
		(layer "F.Cu")
		(net "MB0_CM_UV_R")
	)
	(segment
		(start 166.25443 -366.120426)
		(end 166.57193 -365.802926)
		(width 0.254)
		(layer "F.Cu")
		(net "MB0_CM_UV_R")
	)
	(segment
		(start 167.771572 -365.802926)
		(end 166.57193 -365.802926)
		(width 0.254)
		(layer "F.Cu")
		(net "MB0_CM_UV_R")
	)
	(segment
		(start 172.7835 -367.939066)
		(end 172.194982 -367.939066)
		(width 0.254)
		(layer "F.Cu")
		(net "MB0_CM_UV_R")
	)
	(via
		(at 168.586404 -365.488982)
		(size 0.6604)
		(drill 0.3302)
		(layers "F.Cu" "B.Cu")
		(net "MB0_CM_UV_R")
	)
	(segment
		(start 164.102034 -374.4468)
		(end 165.615366 -374.4468)
		(width 0.254)
		(layer "F.Cu")
		(net "MB0_CM_SENSE_R2_P")
	)
	(segment
		(start 165.340792 -369.443)
		(end 165.1 -369.202208)
		(width 0.254)
		(layer "F.Cu")
		(net "MB0_CM_SENSE_R2_P")
	)
	(segment
		(start 163.376102 -369.994434)
		(end 163.376102 -373.720868)
		(width 0.254)
		(layer "F.Cu")
		(net "MB0_CM_SENSE_R2_P")
	)
	(segment
		(start 163.927536 -369.443)
		(end 163.376102 -369.994434)
		(width 0.254)
		(layer "F.Cu")
		(net "MB0_CM_SENSE_R2_P")
	)
	(segment
		(start 163.2458 -335.318608)
		(end 162.839908 -335.7245)
		(width 0.254)
		(layer "F.Cu")
		(net "MB0_CM_SENSE_R2_P")
	)
	(segment
		(start 167.2717 -369.189)
		(end 167.0177 -369.443)
		(width 0.254)
		(layer "F.Cu")
		(net "MB0_CM_SENSE_R2_P")
	)
	(segment
		(start 164.859208 -369.443)
		(end 163.927536 -369.443)
		(width 0.254)
		(layer "F.Cu")
		(net "MB0_CM_SENSE_R2_P")
	)
	(segment
		(start 167.0177 -372.618)
		(end 167.2717 -372.872)
		(width 0.254)
		(layer "F.Cu")
		(net "MB0_CM_SENSE_R2_P")
	)
	(segment
		(start 165.615366 -374.4468)
		(end 166.367968 -373.694198)
		(width 0.254)
		(layer "F.Cu")
		(net "MB0_CM_SENSE_R2_P")
	)
	(segment
		(start 163.376102 -373.720868)
		(end 164.102034 -374.4468)
		(width 0.254)
		(layer "F.Cu")
		(net "MB0_CM_SENSE_R2_P")
	)
	(segment
		(start 165.1 -369.202208)
		(end 164.859208 -369.443)
		(width 0.254)
		(layer "F.Cu")
		(net "MB0_CM_SENSE_R2_P")
	)
	(segment
		(start 166.596568 -372.618)
		(end 167.0177 -372.618)
		(width 0.254)
		(layer "F.Cu")
		(net "MB0_CM_SENSE_R2_P")
	)
	(segment
		(start 167.0177 -369.443)
		(end 165.340792 -369.443)
		(width 0.254)
		(layer "F.Cu")
		(net "MB0_CM_SENSE_R2_P")
	)
	(segment
		(start 163.2458 -328.047096)
		(end 163.2458 -335.318608)
		(width 0.254)
		(layer "F.Cu")
		(net "MB0_CM_SENSE_R2_P")
	)
	(segment
		(start 159.384746 -327.793096)
		(end 162.9918 -327.793096)
		(width 0.254)
		(layer "F.Cu")
		(net "MB0_CM_SENSE_R2_P")
	)
	(segment
		(start 166.367968 -373.694198)
		(end 166.367968 -372.8466)
		(width 0.254)
		(layer "F.Cu")
		(net "MB0_CM_SENSE_R2_P")
	)
	(segment
		(start 162.9918 -327.793096)
		(end 163.2458 -328.047096)
		(width 0.254)
		(layer "F.Cu")
		(net "MB0_CM_SENSE_R2_P")
	)
	(segment
		(start 166.367968 -372.8466)
		(end 166.596568 -372.618)
		(width 0.254)
		(layer "F.Cu")
		(net "MB0_CM_SENSE_R2_P")
	)
	(via
		(at 162.839908 -335.7245)
		(size 0.5588)
		(drill 0.3048)
		(layers "F.Cu" "B.Cu")
		(net "MB0_CM_SENSE_R2_P")
	)
	(via
		(at 165.1 -369.202208)
		(size 0.5588)
		(drill 0.3048)
		(layers "F.Cu" "B.Cu")
		(net "MB0_CM_SENSE_R2_P")
	)
	(segment
		(start 165.340792 -369.443)
		(end 165.1 -369.202208)
		(width 0.254)
		(layer "In5.Cu")
		(net "MB0_CM_SENSE_R2_P")
	)
	(segment
		(start 162.839908 -335.7245)
		(end 163.2458 -336.130392)
		(width 0.254)
		(layer "In5.Cu")
		(net "MB0_CM_SENSE_R2_P")
	)
	(segment
		(start 165.793674 -361.0483)
		(end 165.793674 -369.244118)
		(width 0.254)
		(layer "In5.Cu")
		(net "MB0_CM_SENSE_R2_P")
	)
	(segment
		(start 163.2458 -336.130392)
		(end 163.2458 -358.500426)
		(width 0.254)
		(layer "In5.Cu")
		(net "MB0_CM_SENSE_R2_P")
	)
	(segment
		(start 165.793674 -369.244118)
		(end 165.594792 -369.443)
		(width 0.254)
		(layer "In5.Cu")
		(net "MB0_CM_SENSE_R2_P")
	)
	(segment
		(start 165.594792 -369.443)
		(end 165.340792 -369.443)
		(width 0.254)
		(layer "In5.Cu")
		(net "MB0_CM_SENSE_R2_P")
	)
	(segment
		(start 163.2458 -358.500426)
		(end 165.793674 -361.0483)
		(width 0.254)
		(layer "In5.Cu")
		(net "MB0_CM_SENSE_R2_P")
	)
	(segment
		(start 164.859208 -369.951)
		(end 164.138102 -369.951)
		(width 0.254)
		(layer "F.Cu")
		(net "MB0_CM_SENSE_R2_N")
	)
	(segment
		(start 167.0177 -369.951)
		(end 165.340792 -369.951)
		(width 0.254)
		(layer "F.Cu")
		(net "MB0_CM_SENSE_R2_N")
	)
	(segment
		(start 165.859968 -372.636034)
		(end 166.386002 -372.11)
		(width 0.254)
		(layer "F.Cu")
		(net "MB0_CM_SENSE_R2_N")
	)
	(segment
		(start 166.386002 -372.11)
		(end 167.0177 -372.11)
		(width 0.254)
		(layer "F.Cu")
		(net "MB0_CM_SENSE_R2_N")
	)
	(segment
		(start 167.2717 -370.205)
		(end 167.0177 -369.951)
		(width 0.254)
		(layer "F.Cu")
		(net "MB0_CM_SENSE_R2_N")
	)
	(segment
		(start 165.1 -370.191792)
		(end 164.859208 -369.951)
		(width 0.254)
		(layer "F.Cu")
		(net "MB0_CM_SENSE_R2_N")
	)
	(segment
		(start 165.340792 -369.951)
		(end 165.1 -370.191792)
		(width 0.254)
		(layer "F.Cu")
		(net "MB0_CM_SENSE_R2_N")
	)
	(segment
		(start 163.884102 -370.205)
		(end 163.884102 -373.510302)
		(width 0.254)
		(layer "F.Cu")
		(net "MB0_CM_SENSE_R2_N")
	)
	(segment
		(start 165.4048 -373.9388)
		(end 165.859968 -373.483632)
		(width 0.254)
		(layer "F.Cu")
		(net "MB0_CM_SENSE_R2_N")
	)
	(segment
		(start 163.884102 -373.510302)
		(end 164.3126 -373.9388)
		(width 0.254)
		(layer "F.Cu")
		(net "MB0_CM_SENSE_R2_N")
	)
	(segment
		(start 163.7538 -335.368392)
		(end 164.109908 -335.7245)
		(width 0.254)
		(layer "F.Cu")
		(net "MB0_CM_SENSE_R2_N")
	)
	(segment
		(start 164.0078 -327.793096)
		(end 163.7538 -328.047096)
		(width 0.254)
		(layer "F.Cu")
		(net "MB0_CM_SENSE_R2_N")
	)
	(segment
		(start 167.614854 -327.793096)
		(end 164.0078 -327.793096)
		(width 0.254)
		(layer "F.Cu")
		(net "MB0_CM_SENSE_R2_N")
	)
	(segment
		(start 167.0177 -372.11)
		(end 167.2717 -371.856)
		(width 0.254)
		(layer "F.Cu")
		(net "MB0_CM_SENSE_R2_N")
	)
	(segment
		(start 164.138102 -369.951)
		(end 163.884102 -370.205)
		(width 0.254)
		(layer "F.Cu")
		(net "MB0_CM_SENSE_R2_N")
	)
	(segment
		(start 163.7538 -328.047096)
		(end 163.7538 -335.368392)
		(width 0.254)
		(layer "F.Cu")
		(net "MB0_CM_SENSE_R2_N")
	)
	(segment
		(start 165.859968 -373.483632)
		(end 165.859968 -372.636034)
		(width 0.254)
		(layer "F.Cu")
		(net "MB0_CM_SENSE_R2_N")
	)
	(segment
		(start 164.3126 -373.9388)
		(end 165.4048 -373.9388)
		(width 0.254)
		(layer "F.Cu")
		(net "MB0_CM_SENSE_R2_N")
	)
	(via
		(at 165.1 -370.191792)
		(size 0.5588)
		(drill 0.3048)
		(layers "F.Cu" "B.Cu")
		(net "MB0_CM_SENSE_R2_N")
	)
	(via
		(at 164.109908 -335.7245)
		(size 0.5588)
		(drill 0.3048)
		(layers "F.Cu" "B.Cu")
		(net "MB0_CM_SENSE_R2_N")
	)
	(segment
		(start 165.340792 -369.951)
		(end 165.1 -370.191792)
		(width 0.254)
		(layer "In5.Cu")
		(net "MB0_CM_SENSE_R2_N")
	)
	(segment
		(start 165.805358 -369.951)
		(end 165.340792 -369.951)
		(width 0.254)
		(layer "In5.Cu")
		(net "MB0_CM_SENSE_R2_N")
	)
	(segment
		(start 166.301674 -360.837734)
		(end 166.301674 -369.454684)
		(width 0.254)
		(layer "In5.Cu")
		(net "MB0_CM_SENSE_R2_N")
	)
	(segment
		(start 163.7538 -336.080608)
		(end 163.7538 -358.28986)
		(width 0.254)
		(layer "In5.Cu")
		(net "MB0_CM_SENSE_R2_N")
	)
	(segment
		(start 166.301674 -369.454684)
		(end 165.805358 -369.951)
		(width 0.254)
		(layer "In5.Cu")
		(net "MB0_CM_SENSE_R2_N")
	)
	(segment
		(start 163.7538 -358.28986)
		(end 166.301674 -360.837734)
		(width 0.254)
		(layer "In5.Cu")
		(net "MB0_CM_SENSE_R2_N")
	)
	(segment
		(start 164.109908 -335.7245)
		(end 163.7538 -336.080608)
		(width 0.254)
		(layer "In5.Cu")
		(net "MB0_CM_SENSE_R2_N")
	)
	(segment
		(start 162.8648 -360.826304)
		(end 163.2458 -360.445304)
		(width 0.254)
		(layer "F.Cu")
		(net "MB0_CM_SENSE_R1_P")
	)
	(segment
		(start 163.2458 -360.445304)
		(end 163.2458 -359.708704)
		(width 0.254)
		(layer "F.Cu")
		(net "MB0_CM_SENSE_R1_P")
	)
	(segment
		(start 163.2458 -359.708704)
		(end 162.9918 -359.454704)
		(width 0.254)
		(layer "F.Cu")
		(net "MB0_CM_SENSE_R1_P")
	)
	(segment
		(start 162.9918 -359.454704)
		(end 159.384746 -359.454704)
		(width 0.254)
		(layer "F.Cu")
		(net "MB0_CM_SENSE_R1_P")
	)
	(via
		(at 165.1 -372.858792)
		(size 0.5588)
		(drill 0.3048)
		(layers "F.Cu" "B.Cu")
		(net "MB0_CM_SENSE_R1_P")
	)
	(via
		(at 162.8648 -360.826304)
		(size 0.5588)
		(drill 0.3048)
		(layers "F.Cu" "B.Cu")
		(net "MB0_CM_SENSE_R1_P")
	)
	(segment
		(start 166.367968 -369.443)
		(end 167.0177 -369.443)
		(width 0.254)
		(layer "B.Cu")
		(net "MB0_CM_SENSE_R1_P")
	)
	(segment
		(start 164.859208 -372.618)
		(end 163.673536 -372.618)
		(width 0.254)
		(layer "B.Cu")
		(net "MB0_CM_SENSE_R1_P")
	)
	(segment
		(start 165.340792 -372.618)
		(end 165.1 -372.858792)
		(width 0.254)
		(layer "B.Cu")
		(net "MB0_CM_SENSE_R1_P")
	)
	(segment
		(start 167.0177 -369.443)
		(end 167.2717 -369.189)
		(width 0.254)
		(layer "B.Cu")
		(net "MB0_CM_SENSE_R1_P")
	)
	(segment
		(start 166.172896 -368.697764)
		(end 166.172896 -369.247928)
		(width 0.254)
		(layer "B.Cu")
		(net "MB0_CM_SENSE_R1_P")
	)
	(segment
		(start 163.16706 -368.78514)
		(end 163.963604 -367.988596)
		(width 0.254)
		(layer "B.Cu")
		(net "MB0_CM_SENSE_R1_P")
	)
	(segment
		(start 165.463728 -367.988596)
		(end 166.172896 -368.697764)
		(width 0.254)
		(layer "B.Cu")
		(net "MB0_CM_SENSE_R1_P")
	)
	(segment
		(start 163.963604 -367.988596)
		(end 165.463728 -367.988596)
		(width 0.254)
		(layer "B.Cu")
		(net "MB0_CM_SENSE_R1_P")
	)
	(segment
		(start 163.673536 -372.618)
		(end 163.16706 -372.111524)
		(width 0.254)
		(layer "B.Cu")
		(net "MB0_CM_SENSE_R1_P")
	)
	(segment
		(start 163.16706 -372.111524)
		(end 163.16706 -368.78514)
		(width 0.254)
		(layer "B.Cu")
		(net "MB0_CM_SENSE_R1_P")
	)
	(segment
		(start 167.0177 -372.618)
		(end 165.340792 -372.618)
		(width 0.254)
		(layer "B.Cu")
		(net "MB0_CM_SENSE_R1_P")
	)
	(segment
		(start 167.2717 -372.872)
		(end 167.0177 -372.618)
		(width 0.254)
		(layer "B.Cu")
		(net "MB0_CM_SENSE_R1_P")
	)
	(segment
		(start 165.1 -372.858792)
		(end 164.859208 -372.618)
		(width 0.254)
		(layer "B.Cu")
		(net "MB0_CM_SENSE_R1_P")
	)
	(segment
		(start 166.172896 -369.247928)
		(end 166.367968 -369.443)
		(width 0.254)
		(layer "B.Cu")
		(net "MB0_CM_SENSE_R1_P")
	)
	(segment
		(start 164.859208 -372.618)
		(end 163.797234 -372.618)
		(width 0.254)
		(layer "In5.Cu")
		(net "MB0_CM_SENSE_R1_P")
	)
	(segment
		(start 163.797234 -372.618)
		(end 163.2458 -372.066566)
		(width 0.254)
		(layer "In5.Cu")
		(net "MB0_CM_SENSE_R1_P")
	)
	(segment
		(start 163.2458 -361.207304)
		(end 162.8648 -360.826304)
		(width 0.254)
		(layer "In5.Cu")
		(net "MB0_CM_SENSE_R1_P")
	)
	(segment
		(start 165.1 -372.858792)
		(end 164.859208 -372.618)
		(width 0.254)
		(layer "In5.Cu")
		(net "MB0_CM_SENSE_R1_P")
	)
	(segment
		(start 163.2458 -372.066566)
		(end 163.2458 -361.207304)
		(width 0.254)
		(layer "In5.Cu")
		(net "MB0_CM_SENSE_R1_P")
	)
	(segment
		(start 163.7538 -359.708704)
		(end 164.0078 -359.454704)
		(width 0.254)
		(layer "F.Cu")
		(net "MB0_CM_SENSE_R1_N")
	)
	(segment
		(start 164.1348 -360.826304)
		(end 163.7538 -360.445304)
		(width 0.254)
		(layer "F.Cu")
		(net "MB0_CM_SENSE_R1_N")
	)
	(segment
		(start 164.0078 -359.454704)
		(end 167.614854 -359.454704)
		(width 0.254)
		(layer "F.Cu")
		(net "MB0_CM_SENSE_R1_N")
	)
	(segment
		(start 163.7538 -360.445304)
		(end 163.7538 -359.708704)
		(width 0.254)
		(layer "F.Cu")
		(net "MB0_CM_SENSE_R1_N")
	)
	(via
		(at 164.1348 -360.826304)
		(size 0.5588)
		(drill 0.3048)
		(layers "F.Cu" "B.Cu")
		(net "MB0_CM_SENSE_R1_N")
	)
	(via
		(at 165.1 -371.869208)
		(size 0.5588)
		(drill 0.3048)
		(layers "F.Cu" "B.Cu")
		(net "MB0_CM_SENSE_R1_N")
	)
	(segment
		(start 167.0177 -369.951)
		(end 166.157402 -369.951)
		(width 0.254)
		(layer "B.Cu")
		(net "MB0_CM_SENSE_R1_N")
	)
	(segment
		(start 167.2717 -370.205)
		(end 167.0177 -369.951)
		(width 0.254)
		(layer "B.Cu")
		(net "MB0_CM_SENSE_R1_N")
	)
	(segment
		(start 165.664896 -368.90833)
		(end 165.253162 -368.496596)
		(width 0.254)
		(layer "B.Cu")
		(net "MB0_CM_SENSE_R1_N")
	)
	(segment
		(start 165.253162 -368.496596)
		(end 164.17417 -368.496596)
		(width 0.254)
		(layer "B.Cu")
		(net "MB0_CM_SENSE_R1_N")
	)
	(segment
		(start 165.340792 -372.11)
		(end 167.0177 -372.11)
		(width 0.254)
		(layer "B.Cu")
		(net "MB0_CM_SENSE_R1_N")
	)
	(segment
		(start 164.17417 -368.496596)
		(end 163.67506 -368.995706)
		(width 0.254)
		(layer "B.Cu")
		(net "MB0_CM_SENSE_R1_N")
	)
	(segment
		(start 165.1 -371.869208)
		(end 165.340792 -372.11)
		(width 0.254)
		(layer "B.Cu")
		(net "MB0_CM_SENSE_R1_N")
	)
	(segment
		(start 164.859208 -372.11)
		(end 165.1 -371.869208)
		(width 0.254)
		(layer "B.Cu")
		(net "MB0_CM_SENSE_R1_N")
	)
	(segment
		(start 163.67506 -371.900958)
		(end 163.884102 -372.11)
		(width 0.254)
		(layer "B.Cu")
		(net "MB0_CM_SENSE_R1_N")
	)
	(segment
		(start 163.67506 -368.995706)
		(end 163.67506 -371.900958)
		(width 0.254)
		(layer "B.Cu")
		(net "MB0_CM_SENSE_R1_N")
	)
	(segment
		(start 165.664896 -369.458494)
		(end 165.664896 -368.90833)
		(width 0.254)
		(layer "B.Cu")
		(net "MB0_CM_SENSE_R1_N")
	)
	(segment
		(start 166.157402 -369.951)
		(end 165.664896 -369.458494)
		(width 0.254)
		(layer "B.Cu")
		(net "MB0_CM_SENSE_R1_N")
	)
	(segment
		(start 163.884102 -372.11)
		(end 164.859208 -372.11)
		(width 0.254)
		(layer "B.Cu")
		(net "MB0_CM_SENSE_R1_N")
	)
	(segment
		(start 167.0177 -372.11)
		(end 167.2717 -371.856)
		(width 0.254)
		(layer "B.Cu")
		(net "MB0_CM_SENSE_R1_N")
	)
	(segment
		(start 163.7538 -361.207304)
		(end 163.7538 -371.856)
		(width 0.254)
		(layer "In5.Cu")
		(net "MB0_CM_SENSE_R1_N")
	)
	(segment
		(start 164.859208 -372.11)
		(end 165.1 -371.869208)
		(width 0.254)
		(layer "In5.Cu")
		(net "MB0_CM_SENSE_R1_N")
	)
	(segment
		(start 164.0078 -372.11)
		(end 164.859208 -372.11)
		(width 0.254)
		(layer "In5.Cu")
		(net "MB0_CM_SENSE_R1_N")
	)
	(segment
		(start 163.7538 -371.856)
		(end 164.0078 -372.11)
		(width 0.254)
		(layer "In5.Cu")
		(net "MB0_CM_SENSE_R1_N")
	)
	(segment
		(start 164.1348 -360.826304)
		(end 163.7538 -361.207304)
		(width 0.254)
		(layer "In5.Cu")
		(net "MB0_CM_SENSE_R1_N")
	)
	(segment
		(start 168.7068 -372.618)
		(end 169.0878 -372.999)
		(width 0.254)
		(layer "F.Cu")
		(net "MB0_CM_SENSE_P")
	)
	(segment
		(start 172.7835 -368.939064)
		(end 171.6659 -368.939064)
		(width 0.254)
		(layer "F.Cu")
		(net "MB0_CM_SENSE_P")
	)
	(segment
		(start 171.6659 -368.939064)
		(end 171.5897 -368.862864)
		(width 0.254)
		(layer "F.Cu")
		(net "MB0_CM_SENSE_P")
	)
	(segment
		(start 168.1607 -372.872)
		(end 168.4147 -372.618)
		(width 0.254)
		(layer "F.Cu")
		(net "MB0_CM_SENSE_P")
	)
	(segment
		(start 168.4147 -372.618)
		(end 168.7068 -372.618)
		(width 0.254)
		(layer "F.Cu")
		(net "MB0_CM_SENSE_P")
	)
	(via
		(at 169.0878 -372.999)
		(size 0.5588)
		(drill 0.3048)
		(layers "F.Cu" "B.Cu")
		(net "MB0_CM_SENSE_P")
	)
	(via
		(at 171.5897 -368.862864)
		(size 0.5588)
		(drill 0.3048)
		(layers "F.Cu" "B.Cu")
		(net "MB0_CM_SENSE_P")
	)
	(segment
		(start 170.23588 -372.618)
		(end 171.406566 -372.618)
		(width 0.254)
		(layer "B.Cu")
		(net "MB0_CM_SENSE_P")
	)
	(segment
		(start 171.406566 -372.618)
		(end 173.165262 -370.859304)
		(width 0.254)
		(layer "B.Cu")
		(net "MB0_CM_SENSE_P")
	)
	(segment
		(start 173.165262 -370.859304)
		(end 173.165262 -369.986306)
		(width 0.254)
		(layer "B.Cu")
		(net "MB0_CM_SENSE_P")
	)
	(segment
		(start 168.1607 -372.872)
		(end 168.4147 -372.618)
		(width 0.254)
		(layer "B.Cu")
		(net "MB0_CM_SENSE_P")
	)
	(segment
		(start 172.613828 -369.434872)
		(end 172.161708 -369.434872)
		(width 0.254)
		(layer "B.Cu")
		(net "MB0_CM_SENSE_P")
	)
	(segment
		(start 169.85488 -372.618)
		(end 170.04538 -372.8085)
		(width 0.254)
		(layer "B.Cu")
		(net "MB0_CM_SENSE_P")
	)
	(segment
		(start 172.161708 -369.434872)
		(end 171.5897 -368.862864)
		(width 0.254)
		(layer "B.Cu")
		(net "MB0_CM_SENSE_P")
	)
	(segment
		(start 170.04538 -372.8085)
		(end 170.23588 -372.618)
		(width 0.254)
		(layer "B.Cu")
		(net "MB0_CM_SENSE_P")
	)
	(segment
		(start 169.0878 -372.999)
		(end 169.4688 -372.618)
		(width 0.254)
		(layer "B.Cu")
		(net "MB0_CM_SENSE_P")
	)
	(segment
		(start 169.4688 -372.618)
		(end 169.85488 -372.618)
		(width 0.254)
		(layer "B.Cu")
		(net "MB0_CM_SENSE_P")
	)
	(segment
		(start 168.7068 -372.618)
		(end 169.0878 -372.999)
		(width 0.254)
		(layer "B.Cu")
		(net "MB0_CM_SENSE_P")
	)
	(segment
		(start 168.4147 -372.618)
		(end 168.7068 -372.618)
		(width 0.254)
		(layer "B.Cu")
		(net "MB0_CM_SENSE_P")
	)
	(segment
		(start 173.165262 -369.986306)
		(end 172.613828 -369.434872)
		(width 0.254)
		(layer "B.Cu")
		(net "MB0_CM_SENSE_P")
	)
	(segment
		(start 172.7835 -370.438934)
		(end 171.6659 -370.438934)
		(width 0.254)
		(layer "F.Cu")
		(net "MB0_CM_SENSE_N")
	)
	(segment
		(start 168.7068 -372.11)
		(end 169.0878 -371.729)
		(width 0.254)
		(layer "F.Cu")
		(net "MB0_CM_SENSE_N")
	)
	(segment
		(start 168.4147 -372.11)
		(end 168.7068 -372.11)
		(width 0.254)
		(layer "F.Cu")
		(net "MB0_CM_SENSE_N")
	)
	(segment
		(start 171.6659 -370.438934)
		(end 171.5897 -370.515134)
		(width 0.254)
		(layer "F.Cu")
		(net "MB0_CM_SENSE_N")
	)
	(segment
		(start 168.1607 -371.856)
		(end 168.4147 -372.11)
		(width 0.254)
		(layer "F.Cu")
		(net "MB0_CM_SENSE_N")
	)
	(via
		(at 169.0878 -371.729)
		(size 0.5588)
		(drill 0.3048)
		(layers "F.Cu" "B.Cu")
		(net "MB0_CM_SENSE_N")
	)
	(via
		(at 171.5897 -370.515134)
		(size 0.5588)
		(drill 0.3048)
		(layers "F.Cu" "B.Cu")
		(net "MB0_CM_SENSE_N")
	)
	(segment
		(start 169.4688 -372.11)
		(end 169.85488 -372.11)
		(width 0.254)
		(layer "B.Cu")
		(net "MB0_CM_SENSE_N")
	)
	(segment
		(start 171.5897 -370.515134)
		(end 172.161962 -369.942872)
		(width 0.254)
		(layer "B.Cu")
		(net "MB0_CM_SENSE_N")
	)
	(segment
		(start 172.161962 -369.942872)
		(end 172.403262 -369.942872)
		(width 0.254)
		(layer "B.Cu")
		(net "MB0_CM_SENSE_N")
	)
	(segment
		(start 168.4147 -372.11)
		(end 168.7068 -372.11)
		(width 0.254)
		(layer "B.Cu")
		(net "MB0_CM_SENSE_N")
	)
	(segment
		(start 168.7068 -372.11)
		(end 169.0878 -371.729)
		(width 0.254)
		(layer "B.Cu")
		(net "MB0_CM_SENSE_N")
	)
	(segment
		(start 172.657262 -370.196872)
		(end 172.657262 -370.648738)
		(width 0.254)
		(layer "B.Cu")
		(net "MB0_CM_SENSE_N")
	)
	(segment
		(start 168.1607 -371.856)
		(end 168.4147 -372.11)
		(width 0.254)
		(layer "B.Cu")
		(net "MB0_CM_SENSE_N")
	)
	(segment
		(start 172.657262 -370.648738)
		(end 171.196 -372.11)
		(width 0.254)
		(layer "B.Cu")
		(net "MB0_CM_SENSE_N")
	)
	(segment
		(start 171.196 -372.11)
		(end 170.23588 -372.11)
		(width 0.254)
		(layer "B.Cu")
		(net "MB0_CM_SENSE_N")
	)
	(segment
		(start 170.23588 -372.11)
		(end 170.04538 -371.9195)
		(width 0.254)
		(layer "B.Cu")
		(net "MB0_CM_SENSE_N")
	)
	(segment
		(start 172.403262 -369.942872)
		(end 172.657262 -370.196872)
		(width 0.254)
		(layer "B.Cu")
		(net "MB0_CM_SENSE_N")
	)
	(segment
		(start 169.0878 -371.729)
		(end 169.4688 -372.11)
		(width 0.254)
		(layer "B.Cu")
		(net "MB0_CM_SENSE_N")
	)
	(segment
		(start 169.85488 -372.11)
		(end 170.04538 -371.9195)
		(width 0.254)
		(layer "B.Cu")
		(net "MB0_CM_SENSE_N")
	)
	(segment
		(start 171.324016 -365.613442)
		(end 169.921682 -365.613442)
		(width 0.254)
		(layer "F.Cu")
		(net "MB0_CM_OV_R")
	)
	(segment
		(start 169.921682 -365.613442)
		(end 168.429686 -364.121446)
		(width 0.254)
		(layer "F.Cu")
		(net "MB0_CM_OV_R")
	)
	(segment
		(start 165.42893 -361.929426)
		(end 164.52723 -361.929426)
		(width 0.254)
		(layer "F.Cu")
		(net "MB0_CM_OV_R")
	)
	(segment
		(start 166.57193 -362.246926)
		(end 167.435784 -362.246926)
		(width 0.254)
		(layer "F.Cu")
		(net "MB0_CM_OV_R")
	)
	(segment
		(start 165.74643 -362.246926)
		(end 165.42893 -361.929426)
		(width 0.254)
		(layer "F.Cu")
		(net "MB0_CM_OV_R")
	)
	(segment
		(start 167.852344 -362.663486)
		(end 167.852344 -363.544104)
		(width 0.254)
		(layer "F.Cu")
		(net "MB0_CM_OV_R")
	)
	(segment
		(start 164.52723 -361.929426)
		(end 164.32403 -362.132626)
		(width 0.254)
		(layer "F.Cu")
		(net "MB0_CM_OV_R")
	)
	(segment
		(start 166.57193 -362.246926)
		(end 165.74643 -362.246926)
		(width 0.254)
		(layer "F.Cu")
		(net "MB0_CM_OV_R")
	)
	(segment
		(start 172.7073 -367.43894)
		(end 172.7073 -366.996726)
		(width 0.254)
		(layer "F.Cu")
		(net "MB0_CM_OV_R")
	)
	(segment
		(start 167.852344 -363.544104)
		(end 168.429686 -364.121446)
		(width 0.254)
		(layer "F.Cu")
		(net "MB0_CM_OV_R")
	)
	(segment
		(start 172.7073 -366.996726)
		(end 171.324016 -365.613442)
		(width 0.254)
		(layer "F.Cu")
		(net "MB0_CM_OV_R")
	)
	(segment
		(start 167.435784 -362.246926)
		(end 167.852344 -362.663486)
		(width 0.254)
		(layer "F.Cu")
		(net "MB0_CM_OV_R")
	)
	(via
		(at 168.429686 -364.121446)
		(size 0.6604)
		(drill 0.3302)
		(layers "F.Cu" "B.Cu")
		(net "MB0_CM_OV_R")
	)
	(via
		(at 212.979 -357.378)
		(size 0.6604)
		(drill 0.3302)
		(layers "F.Cu" "B.Cu")
		(net "MB0_CM_GATE_R")
	)
	(via
		(at 212.09 -356.235)
		(size 0.5588)
		(drill 0.3048)
		(layers "F.Cu" "B.Cu")
		(net "MB0_CM_GATE_R")
	)
	(via
		(at 208.915 -347.853)
		(size 0.5588)
		(drill 0.3048)
		(layers "F.Cu" "B.Cu")
		(net "MB0_CM_GATE_R")
	)
	(via
		(at 208.915 -328.676)
		(size 0.5588)
		(drill 0.3048)
		(layers "F.Cu" "B.Cu")
		(net "MB0_CM_GATE_R")
	)
	(via
		(at 212.09 -355.092)
		(size 0.5588)
		(drill 0.3048)
		(layers "F.Cu" "B.Cu")
		(net "MB0_CM_GATE_R")
	)
	(via
		(at 208.915 -329.692)
		(size 0.5588)
		(drill 0.3048)
		(layers "F.Cu" "B.Cu")
		(net "MB0_CM_GATE_R")
	)
	(via
		(at 208.915 -348.869)
		(size 0.5588)
		(drill 0.3048)
		(layers "F.Cu" "B.Cu")
		(net "MB0_CM_GATE_R")
	)
	(via
		(at 208.915 -338.074)
		(size 0.5588)
		(drill 0.3048)
		(layers "F.Cu" "B.Cu")
		(net "MB0_CM_GATE_R")
	)
	(via
		(at 208.915 -339.09)
		(size 0.5588)
		(drill 0.3048)
		(layers "F.Cu" "B.Cu")
		(net "MB0_CM_GATE_R")
	)
	(via
		(at 172.9486 -373.1768)
		(size 0.5588)
		(drill 0.3048)
		(layers "F.Cu" "B.Cu")
		(net "MB0_CM_GATE")
	)
	(via
		(at 215.138 -357.378)
		(size 0.6604)
		(drill 0.3302)
		(layers "F.Cu" "B.Cu")
		(net "MB0_CM_GATE")
	)
	(via
		(at 216.408 -356.108)
		(size 0.5588)
		(drill 0.3048)
		(layers "F.Cu" "B.Cu")
		(net "MB0_CM_GATE")
	)
	(via
		(at 172.7708 -372.237)
		(size 0.5588)
		(drill 0.3048)
		(layers "F.Cu" "B.Cu")
		(net "MB0_CM_GATE")
	)
	(via
		(at 216.408 -357.124)
		(size 0.5588)
		(drill 0.3048)
		(layers "F.Cu" "B.Cu")
		(net "MB0_CM_GATE")
	)
	(segment
		(start 180.134514 -363.933486)
		(end 212.0773 -363.933486)
		(width 1.524)
		(layer "In5.Cu")
		(net "MB0_CM_GATE")
	)
	(segment
		(start 215.773 -360.237786)
		(end 215.773 -358.394)
		(width 1.524)
		(layer "In5.Cu")
		(net "MB0_CM_GATE")
	)
	(segment
		(start 177.801778 -371.727222)
		(end 178.9938 -370.5352)
		(width 1.524)
		(layer "In5.Cu")
		(net "MB0_CM_GATE")
	)
	(segment
		(start 174.9552 -371.727222)
		(end 177.801778 -371.727222)
		(width 1.524)
		(layer "In5.Cu")
		(net "MB0_CM_GATE")
	)
	(segment
		(start 212.0773 -363.933486)
		(end 215.773 -360.237786)
		(width 1.524)
		(layer "In5.Cu")
		(net "MB0_CM_GATE")
	)
	(segment
		(start 178.9938 -370.5352)
		(end 178.9938 -365.0742)
		(width 1.524)
		(layer "In5.Cu")
		(net "MB0_CM_GATE")
	)
	(segment
		(start 178.9938 -365.0742)
		(end 180.134514 -363.933486)
		(width 1.524)
		(layer "In5.Cu")
		(net "MB0_CM_GATE")
	)
	(segment
		(start 178.943 -365.379)
		(end 179.959 -365.379)
		(width 0.254)
		(layer "F.Cu")
		(net "MB0_CM_ADR2_R")
	)
	(segment
		(start 177.01006 -366.6363)
		(end 177.6857 -366.6363)
		(width 0.254)
		(layer "F.Cu")
		(net "MB0_CM_ADR2_R")
	)
	(segment
		(start 177.6857 -366.6363)
		(end 178.943 -365.379)
		(width 0.254)
		(layer "F.Cu")
		(net "MB0_CM_ADR2_R")
	)
	(segment
		(start 181.1655 -365.379)
		(end 179.959 -365.379)
		(width 0.254)
		(layer "F.Cu")
		(net "MB0_CM_ADR2_R")
	)
	(via
		(at 179.959 -365.379)
		(size 0.6604)
		(drill 0.3302)
		(layers "F.Cu" "B.Cu")
		(net "MB0_CM_ADR2_R")
	)
	(segment
		(start 176.509934 -366.7125)
		(end 176.509934 -366.161066)
		(width 0.254)
		(layer "F.Cu")
		(net "MB0_CM_ADR1_R")
	)
	(segment
		(start 178.689 -364.617)
		(end 178.054 -365.252)
		(width 0.254)
		(layer "F.Cu")
		(net "MB0_CM_ADR1_R")
	)
	(segment
		(start 178.689 -363.9185)
		(end 178.689 -364.617)
		(width 0.254)
		(layer "F.Cu")
		(net "MB0_CM_ADR1_R")
	)
	(segment
		(start 176.509934 -366.161066)
		(end 177.419 -365.252)
		(width 0.254)
		(layer "F.Cu")
		(net "MB0_CM_ADR1_R")
	)
	(segment
		(start 177.419 -365.252)
		(end 178.054 -365.252)
		(width 0.254)
		(layer "F.Cu")
		(net "MB0_CM_ADR1_R")
	)
	(via
		(at 178.054 -365.252)
		(size 0.6604)
		(drill 0.3302)
		(layers "F.Cu" "B.Cu")
		(net "MB0_CM_ADR1_R")
	)
	(via
		(at 207.588358 -356.278942)
		(size 0.6604)
		(drill 0.3302)
		(layers "F.Cu" "B.Cu")
		(net "MB0_12V_CTRL_GATE6")
	)
	(via
		(at 205.74 -349.885)
		(size 0.6096)
		(drill 0.3048)
		(layers "F.Cu" "B.Cu")
		(net "MB0_12V_CTRL_GATE5")
	)
	(via
		(at 205.867 -349.758)
		(size 0.6604)
		(drill 0.3302)
		(layers "F.Cu" "B.Cu")
		(net "MB0_12V_CTRL_GATE4")
	)
	(via
		(at 205.796134 -340.317328)
		(size 0.6096)
		(drill 0.3048)
		(layers "F.Cu" "B.Cu")
		(net "MB0_12V_CTRL_GATE3")
	)
	(via
		(at 205.74 -337.058)
		(size 0.6604)
		(drill 0.3302)
		(layers "F.Cu" "B.Cu")
		(net "MB0_12V_CTRL_GATE2")
	)
	(via
		(at 205.74 -327.787)
		(size 0.6096)
		(drill 0.3048)
		(layers "F.Cu" "B.Cu")
		(net "MB0_12V_CTRL_GATE1")
	)
	(segment
		(start 211.07146 -164.38626)
		(end 210.69046 -164.38626)
		(width 0.17145)
		(layer "F.Cu")
		(net "IO_EXP6_SDA")
	)
	(segment
		(start 211.57946 -164.89426)
		(end 211.07146 -164.38626)
		(width 0.17145)
		(layer "F.Cu")
		(net "IO_EXP6_SDA")
	)
	(segment
		(start 212.69706 -165.77818)
		(end 212.08238 -165.77818)
		(width 0.17145)
		(layer "F.Cu")
		(net "IO_EXP6_SDA")
	)
	(segment
		(start 212.08238 -165.77818)
		(end 211.57946 -165.27526)
		(width 0.17145)
		(layer "F.Cu")
		(net "IO_EXP6_SDA")
	)
	(segment
		(start 210.69046 -164.38626)
		(end 209.48396 -164.38626)
		(width 0.17145)
		(layer "F.Cu")
		(net "IO_EXP6_SDA")
	)
	(segment
		(start 211.57946 -165.27526)
		(end 211.57946 -164.89426)
		(width 0.17145)
		(layer "F.Cu")
		(net "IO_EXP6_SDA")
	)
	(via
		(at 210.69046 -164.38626)
		(size 0.6604)
		(drill 0.3302)
		(layers "F.Cu" "B.Cu")
		(net "IO_EXP6_SDA")
	)
	(segment
		(start 211.71662 -166.42842)
		(end 211.07146 -165.78326)
		(width 0.17145)
		(layer "F.Cu")
		(net "IO_EXP6_SCL")
	)
	(segment
		(start 210.69046 -165.40226)
		(end 211.07146 -165.78326)
		(width 0.17145)
		(layer "F.Cu")
		(net "IO_EXP6_SCL")
	)
	(segment
		(start 209.48396 -165.40226)
		(end 210.69046 -165.40226)
		(width 0.17145)
		(layer "F.Cu")
		(net "IO_EXP6_SCL")
	)
	(segment
		(start 212.69706 -166.42842)
		(end 211.71662 -166.42842)
		(width 0.17145)
		(layer "F.Cu")
		(net "IO_EXP6_SCL")
	)
	(via
		(at 211.07146 -165.78326)
		(size 0.6604)
		(drill 0.3302)
		(layers "F.Cu" "B.Cu")
		(net "IO_EXP6_SCL")
	)
	(segment
		(start 219.84462 -166.42842)
		(end 218.33586 -166.42842)
		(width 0.17145)
		(layer "F.Cu")
		(net "IO_EXP6_A2")
	)
	(segment
		(start 219.84462 -166.42842)
		(end 221.2848 -166.42842)
		(width 0.17145)
		(layer "F.Cu")
		(net "IO_EXP6_A2")
	)
	(segment
		(start 221.29496 -166.41826)
		(end 221.29496 -165.40226)
		(width 0.17145)
		(layer "F.Cu")
		(net "IO_EXP6_A2")
	)
	(segment
		(start 221.2848 -166.42842)
		(end 221.29496 -166.41826)
		(width 0.17145)
		(layer "F.Cu")
		(net "IO_EXP6_A2")
	)
	(via
		(at 219.84462 -166.42842)
		(size 0.6604)
		(drill 0.3302)
		(layers "F.Cu" "B.Cu")
		(net "IO_EXP6_A2")
	)
	(segment
		(start 218.33586 -165.77818)
		(end 219.382086 -165.77818)
		(width 0.17145)
		(layer "F.Cu")
		(net "IO_EXP6_A1")
	)
	(segment
		(start 220.034104 -165.126162)
		(end 220.774006 -164.38626)
		(width 0.17145)
		(layer "F.Cu")
		(net "IO_EXP6_A1")
	)
	(segment
		(start 221.29496 -164.38626)
		(end 221.29496 -163.37026)
		(width 0.17145)
		(layer "F.Cu")
		(net "IO_EXP6_A1")
	)
	(segment
		(start 219.382086 -165.77818)
		(end 220.034104 -165.126162)
		(width 0.17145)
		(layer "F.Cu")
		(net "IO_EXP6_A1")
	)
	(segment
		(start 220.774006 -164.38626)
		(end 221.29496 -164.38626)
		(width 0.17145)
		(layer "F.Cu")
		(net "IO_EXP6_A1")
	)
	(via
		(at 220.034104 -165.126162)
		(size 0.6604)
		(drill 0.3302)
		(layers "F.Cu" "B.Cu")
		(net "IO_EXP6_A1")
	)
	(segment
		(start 210.41106 -167.07866)
		(end 210.05546 -167.43426)
		(width 0.17145)
		(layer "F.Cu")
		(net "IO_EXP6_A0")
	)
	(segment
		(start 210.69046 -167.07866)
		(end 210.41106 -167.07866)
		(width 0.17145)
		(layer "F.Cu")
		(net "IO_EXP6_A0")
	)
	(segment
		(start 209.48396 -167.43426)
		(end 209.48396 -166.41826)
		(width 0.17145)
		(layer "F.Cu")
		(net "IO_EXP6_A0")
	)
	(segment
		(start 212.69706 -167.07866)
		(end 210.69046 -167.07866)
		(width 0.17145)
		(layer "F.Cu")
		(net "IO_EXP6_A0")
	)
	(segment
		(start 210.05546 -167.43426)
		(end 209.48396 -167.43426)
		(width 0.17145)
		(layer "F.Cu")
		(net "IO_EXP6_A0")
	)
	(via
		(at 210.69046 -167.07866)
		(size 0.6604)
		(drill 0.3302)
		(layers "F.Cu" "B.Cu")
		(net "IO_EXP6_A0")
	)
	(segment
		(start 212.46592 -206.36992)
		(end 211.074 -204.978)
		(width 0.17145)
		(layer "F.Cu")
		(net "IO_EXP5_SDA")
	)
	(segment
		(start 211.074 -204.978)
		(end 210.82 -204.978)
		(width 0.17145)
		(layer "F.Cu")
		(net "IO_EXP5_SDA")
	)
	(segment
		(start 210.82 -204.978)
		(end 209.8675 -204.978)
		(width 0.17145)
		(layer "F.Cu")
		(net "IO_EXP5_SDA")
	)
	(segment
		(start 213.0806 -206.36992)
		(end 212.46592 -206.36992)
		(width 0.17145)
		(layer "F.Cu")
		(net "IO_EXP5_SDA")
	)
	(via
		(at 210.82 -204.978)
		(size 0.6604)
		(drill 0.3302)
		(layers "F.Cu" "B.Cu")
		(net "IO_EXP5_SDA")
	)
	(segment
		(start 211.074 -205.994)
		(end 211.455 -206.375)
		(width 0.17145)
		(layer "F.Cu")
		(net "IO_EXP5_SCL")
	)
	(segment
		(start 209.8675 -205.994)
		(end 211.074 -205.994)
		(width 0.17145)
		(layer "F.Cu")
		(net "IO_EXP5_SCL")
	)
	(segment
		(start 213.0806 -207.02016)
		(end 212.10016 -207.02016)
		(width 0.17145)
		(layer "F.Cu")
		(net "IO_EXP5_SCL")
	)
	(segment
		(start 212.10016 -207.02016)
		(end 211.455 -206.375)
		(width 0.17145)
		(layer "F.Cu")
		(net "IO_EXP5_SCL")
	)
	(via
		(at 211.455 -206.375)
		(size 0.6604)
		(drill 0.3302)
		(layers "F.Cu" "B.Cu")
		(net "IO_EXP5_SCL")
	)
	(segment
		(start 220.599 -203.9747)
		(end 219.263214 -203.9747)
		(width 0.17145)
		(layer "F.Cu")
		(net "IO_EXP5_INT_N")
	)
	(segment
		(start 218.7194 -205.71968)
		(end 218.7194 -204.518514)
		(width 0.17145)
		(layer "F.Cu")
		(net "IO_EXP5_INT_N")
	)
	(segment
		(start 219.263214 -203.9747)
		(end 218.944444 -204.29347)
		(width 0.17145)
		(layer "F.Cu")
		(net "IO_EXP5_INT_N")
	)
	(segment
		(start 218.7194 -204.518514)
		(end 218.944444 -204.29347)
		(width 0.17145)
		(layer "F.Cu")
		(net "IO_EXP5_INT_N")
	)
	(via
		(at 218.944444 -204.29347)
		(size 0.6604)
		(drill 0.3302)
		(layers "F.Cu" "B.Cu")
		(net "IO_EXP5_INT_N")
	)
	(segment
		(start 221.6785 -207.01)
		(end 221.66834 -207.02016)
		(width 0.17145)
		(layer "F.Cu")
		(net "IO_EXP5_A2")
	)
	(segment
		(start 221.66834 -207.02016)
		(end 220.22816 -207.02016)
		(width 0.17145)
		(layer "F.Cu")
		(net "IO_EXP5_A2")
	)
	(segment
		(start 222.225362 -206.463138)
		(end 221.6785 -207.01)
		(width 0.17145)
		(layer "F.Cu")
		(net "IO_EXP5_A2")
	)
	(segment
		(start 220.22816 -207.02016)
		(end 218.7194 -207.02016)
		(width 0.17145)
		(layer "F.Cu")
		(net "IO_EXP5_A2")
	)
	(segment
		(start 222.225362 -205.994)
		(end 222.225362 -206.463138)
		(width 0.17145)
		(layer "F.Cu")
		(net "IO_EXP5_A2")
	)
	(via
		(at 220.22816 -207.02016)
		(size 0.6604)
		(drill 0.3302)
		(layers "F.Cu" "B.Cu")
		(net "IO_EXP5_A2")
	)
	(segment
		(start 222.225362 -204.978)
		(end 220.726 -204.978)
		(width 0.17145)
		(layer "F.Cu")
		(net "IO_EXP5_A1")
	)
	(segment
		(start 222.225362 -204.508862)
		(end 222.225362 -204.978)
		(width 0.17145)
		(layer "F.Cu")
		(net "IO_EXP5_A1")
	)
	(segment
		(start 219.33408 -206.36992)
		(end 220.726 -204.978)
		(width 0.17145)
		(layer "F.Cu")
		(net "IO_EXP5_A1")
	)
	(segment
		(start 221.6785 -203.962)
		(end 222.225362 -204.508862)
		(width 0.17145)
		(layer "F.Cu")
		(net "IO_EXP5_A1")
	)
	(segment
		(start 218.7194 -206.36992)
		(end 219.33408 -206.36992)
		(width 0.17145)
		(layer "F.Cu")
		(net "IO_EXP5_A1")
	)
	(via
		(at 220.726 -204.978)
		(size 0.6604)
		(drill 0.3302)
		(layers "F.Cu" "B.Cu")
		(net "IO_EXP5_A1")
	)
	(segment
		(start 213.0806 -207.6704)
		(end 211.074 -207.6704)
		(width 0.17145)
		(layer "F.Cu")
		(net "IO_EXP5_A0")
	)
	(segment
		(start 210.510628 -207.6704)
		(end 210.155028 -208.026)
		(width 0.17145)
		(layer "F.Cu")
		(net "IO_EXP5_A0")
	)
	(segment
		(start 209.8675 -208.026)
		(end 209.8675 -207.01)
		(width 0.17145)
		(layer "F.Cu")
		(net "IO_EXP5_A0")
	)
	(segment
		(start 210.155028 -208.026)
		(end 209.8675 -208.026)
		(width 0.17145)
		(layer "F.Cu")
		(net "IO_EXP5_A0")
	)
	(segment
		(start 211.074 -207.6704)
		(end 210.510628 -207.6704)
		(width 0.17145)
		(layer "F.Cu")
		(net "IO_EXP5_A0")
	)
	(via
		(at 211.074 -207.6704)
		(size 0.6604)
		(drill 0.3302)
		(layers "F.Cu" "B.Cu")
		(net "IO_EXP5_A0")
	)
	(segment
		(start 210.93938 -236.8042)
		(end 210.8962 -236.84738)
		(width 0.17145)
		(layer "F.Cu")
		(net "IO_EXP4_SDA")
	)
	(segment
		(start 210.93938 -235.63072)
		(end 210.93938 -236.8042)
		(width 0.17145)
		(layer "F.Cu")
		(net "IO_EXP4_SDA")
	)
	(segment
		(start 209.54746 -238.84382)
		(end 209.54746 -238.19612)
		(width 0.17145)
		(layer "F.Cu")
		(net "IO_EXP4_SDA")
	)
	(segment
		(start 209.54746 -238.19612)
		(end 210.8962 -236.84738)
		(width 0.17145)
		(layer "F.Cu")
		(net "IO_EXP4_SDA")
	)
	(via
		(at 210.8962 -236.84738)
		(size 0.6604)
		(drill 0.3302)
		(layers "F.Cu" "B.Cu")
		(net "IO_EXP4_SDA")
	)
	(segment
		(start 209.92338 -236.83722)
		(end 209.54238 -237.21822)
		(width 0.17145)
		(layer "F.Cu")
		(net "IO_EXP4_SCL")
	)
	(segment
		(start 208.89722 -238.84382)
		(end 208.89722 -237.86338)
		(width 0.17145)
		(layer "F.Cu")
		(net "IO_EXP4_SCL")
	)
	(segment
		(start 209.92338 -235.63072)
		(end 209.92338 -236.83722)
		(width 0.17145)
		(layer "F.Cu")
		(net "IO_EXP4_SCL")
	)
	(segment
		(start 208.89722 -237.86338)
		(end 209.54238 -237.21822)
		(width 0.17145)
		(layer "F.Cu")
		(net "IO_EXP4_SCL")
	)
	(via
		(at 209.54238 -237.21822)
		(size 0.6604)
		(drill 0.3302)
		(layers "F.Cu" "B.Cu")
		(net "IO_EXP4_SCL")
	)
	(segment
		(start 210.1977 -245.244874)
		(end 210.49615 -245.543324)
		(width 0.17145)
		(layer "F.Cu")
		(net "IO_EXP4_INT_N")
	)
	(segment
		(start 213.35238 -245.47068)
		(end 213.279736 -245.543324)
		(width 0.17145)
		(layer "F.Cu")
		(net "IO_EXP4_INT_N")
	)
	(segment
		(start 210.1977 -244.48262)
		(end 210.1977 -245.244874)
		(width 0.17145)
		(layer "F.Cu")
		(net "IO_EXP4_INT_N")
	)
	(segment
		(start 210.49615 -245.543324)
		(end 212.057234 -245.543324)
		(width 0.17145)
		(layer "F.Cu")
		(net "IO_EXP4_INT_N")
	)
	(segment
		(start 213.279736 -245.543324)
		(end 212.057234 -245.543324)
		(width 0.17145)
		(layer "F.Cu")
		(net "IO_EXP4_INT_N")
	)
	(via
		(at 212.057234 -245.543324)
		(size 0.6604)
		(drill 0.3302)
		(layers "F.Cu" "B.Cu")
		(net "IO_EXP4_INT_N")
	)
	(segment
		(start 208.89722 -247.43156)
		(end 208.90738 -247.44172)
		(width 0.17145)
		(layer "F.Cu")
		(net "IO_EXP4_A2")
	)
	(segment
		(start 208.89722 -244.48262)
		(end 208.89722 -245.99138)
		(width 0.17145)
		(layer "F.Cu")
		(net "IO_EXP4_A2")
	)
	(segment
		(start 208.89722 -245.99138)
		(end 208.89722 -247.43156)
		(width 0.17145)
		(layer "F.Cu")
		(net "IO_EXP4_A2")
	)
	(segment
		(start 208.90738 -247.44172)
		(end 209.92338 -247.44172)
		(width 0.17145)
		(layer "F.Cu")
		(net "IO_EXP4_A2")
	)
	(via
		(at 208.89722 -245.99138)
		(size 0.6604)
		(drill 0.3302)
		(layers "F.Cu" "B.Cu")
		(net "IO_EXP4_A2")
	)
	(segment
		(start 209.54746 -244.48262)
		(end 209.54746 -245.488206)
		(width 0.17145)
		(layer "F.Cu")
		(net "IO_EXP4_A1")
	)
	(segment
		(start 210.93938 -247.44172)
		(end 211.95538 -247.44172)
		(width 0.17145)
		(layer "F.Cu")
		(net "IO_EXP4_A1")
	)
	(segment
		(start 209.54746 -245.488206)
		(end 210.117182 -246.057928)
		(width 0.17145)
		(layer "F.Cu")
		(net "IO_EXP4_A1")
	)
	(segment
		(start 210.117182 -246.057928)
		(end 210.508088 -246.057928)
		(width 0.17145)
		(layer "F.Cu")
		(net "IO_EXP4_A1")
	)
	(segment
		(start 210.93938 -246.48922)
		(end 210.93938 -247.44172)
		(width 0.17145)
		(layer "F.Cu")
		(net "IO_EXP4_A1")
	)
	(segment
		(start 210.508088 -246.057928)
		(end 210.93938 -246.48922)
		(width 0.17145)
		(layer "F.Cu")
		(net "IO_EXP4_A1")
	)
	(via
		(at 210.93938 -246.48922)
		(size 0.6604)
		(drill 0.3302)
		(layers "F.Cu" "B.Cu")
		(net "IO_EXP4_A1")
	)
	(segment
		(start 207.89138 -235.63072)
		(end 207.89138 -236.20222)
		(width 0.17145)
		(layer "F.Cu")
		(net "IO_EXP4_A0")
	)
	(segment
		(start 208.90738 -235.63072)
		(end 207.89138 -235.63072)
		(width 0.17145)
		(layer "F.Cu")
		(net "IO_EXP4_A0")
	)
	(segment
		(start 208.24698 -238.84382)
		(end 208.24698 -236.83722)
		(width 0.17145)
		(layer "F.Cu")
		(net "IO_EXP4_A0")
	)
	(segment
		(start 208.24698 -236.55782)
		(end 208.24698 -236.83722)
		(width 0.17145)
		(layer "F.Cu")
		(net "IO_EXP4_A0")
	)
	(segment
		(start 207.89138 -236.20222)
		(end 208.24698 -236.55782)
		(width 0.17145)
		(layer "F.Cu")
		(net "IO_EXP4_A0")
	)
	(via
		(at 208.24698 -236.83722)
		(size 0.6604)
		(drill 0.3302)
		(layers "F.Cu" "B.Cu")
		(net "IO_EXP4_A0")
	)
	(segment
		(start 240.9444 -218.63304)
		(end 240.9444 -218.04249)
		(width 0.17145)
		(layer "F.Cu")
		(net "IO_EXP3_SDA")
	)
	(segment
		(start 239.5474 -217.7034)
		(end 238.76 -216.916)
		(width 0.17145)
		(layer "F.Cu")
		(net "IO_EXP3_SDA")
	)
	(segment
		(start 238.633 -215.7095)
		(end 238.633 -216.789)
		(width 0.17145)
		(layer "F.Cu")
		(net "IO_EXP3_SDA")
	)
	(segment
		(start 238.633 -216.789)
		(end 238.76 -216.916)
		(width 0.17145)
		(layer "F.Cu")
		(net "IO_EXP3_SDA")
	)
	(segment
		(start 241.01298 -218.70162)
		(end 240.9444 -218.63304)
		(width 0.17145)
		(layer "F.Cu")
		(net "IO_EXP3_SDA")
	)
	(segment
		(start 240.60531 -217.7034)
		(end 239.5474 -217.7034)
		(width 0.17145)
		(layer "F.Cu")
		(net "IO_EXP3_SDA")
	)
	(segment
		(start 240.9444 -218.04249)
		(end 240.60531 -217.7034)
		(width 0.17145)
		(layer "F.Cu")
		(net "IO_EXP3_SDA")
	)
	(via
		(at 238.76 -216.916)
		(size 0.6604)
		(drill 0.3302)
		(layers "F.Cu" "B.Cu")
		(net "IO_EXP3_SDA")
	)
	(segment
		(start 237.5535 -215.773)
		(end 237.5535 -216.916)
		(width 0.17145)
		(layer "F.Cu")
		(net "IO_EXP3_SCL")
	)
	(segment
		(start 237.49 -215.7095)
		(end 237.5535 -215.773)
		(width 0.17145)
		(layer "F.Cu")
		(net "IO_EXP3_SCL")
	)
	(segment
		(start 239.33912 -218.70162)
		(end 237.5535 -216.916)
		(width 0.17145)
		(layer "F.Cu")
		(net "IO_EXP3_SCL")
	)
	(segment
		(start 240.36274 -218.70162)
		(end 239.33912 -218.70162)
		(width 0.17145)
		(layer "F.Cu")
		(net "IO_EXP3_SCL")
	)
	(via
		(at 237.5535 -216.916)
		(size 0.6604)
		(drill 0.3302)
		(layers "F.Cu" "B.Cu")
		(net "IO_EXP3_SCL")
	)
	(segment
		(start 244.341142 -215.7095)
		(end 243.10213 -216.948512)
		(width 0.17145)
		(layer "F.Cu")
		(net "IO_EXP3_A2")
	)
	(segment
		(start 242.9637 -217.645234)
		(end 242.839494 -217.521028)
		(width 0.17145)
		(layer "F.Cu")
		(net "IO_EXP3_A2")
	)
	(segment
		(start 242.9637 -218.70162)
		(end 242.9637 -217.645234)
		(width 0.17145)
		(layer "F.Cu")
		(net "IO_EXP3_A2")
	)
	(segment
		(start 242.839494 -217.211148)
		(end 243.10213 -216.948512)
		(width 0.17145)
		(layer "F.Cu")
		(net "IO_EXP3_A2")
	)
	(segment
		(start 242.839494 -217.521028)
		(end 242.839494 -217.211148)
		(width 0.17145)
		(layer "F.Cu")
		(net "IO_EXP3_A2")
	)
	(segment
		(start 244.348 -215.7095)
		(end 244.341142 -215.7095)
		(width 0.17145)
		(layer "F.Cu")
		(net "IO_EXP3_A2")
	)
	(segment
		(start 245.387622 -215.7095)
		(end 244.348 -215.7095)
		(width 0.17145)
		(layer "F.Cu")
		(net "IO_EXP3_A2")
	)
	(via
		(at 243.10213 -216.948512)
		(size 0.6604)
		(drill 0.3302)
		(layers "F.Cu" "B.Cu")
		(net "IO_EXP3_A2")
	)
	(segment
		(start 242.31346 -217.42146)
		(end 241.935 -217.043)
		(width 0.17145)
		(layer "F.Cu")
		(net "IO_EXP3_A1")
	)
	(segment
		(start 241.935 -215.8365)
		(end 241.935 -217.043)
		(width 0.17145)
		(layer "F.Cu")
		(net "IO_EXP3_A1")
	)
	(segment
		(start 242.062 -215.7095)
		(end 241.935 -215.8365)
		(width 0.17145)
		(layer "F.Cu")
		(net "IO_EXP3_A1")
	)
	(segment
		(start 242.31346 -218.70162)
		(end 242.31346 -217.42146)
		(width 0.17145)
		(layer "F.Cu")
		(net "IO_EXP3_A1")
	)
	(segment
		(start 243.205 -215.7095)
		(end 242.062 -215.7095)
		(width 0.17145)
		(layer "F.Cu")
		(net "IO_EXP3_A1")
	)
	(via
		(at 241.935 -217.043)
		(size 0.6604)
		(drill 0.3302)
		(layers "F.Cu" "B.Cu")
		(net "IO_EXP3_A1")
	)
	(segment
		(start 239.776 -215.7095)
		(end 240.919 -215.7095)
		(width 0.17145)
		(layer "F.Cu")
		(net "IO_EXP3_A0")
	)
	(segment
		(start 240.919 -216.281)
		(end 240.326418 -216.873582)
		(width 0.17145)
		(layer "F.Cu")
		(net "IO_EXP3_A0")
	)
	(segment
		(start 240.919 -215.7095)
		(end 240.919 -216.281)
		(width 0.17145)
		(layer "F.Cu")
		(net "IO_EXP3_A0")
	)
	(segment
		(start 241.66322 -217.78722)
		(end 240.8682 -216.9922)
		(width 0.17145)
		(layer "F.Cu")
		(net "IO_EXP3_A0")
	)
	(segment
		(start 240.445036 -216.9922)
		(end 240.326418 -216.873582)
		(width 0.17145)
		(layer "F.Cu")
		(net "IO_EXP3_A0")
	)
	(segment
		(start 241.66322 -218.70162)
		(end 241.66322 -217.78722)
		(width 0.17145)
		(layer "F.Cu")
		(net "IO_EXP3_A0")
	)
	(segment
		(start 240.8682 -216.9922)
		(end 240.445036 -216.9922)
		(width 0.17145)
		(layer "F.Cu")
		(net "IO_EXP3_A0")
	)
	(via
		(at 240.326418 -216.873582)
		(size 0.6604)
		(drill 0.3302)
		(layers "F.Cu" "B.Cu")
		(net "IO_EXP3_A0")
	)
	(segment
		(start 233.5657 -194.623436)
		(end 233.0958 -195.093336)
		(width 0.17145)
		(layer "F.Cu")
		(net "IO_EXP2_SDA")
	)
	(segment
		(start 233.86923 -195.866258)
		(end 234.162092 -196.15912)
		(width 0.17145)
		(layer "F.Cu")
		(net "IO_EXP2_SDA")
	)
	(segment
		(start 233.0958 -195.3768)
		(end 233.0958 -195.650866)
		(width 0.17145)
		(layer "F.Cu")
		(net "IO_EXP2_SDA")
	)
	(segment
		(start 234.162092 -196.15912)
		(end 235.0516 -196.15912)
		(width 0.17145)
		(layer "F.Cu")
		(net "IO_EXP2_SDA")
	)
	(segment
		(start 233.0958 -195.093336)
		(end 233.0958 -195.3768)
		(width 0.17145)
		(layer "F.Cu")
		(net "IO_EXP2_SDA")
	)
	(segment
		(start 233.311192 -195.866258)
		(end 233.86923 -195.866258)
		(width 0.17145)
		(layer "F.Cu")
		(net "IO_EXP2_SDA")
	)
	(segment
		(start 233.0958 -195.650866)
		(end 233.311192 -195.866258)
		(width 0.17145)
		(layer "F.Cu")
		(net "IO_EXP2_SDA")
	)
	(segment
		(start 233.5657 -194.2592)
		(end 233.5657 -194.623436)
		(width 0.17145)
		(layer "F.Cu")
		(net "IO_EXP2_SDA")
	)
	(via
		(at 233.0958 -195.3768)
		(size 0.6604)
		(drill 0.3302)
		(layers "F.Cu" "B.Cu")
		(net "IO_EXP2_SDA")
	)
	(segment
		(start 233.0958 -196.6468)
		(end 232.791 -196.6468)
		(width 0.17145)
		(layer "F.Cu")
		(net "IO_EXP2_SCL")
	)
	(segment
		(start 233.832146 -196.80936)
		(end 233.669586 -196.6468)
		(width 0.17145)
		(layer "F.Cu")
		(net "IO_EXP2_SCL")
	)
	(segment
		(start 232.7402 -196.596)
		(end 231.7115 -196.596)
		(width 0.17145)
		(layer "F.Cu")
		(net "IO_EXP2_SCL")
	)
	(segment
		(start 232.791 -196.6468)
		(end 232.7402 -196.596)
		(width 0.17145)
		(layer "F.Cu")
		(net "IO_EXP2_SCL")
	)
	(segment
		(start 235.0516 -196.80936)
		(end 233.832146 -196.80936)
		(width 0.17145)
		(layer "F.Cu")
		(net "IO_EXP2_SCL")
	)
	(segment
		(start 233.669586 -196.6468)
		(end 233.0958 -196.6468)
		(width 0.17145)
		(layer "F.Cu")
		(net "IO_EXP2_SCL")
	)
	(via
		(at 233.0958 -196.6468)
		(size 0.6604)
		(drill 0.3302)
		(layers "F.Cu" "B.Cu")
		(net "IO_EXP2_SCL")
	)
	(segment
		(start 243.051076 -194.654424)
		(end 242.692428 -195.013072)
		(width 0.17145)
		(layer "F.Cu")
		(net "IO_EXP2_INT_N")
	)
	(segment
		(start 240.6904 -195.50888)
		(end 242.19662 -195.50888)
		(width 0.17145)
		(layer "F.Cu")
		(net "IO_EXP2_INT_N")
	)
	(segment
		(start 243.93398 -193.29654)
		(end 243.36248 -193.29654)
		(width 0.17145)
		(layer "F.Cu")
		(net "IO_EXP2_INT_N")
	)
	(segment
		(start 243.051076 -193.607944)
		(end 243.051076 -194.654424)
		(width 0.17145)
		(layer "F.Cu")
		(net "IO_EXP2_INT_N")
	)
	(segment
		(start 242.19662 -195.50888)
		(end 242.692428 -195.013072)
		(width 0.17145)
		(layer "F.Cu")
		(net "IO_EXP2_INT_N")
	)
	(segment
		(start 243.36248 -193.29654)
		(end 243.051076 -193.607944)
		(width 0.17145)
		(layer "F.Cu")
		(net "IO_EXP2_INT_N")
	)
	(via
		(at 242.692428 -195.013072)
		(size 0.6604)
		(drill 0.3302)
		(layers "F.Cu" "B.Cu")
		(net "IO_EXP2_INT_N")
	)
	(segment
		(start 243.93398 -197.86854)
		(end 243.93398 -196.72554)
		(width 0.17145)
		(layer "F.Cu")
		(net "IO_EXP2_A2")
	)
	(segment
		(start 243.155978 -197.654672)
		(end 243.369846 -197.86854)
		(width 0.17145)
		(layer "F.Cu")
		(net "IO_EXP2_A2")
	)
	(segment
		(start 243.369846 -197.86854)
		(end 243.93398 -197.86854)
		(width 0.17145)
		(layer "F.Cu")
		(net "IO_EXP2_A2")
	)
	(segment
		(start 240.6904 -196.80936)
		(end 241.511074 -196.80936)
		(width 0.17145)
		(layer "F.Cu")
		(net "IO_EXP2_A2")
	)
	(segment
		(start 242.692428 -197.654672)
		(end 243.155978 -197.654672)
		(width 0.17145)
		(layer "F.Cu")
		(net "IO_EXP2_A2")
	)
	(segment
		(start 241.511074 -196.80936)
		(end 242.356386 -197.654672)
		(width 0.17145)
		(layer "F.Cu")
		(net "IO_EXP2_A2")
	)
	(segment
		(start 242.356386 -197.654672)
		(end 242.692428 -197.654672)
		(width 0.17145)
		(layer "F.Cu")
		(net "IO_EXP2_A2")
	)
	(via
		(at 242.692428 -197.654672)
		(size 0.6604)
		(drill 0.3302)
		(layers "F.Cu" "B.Cu")
		(net "IO_EXP2_A2")
	)
	(segment
		(start 240.6904 -196.15912)
		(end 241.986308 -196.15912)
		(width 0.17145)
		(layer "F.Cu")
		(net "IO_EXP2_A1")
	)
	(segment
		(start 243.93398 -195.58254)
		(end 243.93398 -194.43954)
		(width 0.17145)
		(layer "F.Cu")
		(net "IO_EXP2_A1")
	)
	(segment
		(start 242.692428 -196.333872)
		(end 243.182648 -196.333872)
		(width 0.17145)
		(layer "F.Cu")
		(net "IO_EXP2_A1")
	)
	(segment
		(start 242.16106 -196.333872)
		(end 242.692428 -196.333872)
		(width 0.17145)
		(layer "F.Cu")
		(net "IO_EXP2_A1")
	)
	(segment
		(start 243.182648 -196.333872)
		(end 243.93398 -195.58254)
		(width 0.17145)
		(layer "F.Cu")
		(net "IO_EXP2_A1")
	)
	(segment
		(start 241.986308 -196.15912)
		(end 242.16106 -196.333872)
		(width 0.17145)
		(layer "F.Cu")
		(net "IO_EXP2_A1")
	)
	(via
		(at 242.692428 -196.333872)
		(size 0.6604)
		(drill 0.3302)
		(layers "F.Cu" "B.Cu")
		(net "IO_EXP2_A1")
	)
	(segment
		(start 235.0516 -197.4596)
		(end 234.16768 -197.4596)
		(width 0.17145)
		(layer "F.Cu")
		(net "IO_EXP2_A0")
	)
	(segment
		(start 231.7115 -197.612)
		(end 231.7115 -198.8312)
		(width 0.17145)
		(layer "F.Cu")
		(net "IO_EXP2_A0")
	)
	(segment
		(start 232.412286 -197.739)
		(end 232.285286 -197.612)
		(width 0.17145)
		(layer "F.Cu")
		(net "IO_EXP2_A0")
	)
	(segment
		(start 232.285286 -197.612)
		(end 231.7115 -197.612)
		(width 0.17145)
		(layer "F.Cu")
		(net "IO_EXP2_A0")
	)
	(segment
		(start 233.0704 -197.739)
		(end 232.412286 -197.739)
		(width 0.17145)
		(layer "F.Cu")
		(net "IO_EXP2_A0")
	)
	(segment
		(start 233.88828 -197.739)
		(end 233.0704 -197.739)
		(width 0.17145)
		(layer "F.Cu")
		(net "IO_EXP2_A0")
	)
	(segment
		(start 234.16768 -197.4596)
		(end 233.88828 -197.739)
		(width 0.17145)
		(layer "F.Cu")
		(net "IO_EXP2_A0")
	)
	(via
		(at 233.0704 -197.739)
		(size 0.6604)
		(drill 0.3302)
		(layers "F.Cu" "B.Cu")
		(net "IO_EXP2_A0")
	)
	(segment
		(start 232.42524 -222.469456)
		(end 233.860848 -221.033848)
		(width 0.17145)
		(layer "F.Cu")
		(net "IO_EXP1_SDA")
	)
	(segment
		(start 234.86618 -220.028516)
		(end 233.860848 -221.033848)
		(width 0.17145)
		(layer "F.Cu")
		(net "IO_EXP1_SDA")
	)
	(segment
		(start 234.86618 -219.47886)
		(end 234.86618 -220.028516)
		(width 0.17145)
		(layer "F.Cu")
		(net "IO_EXP1_SDA")
	)
	(segment
		(start 232.42524 -223.612456)
		(end 232.42524 -222.469456)
		(width 0.17145)
		(layer "F.Cu")
		(net "IO_EXP1_SDA")
	)
	(via
		(at 233.860848 -221.033848)
		(size 0.6604)
		(drill 0.3302)
		(layers "F.Cu" "B.Cu")
		(net "IO_EXP1_SDA")
	)
	(segment
		(start 233.72318 -219.92082)
		(end 232.4735 -221.1705)
		(width 0.17145)
		(layer "F.Cu")
		(net "IO_EXP1_SCL")
	)
	(segment
		(start 233.72318 -219.47886)
		(end 233.72318 -219.92082)
		(width 0.17145)
		(layer "F.Cu")
		(net "IO_EXP1_SCL")
	)
	(segment
		(start 231.775 -221.869)
		(end 232.4735 -221.1705)
		(width 0.17145)
		(layer "F.Cu")
		(net "IO_EXP1_SCL")
	)
	(segment
		(start 231.775 -223.612456)
		(end 231.775 -221.869)
		(width 0.17145)
		(layer "F.Cu")
		(net "IO_EXP1_SCL")
	)
	(via
		(at 232.4735 -221.1705)
		(size 0.6604)
		(drill 0.3302)
		(layers "F.Cu" "B.Cu")
		(net "IO_EXP1_SCL")
	)
	(segment
		(start 233.07548 -229.251256)
		(end 233.07548 -230.02367)
		(width 0.17145)
		(layer "F.Cu")
		(net "IO_EXP1_INT_N")
	)
	(segment
		(start 233.07548 -230.02367)
		(end 234.60583 -231.55402)
		(width 0.17145)
		(layer "F.Cu")
		(net "IO_EXP1_INT_N")
	)
	(segment
		(start 235.52404 -232.56748)
		(end 235.52404 -232.47223)
		(width 0.17145)
		(layer "F.Cu")
		(net "IO_EXP1_INT_N")
	)
	(segment
		(start 235.52404 -232.47223)
		(end 234.60583 -231.55402)
		(width 0.17145)
		(layer "F.Cu")
		(net "IO_EXP1_INT_N")
	)
	(via
		(at 234.60583 -231.55402)
		(size 0.6604)
		(drill 0.3302)
		(layers "F.Cu" "B.Cu")
		(net "IO_EXP1_INT_N")
	)
	(segment
		(start 232.22204 -232.56748)
		(end 231.07904 -232.56748)
		(width 0.17145)
		(layer "F.Cu")
		(net "IO_EXP1_A2")
	)
	(segment
		(start 231.775 -231.394)
		(end 231.902 -231.521)
		(width 0.17145)
		(layer "F.Cu")
		(net "IO_EXP1_A2")
	)
	(segment
		(start 231.902 -231.521)
		(end 232.22204 -231.84104)
		(width 0.17145)
		(layer "F.Cu")
		(net "IO_EXP1_A2")
	)
	(segment
		(start 231.775 -229.251256)
		(end 231.775 -231.394)
		(width 0.17145)
		(layer "F.Cu")
		(net "IO_EXP1_A2")
	)
	(segment
		(start 232.22204 -231.84104)
		(end 232.22204 -232.56748)
		(width 0.17145)
		(layer "F.Cu")
		(net "IO_EXP1_A2")
	)
	(via
		(at 231.902 -231.521)
		(size 0.6604)
		(drill 0.3302)
		(layers "F.Cu" "B.Cu")
		(net "IO_EXP1_A2")
	)
	(segment
		(start 233.26852 -232.578656)
		(end 234.369864 -232.578656)
		(width 0.17145)
		(layer "F.Cu")
		(net "IO_EXP1_A1")
	)
	(segment
		(start 233.26852 -231.59212)
		(end 233.26852 -232.578656)
		(width 0.17145)
		(layer "F.Cu")
		(net "IO_EXP1_A1")
	)
	(segment
		(start 234.369864 -232.578656)
		(end 234.38104 -232.56748)
		(width 0.17145)
		(layer "F.Cu")
		(net "IO_EXP1_A1")
	)
	(segment
		(start 232.42524 -230.74884)
		(end 233.26852 -231.59212)
		(width 0.17145)
		(layer "F.Cu")
		(net "IO_EXP1_A1")
	)
	(segment
		(start 232.42524 -229.251256)
		(end 232.42524 -230.74884)
		(width 0.17145)
		(layer "F.Cu")
		(net "IO_EXP1_A1")
	)
	(via
		(at 233.26852 -231.59212)
		(size 0.6604)
		(drill 0.3302)
		(layers "F.Cu" "B.Cu")
		(net "IO_EXP1_A1")
	)
	(segment
		(start 231.12476 -221.361)
		(end 231.12476 -223.612456)
		(width 0.17145)
		(layer "F.Cu")
		(net "IO_EXP1_A0")
	)
	(segment
		(start 231.12476 -219.77604)
		(end 231.41432 -219.48648)
		(width 0.17145)
		(layer "F.Cu")
		(net "IO_EXP1_A0")
	)
	(segment
		(start 231.12476 -221.361)
		(end 231.12476 -219.77604)
		(width 0.17145)
		(layer "F.Cu")
		(net "IO_EXP1_A0")
	)
	(segment
		(start 231.41432 -219.48648)
		(end 232.55732 -219.48648)
		(width 0.17145)
		(layer "F.Cu")
		(net "IO_EXP1_A0")
	)
	(via
		(at 231.12476 -221.361)
		(size 0.6604)
		(drill 0.3302)
		(layers "F.Cu" "B.Cu")
		(net "IO_EXP1_A0")
	)
	(segment
		(start 416.3314 -262.0899)
		(end 417.40582 -262.0899)
		(width 0.17145)
		(layer "F.Cu")
		(net "HDD_PRSNT_9")
	)
	(segment
		(start 413.9692 -262.0899)
		(end 415.3154 -262.0899)
		(width 0.17145)
		(layer "F.Cu")
		(net "HDD_PRSNT_9")
	)
	(segment
		(start 412.8643 -262.0899)
		(end 413.9692 -262.0899)
		(width 0.17145)
		(layer "F.Cu")
		(net "HDD_PRSNT_9")
	)
	(segment
		(start 417.410646 -262.085074)
		(end 422.025064 -262.085074)
		(width 0.17145)
		(layer "F.Cu")
		(net "HDD_PRSNT_9")
	)
	(segment
		(start 412.8516 -262.1026)
		(end 412.8643 -262.0899)
		(width 0.17145)
		(layer "F.Cu")
		(net "HDD_PRSNT_9")
	)
	(segment
		(start 416.3314 -262.0899)
		(end 415.3154 -262.0899)
		(width 0.17145)
		(layer "F.Cu")
		(net "HDD_PRSNT_9")
	)
	(segment
		(start 417.40582 -262.0899)
		(end 417.410646 -262.085074)
		(width 0.17145)
		(layer "F.Cu")
		(net "HDD_PRSNT_9")
	)
	(via
		(at 413.9692 -262.0899)
		(size 0.6604)
		(drill 0.3302)
		(layers "F.Cu" "B.Cu")
		(net "HDD_PRSNT_9")
	)
	(segment
		(start 381.1778 -262.0772)
		(end 382.4351 -262.0772)
		(width 0.17145)
		(layer "F.Cu")
		(net "HDD_PRSNT_8")
	)
	(segment
		(start 382.4351 -262.0772)
		(end 382.4478 -262.0899)
		(width 0.17145)
		(layer "F.Cu")
		(net "HDD_PRSNT_8")
	)
	(segment
		(start 384.916426 -262.085074)
		(end 390.474962 -262.085074)
		(width 0.17145)
		(layer "F.Cu")
		(net "HDD_PRSNT_8")
	)
	(segment
		(start 384.9116 -262.0899)
		(end 384.916426 -262.085074)
		(width 0.17145)
		(layer "F.Cu")
		(net "HDD_PRSNT_8")
	)
	(segment
		(start 384.9116 -262.0899)
		(end 383.8956 -262.0899)
		(width 0.17145)
		(layer "F.Cu")
		(net "HDD_PRSNT_8")
	)
	(segment
		(start 383.8956 -262.0899)
		(end 382.4478 -262.0899)
		(width 0.17145)
		(layer "F.Cu")
		(net "HDD_PRSNT_8")
	)
	(via
		(at 382.4478 -262.0899)
		(size 0.6604)
		(drill 0.3302)
		(layers "F.Cu" "B.Cu")
		(net "HDD_PRSNT_8")
	)
	(segment
		(start 355.209602 -262.0899)
		(end 355.214428 -262.085074)
		(width 0.17145)
		(layer "F.Cu")
		(net "HDD_PRSNT_7")
	)
	(segment
		(start 352.298 -262.0899)
		(end 351.621598 -262.0899)
		(width 0.17145)
		(layer "F.Cu")
		(net "HDD_PRSNT_7")
	)
	(segment
		(start 353.314 -262.0899)
		(end 352.298 -262.0899)
		(width 0.17145)
		(layer "F.Cu")
		(net "HDD_PRSNT_7")
	)
	(segment
		(start 349.7326 -262.0772)
		(end 350.901 -262.0772)
		(width 0.17145)
		(layer "F.Cu")
		(net "HDD_PRSNT_7")
	)
	(segment
		(start 353.314 -262.0899)
		(end 355.209602 -262.0899)
		(width 0.17145)
		(layer "F.Cu")
		(net "HDD_PRSNT_7")
	)
	(segment
		(start 355.214428 -262.085074)
		(end 358.925114 -262.085074)
		(width 0.17145)
		(layer "F.Cu")
		(net "HDD_PRSNT_7")
	)
	(segment
		(start 351.608898 -262.0772)
		(end 350.901 -262.0772)
		(width 0.17145)
		(layer "F.Cu")
		(net "HDD_PRSNT_7")
	)
	(segment
		(start 351.621598 -262.0899)
		(end 351.608898 -262.0772)
		(width 0.17145)
		(layer "F.Cu")
		(net "HDD_PRSNT_7")
	)
	(via
		(at 350.901 -262.0772)
		(size 0.6604)
		(drill 0.3302)
		(layers "F.Cu" "B.Cu")
		(net "HDD_PRSNT_7")
	)
	(segment
		(start 322.483226 -262.0645)
		(end 322.5038 -262.085074)
		(width 0.17145)
		(layer "F.Cu")
		(net "HDD_PRSNT_6")
	)
	(segment
		(start 320.6496 -262.0645)
		(end 319.3034 -262.0645)
		(width 0.17145)
		(layer "F.Cu")
		(net "HDD_PRSNT_6")
	)
	(segment
		(start 321.6656 -262.0645)
		(end 320.6496 -262.0645)
		(width 0.17145)
		(layer "F.Cu")
		(net "HDD_PRSNT_6")
	)
	(segment
		(start 321.6656 -262.0645)
		(end 322.483226 -262.0645)
		(width 0.17145)
		(layer "F.Cu")
		(net "HDD_PRSNT_6")
	)
	(segment
		(start 318.2112 -262.0518)
		(end 318.2239 -262.0645)
		(width 0.17145)
		(layer "F.Cu")
		(net "HDD_PRSNT_6")
	)
	(segment
		(start 322.5038 -262.085074)
		(end 327.375012 -262.085074)
		(width 0.17145)
		(layer "F.Cu")
		(net "HDD_PRSNT_6")
	)
	(segment
		(start 318.2239 -262.0645)
		(end 319.3034 -262.0645)
		(width 0.17145)
		(layer "F.Cu")
		(net "HDD_PRSNT_6")
	)
	(via
		(at 319.3034 -262.0645)
		(size 0.6604)
		(drill 0.3302)
		(layers "F.Cu" "B.Cu")
		(net "HDD_PRSNT_6")
	)
	(segment
		(start 192.5955 -264.922)
		(end 192.5955 -266.1285)
		(width 0.17145)
		(layer "F.Cu")
		(net "HDD_PRSNT_5")
	)
	(segment
		(start 192.5955 -264.188702)
		(end 192.5955 -264.922)
		(width 0.17145)
		(layer "F.Cu")
		(net "HDD_PRSNT_5")
	)
	(segment
		(start 192.5955 -266.1285)
		(end 192.405 -266.319)
		(width 0.17145)
		(layer "F.Cu")
		(net "HDD_PRSNT_5")
	)
	(segment
		(start 192.405 -263.998202)
		(end 192.5955 -264.188702)
		(width 0.17145)
		(layer "F.Cu")
		(net "HDD_PRSNT_5")
	)
	(segment
		(start 190.342774 -262.085074)
		(end 190.3857 -262.128)
		(width 0.17145)
		(layer "F.Cu")
		(net "HDD_PRSNT_5")
	)
	(segment
		(start 190.4111 -262.1534)
		(end 190.3857 -262.128)
		(width 0.17145)
		(layer "F.Cu")
		(net "HDD_PRSNT_5")
	)
	(segment
		(start 190.4111 -263.144)
		(end 190.4111 -263.782302)
		(width 0.17145)
		(layer "F.Cu")
		(net "HDD_PRSNT_5")
	)
	(segment
		(start 192.405 -266.319)
		(end 191.135 -266.319)
		(width 0.17145)
		(layer "F.Cu")
		(net "HDD_PRSNT_5")
	)
	(segment
		(start 190.4111 -263.782302)
		(end 190.627 -263.998202)
		(width 0.17145)
		(layer "F.Cu")
		(net "HDD_PRSNT_5")
	)
	(segment
		(start 190.627 -263.998202)
		(end 192.405 -263.998202)
		(width 0.17145)
		(layer "F.Cu")
		(net "HDD_PRSNT_5")
	)
	(segment
		(start 190.4111 -263.144)
		(end 190.4111 -262.1534)
		(width 0.17145)
		(layer "F.Cu")
		(net "HDD_PRSNT_5")
	)
	(segment
		(start 187.775088 -262.085074)
		(end 190.342774 -262.085074)
		(width 0.17145)
		(layer "F.Cu")
		(net "HDD_PRSNT_5")
	)
	(via
		(at 192.5955 -264.922)
		(size 0.6604)
		(drill 0.3302)
		(layers "F.Cu" "B.Cu")
		(net "HDD_PRSNT_5")
	)
	(segment
		(start 161.056574 -262.085074)
		(end 156.224986 -262.085074)
		(width 0.17145)
		(layer "F.Cu")
		(net "HDD_PRSNT_4")
	)
	(segment
		(start 161.163 -266.065)
		(end 161.163 -264.6045)
		(width 0.17145)
		(layer "F.Cu")
		(net "HDD_PRSNT_4")
	)
	(segment
		(start 161.0995 -263.144)
		(end 161.0995 -264.541)
		(width 0.17145)
		(layer "F.Cu")
		(net "HDD_PRSNT_4")
	)
	(segment
		(start 161.0995 -262.128)
		(end 161.0995 -263.144)
		(width 0.17145)
		(layer "F.Cu")
		(net "HDD_PRSNT_4")
	)
	(segment
		(start 161.163 -264.6045)
		(end 161.0995 -264.541)
		(width 0.17145)
		(layer "F.Cu")
		(net "HDD_PRSNT_4")
	)
	(segment
		(start 161.0995 -262.128)
		(end 161.056574 -262.085074)
		(width 0.17145)
		(layer "F.Cu")
		(net "HDD_PRSNT_4")
	)
	(via
		(at 161.0995 -264.541)
		(size 0.6604)
		(drill 0.3302)
		(layers "F.Cu" "B.Cu")
		(net "HDD_PRSNT_4")
	)
	(segment
		(start 477.0755 -19.685)
		(end 477.0755 -20.701)
		(width 0.17145)
		(layer "F.Cu")
		(net "HDD_PRSNT_35")
	)
	(segment
		(start 478.273364 -21.422614)
		(end 478.79 -21.93925)
		(width 0.17145)
		(layer "F.Cu")
		(net "HDD_PRSNT_35")
	)
	(segment
		(start 478.79 -28.321)
		(end 482.554026 -32.085026)
		(width 0.17145)
		(layer "F.Cu")
		(net "HDD_PRSNT_35")
	)
	(segment
		(start 482.554026 -32.085026)
		(end 485.125014 -32.085026)
		(width 0.17145)
		(layer "F.Cu")
		(net "HDD_PRSNT_35")
	)
	(segment
		(start 477.087692 -17.506188)
		(end 476.123 -18.47088)
		(width 0.17145)
		(layer "F.Cu")
		(net "HDD_PRSNT_35")
	)
	(segment
		(start 478.79 -21.93925)
		(end 478.79 -28.321)
		(width 0.17145)
		(layer "F.Cu")
		(net "HDD_PRSNT_35")
	)
	(segment
		(start 476.123 -18.7325)
		(end 477.0755 -19.685)
		(width 0.17145)
		(layer "F.Cu")
		(net "HDD_PRSNT_35")
	)
	(segment
		(start 476.123 -18.47088)
		(end 476.123 -18.7198)
		(width 0.17145)
		(layer "F.Cu")
		(net "HDD_PRSNT_35")
	)
	(segment
		(start 477.0755 -21.0439)
		(end 477.454214 -21.422614)
		(width 0.17145)
		(layer "F.Cu")
		(net "HDD_PRSNT_35")
	)
	(segment
		(start 477.454214 -21.422614)
		(end 478.273364 -21.422614)
		(width 0.17145)
		(layer "F.Cu")
		(net "HDD_PRSNT_35")
	)
	(segment
		(start 476.123 -18.7198)
		(end 476.123 -18.7325)
		(width 0.17145)
		(layer "F.Cu")
		(net "HDD_PRSNT_35")
	)
	(segment
		(start 477.0755 -20.701)
		(end 477.0755 -21.0439)
		(width 0.17145)
		(layer "F.Cu")
		(net "HDD_PRSNT_35")
	)
	(via
		(at 476.123 -18.7198)
		(size 0.6604)
		(drill 0.3302)
		(layers "F.Cu" "B.Cu")
		(net "HDD_PRSNT_35")
	)
	(segment
		(start 446.337436 -32.0929)
		(end 446.223136 -31.9786)
		(width 0.17145)
		(layer "F.Cu")
		(net "HDD_PRSNT_34")
	)
	(segment
		(start 446.9384 -32.0929)
		(end 446.337436 -32.0929)
		(width 0.17145)
		(layer "F.Cu")
		(net "HDD_PRSNT_34")
	)
	(segment
		(start 449.429378 -32.085026)
		(end 453.574912 -32.085026)
		(width 0.17145)
		(layer "F.Cu")
		(net "HDD_PRSNT_34")
	)
	(segment
		(start 446.223136 -31.9786)
		(end 445.5922 -31.9786)
		(width 0.17145)
		(layer "F.Cu")
		(net "HDD_PRSNT_34")
	)
	(segment
		(start 447.9544 -32.0929)
		(end 446.9384 -32.0929)
		(width 0.17145)
		(layer "F.Cu")
		(net "HDD_PRSNT_34")
	)
	(segment
		(start 447.9544 -32.0929)
		(end 449.421504 -32.0929)
		(width 0.17145)
		(layer "F.Cu")
		(net "HDD_PRSNT_34")
	)
	(segment
		(start 449.421504 -32.0929)
		(end 449.429378 -32.085026)
		(width 0.17145)
		(layer "F.Cu")
		(net "HDD_PRSNT_34")
	)
	(segment
		(start 445.5922 -31.9786)
		(end 444.4238 -31.9786)
		(width 0.17145)
		(layer "F.Cu")
		(net "HDD_PRSNT_34")
	)
	(via
		(at 445.5922 -31.9786)
		(size 0.6604)
		(drill 0.3302)
		(layers "F.Cu" "B.Cu")
		(net "HDD_PRSNT_34")
	)
	(segment
		(start 414.053274 -32.1056)
		(end 414.065974 -32.0929)
		(width 0.17145)
		(layer "F.Cu")
		(net "HDD_PRSNT_33")
	)
	(segment
		(start 417.251388 -32.0929)
		(end 417.259262 -32.085026)
		(width 0.17145)
		(layer "F.Cu")
		(net "HDD_PRSNT_33")
	)
	(segment
		(start 416.3822 -32.0929)
		(end 415.3662 -32.0929)
		(width 0.17145)
		(layer "F.Cu")
		(net "HDD_PRSNT_33")
	)
	(segment
		(start 412.8262 -32.1056)
		(end 414.053274 -32.1056)
		(width 0.17145)
		(layer "F.Cu")
		(net "HDD_PRSNT_33")
	)
	(segment
		(start 415.3662 -32.0929)
		(end 414.065974 -32.0929)
		(width 0.17145)
		(layer "F.Cu")
		(net "HDD_PRSNT_33")
	)
	(segment
		(start 417.259262 -32.085026)
		(end 422.025064 -32.085026)
		(width 0.17145)
		(layer "F.Cu")
		(net "HDD_PRSNT_33")
	)
	(segment
		(start 416.3822 -32.0929)
		(end 417.251388 -32.0929)
		(width 0.17145)
		(layer "F.Cu")
		(net "HDD_PRSNT_33")
	)
	(via
		(at 414.065974 -32.0929)
		(size 0.6604)
		(drill 0.3302)
		(layers "F.Cu" "B.Cu")
		(net "HDD_PRSNT_33")
	)
	(segment
		(start 382.515872 -32.0929)
		(end 383.8956 -32.0929)
		(width 0.17145)
		(layer "F.Cu")
		(net "HDD_PRSNT_32")
	)
	(segment
		(start 381.3429 -32.0929)
		(end 382.515872 -32.0929)
		(width 0.17145)
		(layer "F.Cu")
		(net "HDD_PRSNT_32")
	)
	(segment
		(start 384.9116 -32.0929)
		(end 384.919474 -32.085026)
		(width 0.17145)
		(layer "F.Cu")
		(net "HDD_PRSNT_32")
	)
	(segment
		(start 384.9116 -32.0929)
		(end 383.8956 -32.0929)
		(width 0.17145)
		(layer "F.Cu")
		(net "HDD_PRSNT_32")
	)
	(segment
		(start 384.919474 -32.085026)
		(end 390.474962 -32.085026)
		(width 0.17145)
		(layer "F.Cu")
		(net "HDD_PRSNT_32")
	)
	(segment
		(start 381.3302 -32.1056)
		(end 381.3429 -32.0929)
		(width 0.17145)
		(layer "F.Cu")
		(net "HDD_PRSNT_32")
	)
	(via
		(at 382.515872 -32.0929)
		(size 0.6604)
		(drill 0.3302)
		(layers "F.Cu" "B.Cu")
		(net "HDD_PRSNT_32")
	)
	(segment
		(start 350.966024 -32.0929)
		(end 352.3488 -32.0929)
		(width 0.17145)
		(layer "F.Cu")
		(net "HDD_PRSNT_31")
	)
	(segment
		(start 353.3648 -32.0929)
		(end 352.3488 -32.0929)
		(width 0.17145)
		(layer "F.Cu")
		(net "HDD_PRSNT_31")
	)
	(segment
		(start 349.6945 -32.0929)
		(end 350.966024 -32.0929)
		(width 0.17145)
		(layer "F.Cu")
		(net "HDD_PRSNT_31")
	)
	(segment
		(start 349.6818 -32.1056)
		(end 349.6945 -32.0929)
		(width 0.17145)
		(layer "F.Cu")
		(net "HDD_PRSNT_31")
	)
	(segment
		(start 353.3648 -32.0929)
		(end 353.372674 -32.085026)
		(width 0.17145)
		(layer "F.Cu")
		(net "HDD_PRSNT_31")
	)
	(segment
		(start 353.372674 -32.085026)
		(end 358.925114 -32.085026)
		(width 0.17145)
		(layer "F.Cu")
		(net "HDD_PRSNT_31")
	)
	(via
		(at 350.966024 -32.0929)
		(size 0.6604)
		(drill 0.3302)
		(layers "F.Cu" "B.Cu")
		(net "HDD_PRSNT_31")
	)
	(segment
		(start 321.7164 -32.0929)
		(end 320.7004 -32.0929)
		(width 0.17145)
		(layer "F.Cu")
		(net "HDD_PRSNT_30")
	)
	(segment
		(start 322.968874 -32.0929)
		(end 322.976748 -32.085026)
		(width 0.17145)
		(layer "F.Cu")
		(net "HDD_PRSNT_30")
	)
	(segment
		(start 318.262 -32.1056)
		(end 318.2747 -32.0929)
		(width 0.17145)
		(layer "F.Cu")
		(net "HDD_PRSNT_30")
	)
	(segment
		(start 321.7164 -32.0929)
		(end 322.968874 -32.0929)
		(width 0.17145)
		(layer "F.Cu")
		(net "HDD_PRSNT_30")
	)
	(segment
		(start 322.976748 -32.085026)
		(end 327.375012 -32.085026)
		(width 0.17145)
		(layer "F.Cu")
		(net "HDD_PRSNT_30")
	)
	(segment
		(start 318.2747 -32.0929)
		(end 319.413382 -32.0929)
		(width 0.17145)
		(layer "F.Cu")
		(net "HDD_PRSNT_30")
	)
	(segment
		(start 320.7004 -32.0929)
		(end 319.413382 -32.0929)
		(width 0.17145)
		(layer "F.Cu")
		(net "HDD_PRSNT_30")
	)
	(via
		(at 319.413382 -32.0929)
		(size 0.6604)
		(drill 0.3302)
		(layers "F.Cu" "B.Cu")
		(net "HDD_PRSNT_30")
	)
	(segment
		(start 129.4765 -263.144)
		(end 129.4765 -264.541)
		(width 0.17145)
		(layer "F.Cu")
		(net "HDD_PRSNT_3")
	)
	(segment
		(start 129.54 -266.065)
		(end 129.54 -264.6045)
		(width 0.17145)
		(layer "F.Cu")
		(net "HDD_PRSNT_3")
	)
	(segment
		(start 129.4765 -262.128)
		(end 129.433574 -262.085074)
		(width 0.17145)
		(layer "F.Cu")
		(net "HDD_PRSNT_3")
	)
	(segment
		(start 129.54 -264.6045)
		(end 129.4765 -264.541)
		(width 0.17145)
		(layer "F.Cu")
		(net "HDD_PRSNT_3")
	)
	(segment
		(start 129.4765 -262.128)
		(end 129.4765 -263.144)
		(width 0.17145)
		(layer "F.Cu")
		(net "HDD_PRSNT_3")
	)
	(segment
		(start 129.433574 -262.085074)
		(end 124.674884 -262.085074)
		(width 0.17145)
		(layer "F.Cu")
		(net "HDD_PRSNT_3")
	)
	(via
		(at 129.4765 -264.541)
		(size 0.6604)
		(drill 0.3302)
		(layers "F.Cu" "B.Cu")
		(net "HDD_PRSNT_3")
	)
	(segment
		(start 190.009526 -32.085026)
		(end 187.775088 -32.085026)
		(width 0.17145)
		(layer "F.Cu")
		(net "HDD_PRSNT_29")
	)
	(segment
		(start 190.0555 -32.131)
		(end 190.0555 -33.147)
		(width 0.17145)
		(layer "F.Cu")
		(net "HDD_PRSNT_29")
	)
	(segment
		(start 190.0555 -32.131)
		(end 190.009526 -32.085026)
		(width 0.17145)
		(layer "F.Cu")
		(net "HDD_PRSNT_29")
	)
	(segment
		(start 190.0555 -33.782)
		(end 190.0555 -33.147)
		(width 0.17145)
		(layer "F.Cu")
		(net "HDD_PRSNT_29")
	)
	(segment
		(start 190.0936 -34.8234)
		(end 190.0936 -33.8201)
		(width 0.17145)
		(layer "F.Cu")
		(net "HDD_PRSNT_29")
	)
	(segment
		(start 190.0936 -33.8201)
		(end 190.0555 -33.782)
		(width 0.17145)
		(layer "F.Cu")
		(net "HDD_PRSNT_29")
	)
	(segment
		(start 158.496 -32.0675)
		(end 158.513526 -32.085026)
		(width 0.17145)
		(layer "F.Cu")
		(net "HDD_PRSNT_28")
	)
	(segment
		(start 158.513526 -32.085026)
		(end 156.224986 -32.085026)
		(width 0.17145)
		(layer "F.Cu")
		(net "HDD_PRSNT_28")
	)
	(segment
		(start 160.775396 -32.0675)
		(end 159.512 -32.0675)
		(width 0.17145)
		(layer "F.Cu")
		(net "HDD_PRSNT_28")
	)
	(segment
		(start 161.8615 -32.0675)
		(end 160.775396 -32.0675)
		(width 0.17145)
		(layer "F.Cu")
		(net "HDD_PRSNT_28")
	)
	(segment
		(start 161.8742 -32.0802)
		(end 161.8615 -32.0675)
		(width 0.17145)
		(layer "F.Cu")
		(net "HDD_PRSNT_28")
	)
	(segment
		(start 159.512 -32.0675)
		(end 158.496 -32.0675)
		(width 0.17145)
		(layer "F.Cu")
		(net "HDD_PRSNT_28")
	)
	(via
		(at 160.775396 -32.0675)
		(size 0.6604)
		(drill 0.3302)
		(layers "F.Cu" "B.Cu")
		(net "HDD_PRSNT_28")
	)
	(segment
		(start 130.4417 -32.0675)
		(end 129.225294 -32.0675)
		(width 0.17145)
		(layer "F.Cu")
		(net "HDD_PRSNT_27")
	)
	(segment
		(start 130.4544 -32.0802)
		(end 130.4417 -32.0675)
		(width 0.17145)
		(layer "F.Cu")
		(net "HDD_PRSNT_27")
	)
	(segment
		(start 126.286006 -32.085026)
		(end 124.674884 -32.085026)
		(width 0.17145)
		(layer "F.Cu")
		(net "HDD_PRSNT_27")
	)
	(segment
		(start 126.303532 -32.0675)
		(end 126.286006 -32.085026)
		(width 0.17145)
		(layer "F.Cu")
		(net "HDD_PRSNT_27")
	)
	(segment
		(start 126.9746 -32.0675)
		(end 127.9906 -32.0675)
		(width 0.17145)
		(layer "F.Cu")
		(net "HDD_PRSNT_27")
	)
	(segment
		(start 126.9746 -32.0675)
		(end 126.303532 -32.0675)
		(width 0.17145)
		(layer "F.Cu")
		(net "HDD_PRSNT_27")
	)
	(segment
		(start 127.9906 -32.0675)
		(end 129.225294 -32.0675)
		(width 0.17145)
		(layer "F.Cu")
		(net "HDD_PRSNT_27")
	)
	(via
		(at 129.225294 -32.0675)
		(size 0.6604)
		(drill 0.3302)
		(layers "F.Cu" "B.Cu")
		(net "HDD_PRSNT_27")
	)
	(segment
		(start 95.377 -32.0929)
		(end 94.545404 -32.0929)
		(width 0.17145)
		(layer "F.Cu")
		(net "HDD_PRSNT_26")
	)
	(segment
		(start 98.806 -32.1056)
		(end 98.7933 -32.0929)
		(width 0.17145)
		(layer "F.Cu")
		(net "HDD_PRSNT_26")
	)
	(segment
		(start 96.393 -32.0929)
		(end 95.377 -32.0929)
		(width 0.17145)
		(layer "F.Cu")
		(net "HDD_PRSNT_26")
	)
	(segment
		(start 98.7933 -32.0929)
		(end 97.675446 -32.0929)
		(width 0.17145)
		(layer "F.Cu")
		(net "HDD_PRSNT_26")
	)
	(segment
		(start 97.675446 -32.0929)
		(end 96.393 -32.0929)
		(width 0.17145)
		(layer "F.Cu")
		(net "HDD_PRSNT_26")
	)
	(segment
		(start 94.53753 -32.085026)
		(end 93.125036 -32.085026)
		(width 0.17145)
		(layer "F.Cu")
		(net "HDD_PRSNT_26")
	)
	(segment
		(start 94.545404 -32.0929)
		(end 94.53753 -32.085026)
		(width 0.17145)
		(layer "F.Cu")
		(net "HDD_PRSNT_26")
	)
	(via
		(at 97.675446 -32.0929)
		(size 0.6604)
		(drill 0.3302)
		(layers "F.Cu" "B.Cu")
		(net "HDD_PRSNT_26")
	)
	(segment
		(start 64.7446 -32.0929)
		(end 63.7286 -32.0929)
		(width 0.17145)
		(layer "F.Cu")
		(net "HDD_PRSNT_25")
	)
	(segment
		(start 63.7286 -32.0929)
		(end 62.958218 -32.0929)
		(width 0.17145)
		(layer "F.Cu")
		(net "HDD_PRSNT_25")
	)
	(segment
		(start 67.2719 -32.0929)
		(end 66.1416 -32.0929)
		(width 0.17145)
		(layer "F.Cu")
		(net "HDD_PRSNT_25")
	)
	(segment
		(start 62.950344 -32.085026)
		(end 61.574934 -32.085026)
		(width 0.17145)
		(layer "F.Cu")
		(net "HDD_PRSNT_25")
	)
	(segment
		(start 66.1416 -32.0929)
		(end 64.7446 -32.0929)
		(width 0.17145)
		(layer "F.Cu")
		(net "HDD_PRSNT_25")
	)
	(segment
		(start 67.31 -32.0548)
		(end 67.2719 -32.0929)
		(width 0.17145)
		(layer "F.Cu")
		(net "HDD_PRSNT_25")
	)
	(segment
		(start 62.958218 -32.0929)
		(end 62.950344 -32.085026)
		(width 0.17145)
		(layer "F.Cu")
		(net "HDD_PRSNT_25")
	)
	(via
		(at 66.1416 -32.0929)
		(size 0.6604)
		(drill 0.3302)
		(layers "F.Cu" "B.Cu")
		(net "HDD_PRSNT_25")
	)
	(segment
		(start 33.4264 -32.0421)
		(end 32.4104 -32.0421)
		(width 0.17145)
		(layer "F.Cu")
		(net "HDD_PRSNT_24")
	)
	(segment
		(start 35.6743 -32.0421)
		(end 34.5948 -32.0421)
		(width 0.17145)
		(layer "F.Cu")
		(net "HDD_PRSNT_24")
	)
	(segment
		(start 34.5948 -32.0421)
		(end 33.4264 -32.0421)
		(width 0.17145)
		(layer "F.Cu")
		(net "HDD_PRSNT_24")
	)
	(segment
		(start 31.869126 -32.0421)
		(end 31.8262 -32.085026)
		(width 0.17145)
		(layer "F.Cu")
		(net "HDD_PRSNT_24")
	)
	(segment
		(start 31.8262 -32.085026)
		(end 30.025086 -32.085026)
		(width 0.17145)
		(layer "F.Cu")
		(net "HDD_PRSNT_24")
	)
	(segment
		(start 32.4104 -32.0421)
		(end 31.869126 -32.0421)
		(width 0.17145)
		(layer "F.Cu")
		(net "HDD_PRSNT_24")
	)
	(segment
		(start 35.687 -32.0294)
		(end 35.6743 -32.0421)
		(width 0.17145)
		(layer "F.Cu")
		(net "HDD_PRSNT_24")
	)
	(via
		(at 34.5948 -32.0421)
		(size 0.6604)
		(drill 0.3302)
		(layers "F.Cu" "B.Cu")
		(net "HDD_PRSNT_24")
	)
	(segment
		(start 477.267016 -136.513316)
		(end 478.44202 -136.513316)
		(width 0.17145)
		(layer "F.Cu")
		(net "HDD_PRSNT_23")
	)
	(segment
		(start 476.5421 -134.7724)
		(end 476.5421 -135.7884)
		(width 0.17145)
		(layer "F.Cu")
		(net "HDD_PRSNT_23")
	)
	(segment
		(start 482.49205 -147.08505)
		(end 485.125014 -147.08505)
		(width 0.17145)
		(layer "F.Cu")
		(net "HDD_PRSNT_23")
	)
	(segment
		(start 478.917 -143.51)
		(end 482.49205 -147.08505)
		(width 0.17145)
		(layer "F.Cu")
		(net "HDD_PRSNT_23")
	)
	(segment
		(start 476.5294 -133.5786)
		(end 476.5421 -133.5913)
		(width 0.17145)
		(layer "F.Cu")
		(net "HDD_PRSNT_23")
	)
	(segment
		(start 478.44202 -136.513316)
		(end 478.917 -136.988296)
		(width 0.17145)
		(layer "F.Cu")
		(net "HDD_PRSNT_23")
	)
	(segment
		(start 478.917 -136.988296)
		(end 478.917 -143.51)
		(width 0.17145)
		(layer "F.Cu")
		(net "HDD_PRSNT_23")
	)
	(segment
		(start 476.5421 -133.5913)
		(end 476.5421 -134.7724)
		(width 0.17145)
		(layer "F.Cu")
		(net "HDD_PRSNT_23")
	)
	(segment
		(start 476.5421 -135.7884)
		(end 477.267016 -136.513316)
		(width 0.17145)
		(layer "F.Cu")
		(net "HDD_PRSNT_23")
	)
	(segment
		(start 476.5294 -132.3848)
		(end 476.5294 -133.5786)
		(width 0.17145)
		(layer "F.Cu")
		(net "HDD_PRSNT_23")
	)
	(via
		(at 476.5421 -133.5913)
		(size 0.6604)
		(drill 0.3302)
		(layers "F.Cu" "B.Cu")
		(net "HDD_PRSNT_23")
	)
	(segment
		(start 447.97345 -147.08505)
		(end 453.574912 -147.08505)
		(width 0.17145)
		(layer "F.Cu")
		(net "HDD_PRSNT_22")
	)
	(segment
		(start 447.8655 -149.5425)
		(end 447.802 -149.606)
		(width 0.17145)
		(layer "F.Cu")
		(net "HDD_PRSNT_22")
	)
	(segment
		(start 447.8655 -148.209)
		(end 447.8655 -149.5425)
		(width 0.17145)
		(layer "F.Cu")
		(net "HDD_PRSNT_22")
	)
	(segment
		(start 447.802 -151.13)
		(end 447.802 -149.606)
		(width 0.17145)
		(layer "F.Cu")
		(net "HDD_PRSNT_22")
	)
	(segment
		(start 447.8655 -147.193)
		(end 447.97345 -147.08505)
		(width 0.17145)
		(layer "F.Cu")
		(net "HDD_PRSNT_22")
	)
	(segment
		(start 447.8655 -147.193)
		(end 447.8655 -148.209)
		(width 0.17145)
		(layer "F.Cu")
		(net "HDD_PRSNT_22")
	)
	(via
		(at 447.802 -149.606)
		(size 0.6604)
		(drill 0.3302)
		(layers "F.Cu" "B.Cu")
		(net "HDD_PRSNT_22")
	)
	(segment
		(start 416.1028 -147.0787)
		(end 418.041582 -147.0787)
		(width 0.17145)
		(layer "F.Cu")
		(net "HDD_PRSNT_21")
	)
	(segment
		(start 418.041582 -147.0787)
		(end 418.047932 -147.08505)
		(width 0.17145)
		(layer "F.Cu")
		(net "HDD_PRSNT_21")
	)
	(segment
		(start 412.877 -147.066)
		(end 414.0327 -147.066)
		(width 0.17145)
		(layer "F.Cu")
		(net "HDD_PRSNT_21")
	)
	(segment
		(start 416.1028 -147.0787)
		(end 415.0868 -147.0787)
		(width 0.17145)
		(layer "F.Cu")
		(net "HDD_PRSNT_21")
	)
	(segment
		(start 415.0868 -147.0787)
		(end 414.0454 -147.0787)
		(width 0.17145)
		(layer "F.Cu")
		(net "HDD_PRSNT_21")
	)
	(segment
		(start 414.0327 -147.066)
		(end 414.0454 -147.0787)
		(width 0.17145)
		(layer "F.Cu")
		(net "HDD_PRSNT_21")
	)
	(segment
		(start 418.047932 -147.08505)
		(end 422.025064 -147.08505)
		(width 0.17145)
		(layer "F.Cu")
		(net "HDD_PRSNT_21")
	)
	(via
		(at 414.0454 -147.0787)
		(size 0.6604)
		(drill 0.3302)
		(layers "F.Cu" "B.Cu")
		(net "HDD_PRSNT_21")
	)
	(segment
		(start 384.8608 -147.0787)
		(end 383.8448 -147.0787)
		(width 0.17145)
		(layer "F.Cu")
		(net "HDD_PRSNT_20")
	)
	(segment
		(start 386.087366 -147.08505)
		(end 390.474962 -147.08505)
		(width 0.17145)
		(layer "F.Cu")
		(net "HDD_PRSNT_20")
	)
	(segment
		(start 384.8608 -147.0787)
		(end 386.081016 -147.0787)
		(width 0.17145)
		(layer "F.Cu")
		(net "HDD_PRSNT_20")
	)
	(segment
		(start 383.244598 -147.0152)
		(end 382.4986 -147.0152)
		(width 0.17145)
		(layer "F.Cu")
		(net "HDD_PRSNT_20")
	)
	(segment
		(start 386.081016 -147.0787)
		(end 386.087366 -147.08505)
		(width 0.17145)
		(layer "F.Cu")
		(net "HDD_PRSNT_20")
	)
	(segment
		(start 383.308098 -147.0787)
		(end 383.244598 -147.0152)
		(width 0.17145)
		(layer "F.Cu")
		(net "HDD_PRSNT_20")
	)
	(segment
		(start 381.2032 -147.0152)
		(end 382.4986 -147.0152)
		(width 0.17145)
		(layer "F.Cu")
		(net "HDD_PRSNT_20")
	)
	(segment
		(start 383.8448 -147.0787)
		(end 383.308098 -147.0787)
		(width 0.17145)
		(layer "F.Cu")
		(net "HDD_PRSNT_20")
	)
	(via
		(at 382.4986 -147.0152)
		(size 0.6604)
		(drill 0.3302)
		(layers "F.Cu" "B.Cu")
		(net "HDD_PRSNT_20")
	)
	(segment
		(start 97.9805 -262.128)
		(end 97.9805 -263.144)
		(width 0.17145)
		(layer "F.Cu")
		(net "HDD_PRSNT_2")
	)
	(segment
		(start 97.937574 -262.085074)
		(end 93.125036 -262.085074)
		(width 0.17145)
		(layer "F.Cu")
		(net "HDD_PRSNT_2")
	)
	(segment
		(start 97.9805 -263.144)
		(end 97.9805 -264.541)
		(width 0.17145)
		(layer "F.Cu")
		(net "HDD_PRSNT_2")
	)
	(segment
		(start 98.044 -264.6045)
		(end 97.9805 -264.541)
		(width 0.17145)
		(layer "F.Cu")
		(net "HDD_PRSNT_2")
	)
	(segment
		(start 98.044 -266.065)
		(end 98.044 -264.6045)
		(width 0.17145)
		(layer "F.Cu")
		(net "HDD_PRSNT_2")
	)
	(segment
		(start 97.9805 -262.128)
		(end 97.937574 -262.085074)
		(width 0.17145)
		(layer "F.Cu")
		(net "HDD_PRSNT_2")
	)
	(via
		(at 97.9805 -264.541)
		(size 0.6604)
		(drill 0.3302)
		(layers "F.Cu" "B.Cu")
		(net "HDD_PRSNT_2")
	)
	(segment
		(start 354.905564 -147.0787)
		(end 354.911914 -147.08505)
		(width 0.17145)
		(layer "F.Cu")
		(net "HDD_PRSNT_19")
	)
	(segment
		(start 354.911914 -147.08505)
		(end 358.925114 -147.08505)
		(width 0.17145)
		(layer "F.Cu")
		(net "HDD_PRSNT_19")
	)
	(segment
		(start 351.525078 -147.1168)
		(end 350.9264 -147.1168)
		(width 0.17145)
		(layer "F.Cu")
		(net "HDD_PRSNT_19")
	)
	(segment
		(start 353.1616 -147.0787)
		(end 354.905564 -147.0787)
		(width 0.17145)
		(layer "F.Cu")
		(net "HDD_PRSNT_19")
	)
	(segment
		(start 352.1456 -147.0787)
		(end 351.563178 -147.0787)
		(width 0.17145)
		(layer "F.Cu")
		(net "HDD_PRSNT_19")
	)
	(segment
		(start 353.1616 -147.0787)
		(end 352.1456 -147.0787)
		(width 0.17145)
		(layer "F.Cu")
		(net "HDD_PRSNT_19")
	)
	(segment
		(start 351.563178 -147.0787)
		(end 351.525078 -147.1168)
		(width 0.17145)
		(layer "F.Cu")
		(net "HDD_PRSNT_19")
	)
	(segment
		(start 349.7834 -147.1168)
		(end 350.9264 -147.1168)
		(width 0.17145)
		(layer "F.Cu")
		(net "HDD_PRSNT_19")
	)
	(via
		(at 350.9264 -147.1168)
		(size 0.6604)
		(drill 0.3302)
		(layers "F.Cu" "B.Cu")
		(net "HDD_PRSNT_19")
	)
	(segment
		(start 321.7164 -147.0787)
		(end 321.8561 -147.0787)
		(width 0.17145)
		(layer "F.Cu")
		(net "HDD_PRSNT_18")
	)
	(segment
		(start 321.86245 -147.08505)
		(end 327.375012 -147.08505)
		(width 0.17145)
		(layer "F.Cu")
		(net "HDD_PRSNT_18")
	)
	(segment
		(start 318.2239 -147.0787)
		(end 319.405 -147.0787)
		(width 0.17145)
		(layer "F.Cu")
		(net "HDD_PRSNT_18")
	)
	(segment
		(start 320.7004 -147.0787)
		(end 319.405 -147.0787)
		(width 0.17145)
		(layer "F.Cu")
		(net "HDD_PRSNT_18")
	)
	(segment
		(start 321.7164 -147.0787)
		(end 320.7004 -147.0787)
		(width 0.17145)
		(layer "F.Cu")
		(net "HDD_PRSNT_18")
	)
	(segment
		(start 318.2112 -147.0914)
		(end 318.2239 -147.0787)
		(width 0.17145)
		(layer "F.Cu")
		(net "HDD_PRSNT_18")
	)
	(segment
		(start 321.8561 -147.0787)
		(end 321.86245 -147.08505)
		(width 0.17145)
		(layer "F.Cu")
		(net "HDD_PRSNT_18")
	)
	(via
		(at 319.405 -147.0787)
		(size 0.6604)
		(drill 0.3302)
		(layers "F.Cu" "B.Cu")
		(net "HDD_PRSNT_18")
	)
	(segment
		(start 191.135 -149.352)
		(end 192.1002 -149.352)
		(width 0.17145)
		(layer "F.Cu")
		(net "HDD_PRSNT_17")
	)
	(segment
		(start 192.3542 -147.3327)
		(end 192.3542 -148.0312)
		(width 0.17145)
		(layer "F.Cu")
		(net "HDD_PRSNT_17")
	)
	(segment
		(start 192.1002 -147.0787)
		(end 192.3542 -147.3327)
		(width 0.17145)
		(layer "F.Cu")
		(net "HDD_PRSNT_17")
	)
	(segment
		(start 192.1002 -149.352)
		(end 192.3542 -149.098)
		(width 0.17145)
		(layer "F.Cu")
		(net "HDD_PRSNT_17")
	)
	(segment
		(start 192.3542 -149.098)
		(end 192.3542 -148.0312)
		(width 0.17145)
		(layer "F.Cu")
		(net "HDD_PRSNT_17")
	)
	(segment
		(start 191.0588 -147.0787)
		(end 192.1002 -147.0787)
		(width 0.17145)
		(layer "F.Cu")
		(net "HDD_PRSNT_17")
	)
	(segment
		(start 191.0588 -147.0787)
		(end 190.0428 -147.0787)
		(width 0.17145)
		(layer "F.Cu")
		(net "HDD_PRSNT_17")
	)
	(segment
		(start 190.0428 -147.0787)
		(end 190.03645 -147.08505)
		(width 0.17145)
		(layer "F.Cu")
		(net "HDD_PRSNT_17")
	)
	(segment
		(start 190.03645 -147.08505)
		(end 187.775088 -147.08505)
		(width 0.17145)
		(layer "F.Cu")
		(net "HDD_PRSNT_17")
	)
	(via
		(at 192.3542 -148.0312)
		(size 0.6604)
		(drill 0.3302)
		(layers "F.Cu" "B.Cu")
		(net "HDD_PRSNT_17")
	)
	(segment
		(start 161.0995 -147.066)
		(end 161.08045 -147.08505)
		(width 0.17145)
		(layer "F.Cu")
		(net "HDD_PRSNT_16")
	)
	(segment
		(start 161.0995 -149.479)
		(end 161.0995 -148.082)
		(width 0.17145)
		(layer "F.Cu")
		(net "HDD_PRSNT_16")
	)
	(segment
		(start 161.163 -149.5425)
		(end 161.0995 -149.479)
		(width 0.17145)
		(layer "F.Cu")
		(net "HDD_PRSNT_16")
	)
	(segment
		(start 161.08045 -147.08505)
		(end 156.224986 -147.08505)
		(width 0.17145)
		(layer "F.Cu")
		(net "HDD_PRSNT_16")
	)
	(segment
		(start 161.163 -151.003)
		(end 161.163 -149.5425)
		(width 0.17145)
		(layer "F.Cu")
		(net "HDD_PRSNT_16")
	)
	(segment
		(start 161.0995 -148.082)
		(end 161.0995 -147.066)
		(width 0.17145)
		(layer "F.Cu")
		(net "HDD_PRSNT_16")
	)
	(via
		(at 161.0995 -149.479)
		(size 0.6604)
		(drill 0.3302)
		(layers "F.Cu" "B.Cu")
		(net "HDD_PRSNT_16")
	)
	(segment
		(start 129.54 -151.003)
		(end 129.54 -149.5425)
		(width 0.17145)
		(layer "F.Cu")
		(net "HDD_PRSNT_15")
	)
	(segment
		(start 129.4765 -148.082)
		(end 129.4765 -147.066)
		(width 0.17145)
		(layer "F.Cu")
		(net "HDD_PRSNT_15")
	)
	(segment
		(start 129.4765 -149.479)
		(end 129.4765 -148.082)
		(width 0.17145)
		(layer "F.Cu")
		(net "HDD_PRSNT_15")
	)
	(segment
		(start 127.258318 -147.08505)
		(end 124.674884 -147.08505)
		(width 0.17145)
		(layer "F.Cu")
		(net "HDD_PRSNT_15")
	)
	(segment
		(start 127.277368 -147.066)
		(end 127.258318 -147.08505)
		(width 0.17145)
		(layer "F.Cu")
		(net "HDD_PRSNT_15")
	)
	(segment
		(start 129.54 -149.5425)
		(end 129.4765 -149.479)
		(width 0.17145)
		(layer "F.Cu")
		(net "HDD_PRSNT_15")
	)
	(segment
		(start 129.4765 -147.066)
		(end 127.277368 -147.066)
		(width 0.17145)
		(layer "F.Cu")
		(net "HDD_PRSNT_15")
	)
	(via
		(at 129.4765 -149.479)
		(size 0.6604)
		(drill 0.3302)
		(layers "F.Cu" "B.Cu")
		(net "HDD_PRSNT_15")
	)
	(segment
		(start 97.9805 -148.082)
		(end 97.9805 -149.479)
		(width 0.17145)
		(layer "F.Cu")
		(net "HDD_PRSNT_14")
	)
	(segment
		(start 98.044 -149.5425)
		(end 97.9805 -149.479)
		(width 0.17145)
		(layer "F.Cu")
		(net "HDD_PRSNT_14")
	)
	(segment
		(start 97.9805 -147.066)
		(end 97.9805 -148.082)
		(width 0.17145)
		(layer "F.Cu")
		(net "HDD_PRSNT_14")
	)
	(segment
		(start 97.9805 -147.066)
		(end 97.96145 -147.08505)
		(width 0.17145)
		(layer "F.Cu")
		(net "HDD_PRSNT_14")
	)
	(segment
		(start 97.96145 -147.08505)
		(end 93.125036 -147.08505)
		(width 0.17145)
		(layer "F.Cu")
		(net "HDD_PRSNT_14")
	)
	(segment
		(start 98.044 -151.003)
		(end 98.044 -149.5425)
		(width 0.17145)
		(layer "F.Cu")
		(net "HDD_PRSNT_14")
	)
	(via
		(at 97.9805 -149.479)
		(size 0.6604)
		(drill 0.3302)
		(layers "F.Cu" "B.Cu")
		(net "HDD_PRSNT_14")
	)
	(segment
		(start 66.3575 -147.066)
		(end 66.33845 -147.08505)
		(width 0.17145)
		(layer "F.Cu")
		(net "HDD_PRSNT_13")
	)
	(segment
		(start 66.421 -151.003)
		(end 66.421 -149.5425)
		(width 0.17145)
		(layer "F.Cu")
		(net "HDD_PRSNT_13")
	)
	(segment
		(start 66.3575 -149.479)
		(end 66.3575 -148.082)
		(width 0.17145)
		(layer "F.Cu")
		(net "HDD_PRSNT_13")
	)
	(segment
		(start 66.3575 -147.066)
		(end 66.3575 -148.082)
		(width 0.17145)
		(layer "F.Cu")
		(net "HDD_PRSNT_13")
	)
	(segment
		(start 66.33845 -147.08505)
		(end 61.574934 -147.08505)
		(width 0.17145)
		(layer "F.Cu")
		(net "HDD_PRSNT_13")
	)
	(segment
		(start 66.421 -149.5425)
		(end 66.3575 -149.479)
		(width 0.17145)
		(layer "F.Cu")
		(net "HDD_PRSNT_13")
	)
	(via
		(at 66.3575 -149.479)
		(size 0.6604)
		(drill 0.3302)
		(layers "F.Cu" "B.Cu")
		(net "HDD_PRSNT_13")
	)
	(segment
		(start 34.925 -149.5425)
		(end 34.8615 -149.479)
		(width 0.17145)
		(layer "F.Cu")
		(net "HDD_PRSNT_12")
	)
	(segment
		(start 34.8615 -147.066)
		(end 34.84245 -147.08505)
		(width 0.17145)
		(layer "F.Cu")
		(net "HDD_PRSNT_12")
	)
	(segment
		(start 34.8615 -147.066)
		(end 34.8615 -148.082)
		(width 0.17145)
		(layer "F.Cu")
		(net "HDD_PRSNT_12")
	)
	(segment
		(start 34.84245 -147.08505)
		(end 30.025086 -147.08505)
		(width 0.17145)
		(layer "F.Cu")
		(net "HDD_PRSNT_12")
	)
	(segment
		(start 34.925 -151.003)
		(end 34.925 -149.5425)
		(width 0.17145)
		(layer "F.Cu")
		(net "HDD_PRSNT_12")
	)
	(segment
		(start 34.8615 -148.082)
		(end 34.8615 -149.479)
		(width 0.17145)
		(layer "F.Cu")
		(net "HDD_PRSNT_12")
	)
	(via
		(at 34.8615 -149.479)
		(size 0.6604)
		(drill 0.3302)
		(layers "F.Cu" "B.Cu")
		(net "HDD_PRSNT_12")
	)
	(segment
		(start 478.028 -251.0155)
		(end 478.79 -251.7775)
		(width 0.17145)
		(layer "F.Cu")
		(net "HDD_PRSNT_11")
	)
	(segment
		(start 477.4692 -251.0155)
		(end 478.028 -251.0155)
		(width 0.17145)
		(layer "F.Cu")
		(net "HDD_PRSNT_11")
	)
	(segment
		(start 475.4626 -251.0028)
		(end 476.4405 -251.0028)
		(width 0.17145)
		(layer "F.Cu")
		(net "HDD_PRSNT_11")
	)
	(segment
		(start 478.79 -251.7775)
		(end 478.79 -258.445)
		(width 0.17145)
		(layer "F.Cu")
		(net "HDD_PRSNT_11")
	)
	(segment
		(start 476.4532 -251.0155)
		(end 477.4692 -251.0155)
		(width 0.17145)
		(layer "F.Cu")
		(net "HDD_PRSNT_11")
	)
	(segment
		(start 474.345 -251.0028)
		(end 475.4626 -251.0028)
		(width 0.17145)
		(layer "F.Cu")
		(net "HDD_PRSNT_11")
	)
	(segment
		(start 478.79 -258.445)
		(end 482.430074 -262.085074)
		(width 0.17145)
		(layer "F.Cu")
		(net "HDD_PRSNT_11")
	)
	(segment
		(start 476.4405 -251.0028)
		(end 476.4532 -251.0155)
		(width 0.17145)
		(layer "F.Cu")
		(net "HDD_PRSNT_11")
	)
	(segment
		(start 482.430074 -262.085074)
		(end 485.125014 -262.085074)
		(width 0.17145)
		(layer "F.Cu")
		(net "HDD_PRSNT_11")
	)
	(via
		(at 475.4626 -251.0028)
		(size 0.6604)
		(drill 0.3302)
		(layers "F.Cu" "B.Cu")
		(net "HDD_PRSNT_11")
	)
	(segment
		(start 445.5922 -262.0899)
		(end 446.8622 -262.0899)
		(width 0.17145)
		(layer "F.Cu")
		(net "HDD_PRSNT_10")
	)
	(segment
		(start 448.051174 -262.0899)
		(end 448.056 -262.085074)
		(width 0.17145)
		(layer "F.Cu")
		(net "HDD_PRSNT_10")
	)
	(segment
		(start 447.8782 -262.0899)
		(end 448.051174 -262.0899)
		(width 0.17145)
		(layer "F.Cu")
		(net "HDD_PRSNT_10")
	)
	(segment
		(start 448.056 -262.085074)
		(end 453.574912 -262.085074)
		(width 0.17145)
		(layer "F.Cu")
		(net "HDD_PRSNT_10")
	)
	(segment
		(start 445.5795 -262.1026)
		(end 445.5922 -262.0899)
		(width 0.17145)
		(layer "F.Cu")
		(net "HDD_PRSNT_10")
	)
	(segment
		(start 444.3222 -262.1026)
		(end 445.5795 -262.1026)
		(width 0.17145)
		(layer "F.Cu")
		(net "HDD_PRSNT_10")
	)
	(segment
		(start 447.8782 -262.0899)
		(end 446.8622 -262.0899)
		(width 0.17145)
		(layer "F.Cu")
		(net "HDD_PRSNT_10")
	)
	(via
		(at 445.5922 -262.0899)
		(size 0.6604)
		(drill 0.3302)
		(layers "F.Cu" "B.Cu")
		(net "HDD_PRSNT_10")
	)
	(segment
		(start 66.3448 -264.7442)
		(end 66.421 -264.668)
		(width 0.17145)
		(layer "F.Cu")
		(net "HDD_PRSNT_1")
	)
	(segment
		(start 66.2813 -264.5283)
		(end 66.421 -264.668)
		(width 0.17145)
		(layer "F.Cu")
		(net "HDD_PRSNT_1")
	)
	(segment
		(start 66.238374 -262.085074)
		(end 61.574934 -262.085074)
		(width 0.17145)
		(layer "F.Cu")
		(net "HDD_PRSNT_1")
	)
	(segment
		(start 66.3448 -266.065)
		(end 66.3448 -264.7442)
		(width 0.17145)
		(layer "F.Cu")
		(net "HDD_PRSNT_1")
	)
	(segment
		(start 66.2813 -263.144)
		(end 66.2813 -264.5283)
		(width 0.17145)
		(layer "F.Cu")
		(net "HDD_PRSNT_1")
	)
	(segment
		(start 66.2813 -262.128)
		(end 66.2813 -263.144)
		(width 0.17145)
		(layer "F.Cu")
		(net "HDD_PRSNT_1")
	)
	(segment
		(start 66.2813 -262.128)
		(end 66.238374 -262.085074)
		(width 0.17145)
		(layer "F.Cu")
		(net "HDD_PRSNT_1")
	)
	(via
		(at 66.421 -264.668)
		(size 0.6604)
		(drill 0.3302)
		(layers "F.Cu" "B.Cu")
		(net "HDD_PRSNT_1")
	)
	(segment
		(start 222.18396 -164.38626)
		(end 223.19996 -164.38626)
		(width 0.508)
		(layer "F.Cu")
		(net "GND")
	)
	(segment
		(start 223.114362 -204.978)
		(end 223.769682 -204.32268)
		(width 0.508)
		(layer "F.Cu")
		(net "GND")
	)
	(segment
		(start 444.485268 -103.07828)
		(end 444.487808 -103.08082)
		(width 0.508)
		(layer "F.Cu")
		(net "GND")
	)
	(segment
		(start 32.584644 -10.385044)
		(end 32.2326 -10.033)
		(width 0.3048)
		(layer "F.Cu")
		(net "GND")
	)
	(segment
		(start 165.862 -377.1265)
		(end 165.862 -378.079)
		(width 0.508)
		(layer "F.Cu")
		(net "GND")
	)
	(segment
		(start 86.5505 -19.558)
		(end 86.5505 -20.447)
		(width 0.508)
		(layer "F.Cu")
		(net "GND")
	)
	(segment
		(start 219.165932 -353.794568)
		(end 220.091 -353.794568)
		(width 0.508)
		(layer "F.Cu")
		(net "GND")
	)
	(segment
		(start 178.83124 -135.4328)
		(end 179.7558 -135.4328)
		(width 0.4064)
		(layer "F.Cu")
		(net "GND")
	)
	(segment
		(start 81.788 -260.604)
		(end 81.788 -262.001)
		(width 0.508)
		(layer "F.Cu")
		(net "GND")
	)
	(segment
		(start 27.298396 -371.3861)
		(end 27.101038 -371.3861)
		(width 0.508)
		(layer "F.Cu")
		(net "GND")
	)
	(segment
		(start 25.355042 -251.430028)
		(end 27.161998 -251.430028)
		(width 0.508)
		(layer "F.Cu")
		(net "GND")
	)
	(segment
		(start 241.046 -308.558692)
		(end 240.867692 -308.737)
		(width 0.2032)
		(layer "F.Cu")
		(net "GND")
	)
	(segment
		(start 321.709796 -369.2906)
		(end 321.709796 -368.8842)
		(width 0.4064)
		(layer "F.Cu")
		(net "GND")
	)
	(segment
		(start 23.4315 -134.493)
		(end 23.4315 -135.382)
		(width 0.508)
		(layer "F.Cu")
		(net "GND")
	)
	(segment
		(start 156.224986 -16.845026)
		(end 154.504898 -16.845026)
		(width 0.508)
		(layer "F.Cu")
		(net "GND")
	)
	(segment
		(start 457.2762 -246.90324)
		(end 457.2762 -247.65)
		(width 0.4064)
		(layer "F.Cu")
		(net "GND")
	)
	(segment
		(start 390.474962 -153.43505)
		(end 388.754874 -153.43505)
		(width 0.508)
		(layer "F.Cu")
		(net "GND")
	)
	(segment
		(start 237.363 -223.52)
		(end 237.363 -224.829624)
		(width 0.508)
		(layer "F.Cu")
		(net "GND")
	)
	(segment
		(start 238.9505 -228.219)
		(end 238.506 -227.7745)
		(width 0.508)
		(layer "F.Cu")
		(net "GND")
	)
	(segment
		(start 215.09228 -164.00526)
		(end 215.1253 -164.03828)
		(width 0.508)
		(layer "F.Cu")
		(net "GND")
	)
	(segment
		(start 233.26852 -234.504738)
		(end 233.265726 -234.507532)
		(width 0.508)
		(layer "F.Cu")
		(net "GND")
	)
	(segment
		(start 98.8695 -262.128)
		(end 98.8695 -261.239)
		(width 0.508)
		(layer "F.Cu")
		(net "GND")
	)
	(segment
		(start 459.1558 -245.60276)
		(end 459.1558 -244.856)
		(width 0.4064)
		(layer "F.Cu")
		(net "GND")
	)
	(segment
		(start 361.315 -46.101)
		(end 361.315 -47.117)
		(width 0.508)
		(layer "F.Cu")
		(net "GND")
	)
	(segment
		(start 327.375012 -148.35505)
		(end 325.654924 -148.35505)
		(width 0.508)
		(layer "F.Cu")
		(net "GND")
	)
	(segment
		(start 358.925114 -128.03505)
		(end 357.205026 -128.03505)
		(width 0.508)
		(layer "F.Cu")
		(net "GND")
	)
	(segment
		(start 124.674884 -263.355074)
		(end 122.954796 -263.355074)
		(width 0.508)
		(layer "F.Cu")
		(net "GND")
	)
	(segment
		(start 420.200074 -7.035038)
		(end 422.082976 -7.035038)
		(width 0.508)
		(layer "F.Cu")
		(net "GND")
	)
	(segment
		(start 114.41176 -248.6152)
		(end 113.665 -248.6152)
		(width 0.4064)
		(layer "F.Cu")
		(net "GND")
	)
	(segment
		(start 224.281746 -225.116136)
		(end 224.300288 -225.097594)
		(width 0.508)
		(layer "F.Cu")
		(net "GND")
	)
	(segment
		(start 183.105044 -21.42998)
		(end 184.476644 -21.42998)
		(width 0.508)
		(layer "F.Cu")
		(net "GND")
	)
	(segment
		(start 144.907 -260.604)
		(end 144.907 -262.001)
		(width 0.508)
		(layer "F.Cu")
		(net "GND")
	)
	(segment
		(start 393.954 -268.605)
		(end 392.938 -268.605)
		(width 0.508)
		(layer "F.Cu")
		(net "GND")
	)
	(segment
		(start 124.674884 -16.845026)
		(end 122.954796 -16.845026)
		(width 0.508)
		(layer "F.Cu")
		(net "GND")
	)
	(segment
		(start 403.796246 -100.844604)
		(end 403.796246 -101.754178)
		(width 0.508)
		(layer "F.Cu")
		(net "GND")
	)
	(segment
		(start 250.645422 -226.35591)
		(end 250.628912 -226.3394)
		(width 0.4572)
		(layer "F.Cu")
		(net "GND")
	)
	(segment
		(start 485.125014 -268.435074)
		(end 483.404926 -268.435074)
		(width 0.508)
		(layer "F.Cu")
		(net "GND")
	)
	(segment
		(start 458.216 -128.2065)
		(end 458.216 -127.381)
		(width 0.508)
		(layer "F.Cu")
		(net "GND")
	)
	(segment
		(start 73.924668 -212.390228)
		(end 73.924668 -211.310728)
		(width 0.508)
		(layer "F.Cu")
		(net "GND")
	)
	(segment
		(start 417.35502 -26.230072)
		(end 419.161976 -26.230072)
		(width 0.508)
		(layer "F.Cu")
		(net "GND")
	)
	(segment
		(start 479.298 -276.225)
		(end 479.298 -277.241)
		(width 0.508)
		(layer "F.Cu")
		(net "GND")
	)
	(segment
		(start 319.89903 -97.350326)
		(end 319.89903 -96.270826)
		(width 0.508)
		(layer "F.Cu")
		(net "GND")
	)
	(segment
		(start 30.025086 -16.845026)
		(end 28.304998 -16.845026)
		(width 0.508)
		(layer "F.Cu")
		(net "GND")
	)
	(segment
		(start 458.47 -38.227)
		(end 459.434946 -38.227)
		(width 0.508)
		(layer "F.Cu")
		(net "GND")
	)
	(segment
		(start 457.2635 -250.4948)
		(end 456.6666 -250.4948)
		(width 0.508)
		(layer "F.Cu")
		(net "GND")
	)
	(segment
		(start 222.98025 -302.81245)
		(end 222.8596 -302.6918)
		(width 0.508)
		(layer "F.Cu")
		(net "GND")
	)
	(segment
		(start 35.299396 -363.0041)
		(end 33.688528 -363.0041)
		(width 0.508)
		(layer "F.Cu")
		(net "GND")
	)
	(segment
		(start 30.025086 -13.035026)
		(end 28.304998 -13.035026)
		(width 0.508)
		(layer "F.Cu")
		(net "GND")
	)
	(segment
		(start 124.674884 -145.81505)
		(end 122.954796 -145.81505)
		(width 0.508)
		(layer "F.Cu")
		(net "GND")
	)
	(segment
		(start 463.3468 -4.826)
		(end 463.6897 -4.826)
		(width 0.508)
		(layer "F.Cu")
		(net "GND")
	)
	(segment
		(start 221.2975 -225.425)
		(end 223.18091 -225.425)
		(width 0.508)
		(layer "F.Cu")
		(net "GND")
	)
	(segment
		(start 406.649428 -217.413586)
		(end 406.258014 -217.805)
		(width 0.508)
		(layer "F.Cu")
		(net "GND")
	)
	(segment
		(start 187.775088 -30.815026)
		(end 186.055 -30.815026)
		(width 0.508)
		(layer "F.Cu")
		(net "GND")
	)
	(segment
		(start 38.956996 -369.2525)
		(end 39.960296 -369.2525)
		(width 0.508)
		(layer "F.Cu")
		(net "GND")
	)
	(segment
		(start 86.995 -156.2608)
		(end 85.725 -156.2608)
		(width 0.508)
		(layer "F.Cu")
		(net "GND")
	)
	(segment
		(start 19.79676 -133.5532)
		(end 19.05 -133.5532)
		(width 0.4064)
		(layer "F.Cu")
		(net "GND")
	)
	(segment
		(start 259.490972 -372.77421)
		(end 259.490972 -373.54891)
		(width 0.508)
		(layer "F.Cu")
		(net "GND")
	)
	(segment
		(start 59.749944 -50.785014)
		(end 61.632846 -50.785014)
		(width 0.508)
		(layer "F.Cu")
		(net "GND")
	)
	(segment
		(start 390.474962 -148.35505)
		(end 388.754874 -148.35505)
		(width 0.508)
		(layer "F.Cu")
		(net "GND")
	)
	(segment
		(start 27.088338 -371.3988)
		(end 26.510996 -371.3988)
		(width 0.508)
		(layer "F.Cu")
		(net "GND")
	)
	(segment
		(start 405.569928 -101.813868)
		(end 405.56942 -101.814376)
		(width 0.508)
		(layer "F.Cu")
		(net "GND")
	)
	(segment
		(start 56.90489 -136.430004)
		(end 59.037982 -136.430004)
		(width 0.508)
		(layer "F.Cu")
		(net "GND")
	)
	(segment
		(start 93.125036 -155.97505)
		(end 91.404948 -155.97505)
		(width 0.508)
		(layer "F.Cu")
		(net "GND")
	)
	(segment
		(start 249.69978 -210.75396)
		(end 249.705876 -210.747864)
		(width 0.508)
		(layer "F.Cu")
		(net "GND")
	)
	(segment
		(start 149.6695 -134.493)
		(end 149.6695 -135.382)
		(width 0.508)
		(layer "F.Cu")
		(net "GND")
	)
	(segment
		(start 357.100124 -50.785014)
		(end 355.078538 -50.785014)
		(width 0.508)
		(layer "F.Cu")
		(net "GND")
	)
	(segment
		(start 82.91576 -248.6152)
		(end 82.169 -248.6152)
		(width 0.4064)
		(layer "F.Cu")
		(net "GND")
	)
	(segment
		(start 448.904868 -141.230096)
		(end 450.711824 -141.230096)
		(width 0.508)
		(layer "F.Cu")
		(net "GND")
	)
	(segment
		(start 211.6328 -189.20968)
		(end 213.2076 -189.20968)
		(width 0.3556)
		(layer "F.Cu")
		(net "GND")
	)
	(segment
		(start 260.73481 -224.340674)
		(end 260.73481 -223.89719)
		(width 0.508)
		(layer "F.Cu")
		(net "GND")
	)
	(segment
		(start 392.938 -39.680388)
		(end 392.938 -38.608)
		(width 0.508)
		(layer "F.Cu")
		(net "GND")
	)
	(segment
		(start 427.983904 -364.5535)
		(end 428.301404 -364.236)
		(width 0.508)
		(layer "F.Cu")
		(net "GND")
	)
	(segment
		(start 237.363 -222.5675)
		(end 237.1725 -222.377)
		(width 0.508)
		(layer "F.Cu")
		(net "GND")
	)
	(segment
		(start 479.034602 -271.344644)
		(end 477.668844 -271.344644)
		(width 0.508)
		(layer "F.Cu")
		(net "GND")
	)
	(segment
		(start 417.35502 -256.23012)
		(end 419.161976 -256.23012)
		(width 0.508)
		(layer "F.Cu")
		(net "GND")
	)
	(segment
		(start 472.2622 -247.53824)
		(end 472.2622 -248.285)
		(width 0.4064)
		(layer "F.Cu")
		(net "GND")
	)
	(segment
		(start 468.8078 -35.56)
		(end 467.614 -35.56)
		(width 0.508)
		(layer "F.Cu")
		(net "GND")
	)
	(segment
		(start 478.6884 -11.6205)
		(end 478.6884 -12.446)
		(width 0.508)
		(layer "F.Cu")
		(net "GND")
	)
	(segment
		(start 451.749922 -165.785038)
		(end 453.632824 -165.785038)
		(width 0.508)
		(layer "F.Cu")
		(net "GND")
	)
	(segment
		(start 362.6612 -16.90624)
		(end 362.6612 -17.653)
		(width 0.4064)
		(layer "F.Cu")
		(net "GND")
	)
	(segment
		(start 302.393096 -327.414382)
		(end 302.393096 -326.593962)
		(width 0.508)
		(layer "F.Cu")
		(net "GND")
	)
	(segment
		(start 29.177996 -375.0818)
		(end 29.177996 -375.031)
		(width 0.4064)
		(layer "F.Cu")
		(net "GND")
	)
	(segment
		(start 323.641212 -103.555038)
		(end 323.696584 -103.61041)
		(width 0.508)
		(layer "F.Cu")
		(net "GND")
	)
	(segment
		(start 425.7802 -246.90324)
		(end 425.7802 -247.65)
		(width 0.4064)
		(layer "F.Cu")
		(net "GND")
	)
	(segment
		(start 187.775088 -263.355074)
		(end 186.055 -263.355074)
		(width 0.508)
		(layer "F.Cu")
		(net "GND")
	)
	(segment
		(start 444.485268 -102.26802)
		(end 444.485268 -103.07828)
		(width 0.508)
		(layer "F.Cu")
		(net "GND")
	)
	(segment
		(start 243.205 -214.8205)
		(end 243.205 -213.9696)
		(width 0.508)
		(layer "F.Cu")
		(net "GND")
	)
	(segment
		(start 247.965468 -223.8375)
		(end 247.965468 -224.6884)
		(width 0.508)
		(layer "F.Cu")
		(net "GND")
	)
	(segment
		(start 147.992592 -216.810844)
		(end 147.992592 -215.90127)
		(width 0.508)
		(layer "F.Cu")
		(net "GND")
	)
	(segment
		(start 120.00484 -23.830026)
		(end 121.811796 -23.830026)
		(width 0.508)
		(layer "F.Cu")
		(net "GND")
	)
	(segment
		(start 405.569928 -100.709476)
		(end 405.569928 -101.813868)
		(width 0.508)
		(layer "F.Cu")
		(net "GND")
	)
	(segment
		(start 213.4108 -202.629262)
		(end 213.692486 -202.347576)
		(width 0.508)
		(layer "F.Cu")
		(net "GND")
	)
	(segment
		(start 176.403 -260.604)
		(end 176.403 -262.001)
		(width 0.508)
		(layer "F.Cu")
		(net "GND")
	)
	(segment
		(start 59.749944 -237.035086)
		(end 61.632846 -237.035086)
		(width 0.508)
		(layer "F.Cu")
		(net "GND")
	)
	(segment
		(start 332.105 -243.1415)
		(end 332.105 -242.316)
		(width 0.508)
		(layer "F.Cu")
		(net "GND")
	)
	(segment
		(start 114.0206 -263.779)
		(end 113.0554 -263.779)
		(width 0.508)
		(layer "F.Cu")
		(net "GND")
	)
	(segment
		(start 459.1558 -130.66776)
		(end 459.1558 -129.921)
		(width 0.4064)
		(layer "F.Cu")
		(net "GND")
	)
	(segment
		(start 458.47 -268.224)
		(end 459.867 -268.224)
		(width 0.508)
		(layer "F.Cu")
		(net "GND")
	)
	(segment
		(start 318.356996 -371.6401)
		(end 318.356996 -370.6622)
		(width 0.508)
		(layer "F.Cu")
		(net "GND")
	)
	(segment
		(start 61.574934 -243.035074)
		(end 63.457074 -243.035074)
		(width 0.508)
		(layer "F.Cu")
		(net "GND")
	)
	(segment
		(start 67.247008 -147.065492)
		(end 68.119498 -147.065492)
		(width 0.508)
		(layer "F.Cu")
		(net "GND")
	)
	(segment
		(start 115.71224 -135.4328)
		(end 116.6368 -135.4328)
		(width 0.4064)
		(layer "F.Cu")
		(net "GND")
	)
	(segment
		(start 390.474962 -155.97505)
		(end 388.754874 -155.97505)
		(width 0.508)
		(layer "F.Cu")
		(net "GND")
	)
	(segment
		(start 241.878104 -308.737)
		(end 240.867692 -308.737)
		(width 0.2032)
		(layer "F.Cu")
		(net "GND")
	)
	(segment
		(start 260.790436 -353.474528)
		(end 260.26745 -353.474528)
		(width 0.508)
		(layer "F.Cu")
		(net "GND")
	)
	(segment
		(start 207.88884 -234.73918)
		(end 207.88884 -233.682794)
		(width 0.508)
		(layer "F.Cu")
		(net "GND")
	)
	(segment
		(start 142.5575 -139.065)
		(end 142.5575 -139.954)
		(width 0.508)
		(layer "F.Cu")
		(net "GND")
	)
	(segment
		(start 435.346094 -216.754202)
		(end 435.35092 -216.759028)
		(width 0.508)
		(layer "F.Cu")
		(net "GND")
	)
	(segment
		(start 331.1652 -131.96824)
		(end 331.1652 -132.715)
		(width 0.4064)
		(layer "F.Cu")
		(net "GND")
	)
	(segment
		(start 236.982 -192.86728)
		(end 236.982 -191.184784)
		(width 0.508)
		(layer "F.Cu")
		(net "GND")
	)
	(segment
		(start 300.709076 -341.257382)
		(end 300.709076 -342.077802)
		(width 0.508)
		(layer "F.Cu")
		(net "GND")
	)
	(segment
		(start 424.434 -48.420528)
		(end 424.434762 -48.42129)
		(width 0.508)
		(layer "F.Cu")
		(net "GND")
	)
	(segment
		(start 56.90489 -138.83005)
		(end 58.711846 -138.83005)
		(width 0.508)
		(layer "F.Cu")
		(net "GND")
	)
	(segment
		(start 87.376 -161.163)
		(end 87.376 -162.179)
		(width 0.508)
		(layer "F.Cu")
		(net "GND")
	)
	(segment
		(start 390.474962 -135.65505)
		(end 388.754874 -135.65505)
		(width 0.508)
		(layer "F.Cu")
		(net "GND")
	)
	(segment
		(start 375.099326 -216.497154)
		(end 375.099326 -217.413586)
		(width 0.508)
		(layer "F.Cu")
		(net "GND")
	)
	(segment
		(start 13.7668 -150.622)
		(end 12.573 -150.622)
		(width 0.508)
		(layer "F.Cu")
		(net "GND")
	)
	(segment
		(start 372.246144 -216.754202)
		(end 372.25097 -216.759028)
		(width 0.508)
		(layer "F.Cu")
		(net "GND")
	)
	(segment
		(start 158.236158 -148.35505)
		(end 158.24327 -148.347938)
		(width 0.4572)
		(layer "F.Cu")
		(net "GND")
	)
	(segment
		(start 282.984448 -347.096842)
		(end 282.984448 -346.271342)
		(width 0.508)
		(layer "F.Cu")
		(net "GND")
	)
	(segment
		(start 183.1594 -374.8532)
		(end 183.4388 -375.1326)
		(width 0.508)
		(layer "F.Cu")
		(net "GND")
	)
	(segment
		(start 30.082236 -368.36096)
		(end 30.803596 -367.6396)
		(width 0.4064)
		(layer "F.Cu")
		(net "GND")
	)
	(segment
		(start 167.549068 -215.768428)
		(end 167.549068 -216.678002)
		(width 0.508)
		(layer "F.Cu")
		(net "GND")
	)
	(segment
		(start 151.554942 -138.83005)
		(end 153.361898 -138.83005)
		(width 0.508)
		(layer "F.Cu")
		(net "GND")
	)
	(segment
		(start 139.75715 -101.8286)
		(end 139.75715 -100.7237)
		(width 0.508)
		(layer "F.Cu")
		(net "GND")
	)
	(segment
		(start 392.938 -46.101)
		(end 392.938 -47.117)
		(width 0.508)
		(layer "F.Cu")
		(net "GND")
	)
	(segment
		(start 59.749944 -165.785038)
		(end 61.632846 -165.785038)
		(width 0.508)
		(layer "F.Cu")
		(net "GND")
	)
	(segment
		(start 282.524962 -157.097222)
		(end 282.523692 -157.098492)
		(width 0.508)
		(layer "F.Cu")
		(net "GND")
	)
	(segment
		(start 93.125036 -128.03505)
		(end 91.404948 -128.03505)
		(width 0.508)
		(layer "F.Cu")
		(net "GND")
	)
	(segment
		(start 223.489774 -225.116136)
		(end 224.281746 -225.116136)
		(width 0.508)
		(layer "F.Cu")
		(net "GND")
	)
	(segment
		(start 236.5375 -194.01028)
		(end 237.551214 -194.01028)
		(width 0.508)
		(layer "F.Cu")
		(net "GND")
	)
	(segment
		(start 473.202 -128.8415)
		(end 474.091 -128.8415)
		(width 0.508)
		(layer "F.Cu")
		(net "GND")
	)
	(segment
		(start 324.621144 -23.830026)
		(end 324.621652 -23.830534)
		(width 0.4572)
		(layer "F.Cu")
		(net "GND")
	)
	(segment
		(start 422.025064 -40.975026)
		(end 420.304976 -40.975026)
		(width 0.508)
		(layer "F.Cu")
		(net "GND")
	)
	(segment
		(start 422.025064 -155.97505)
		(end 420.304976 -155.97505)
		(width 0.508)
		(layer "F.Cu")
		(net "GND")
	)
	(segment
		(start 187.775088 -268.435074)
		(end 186.055 -268.435074)
		(width 0.508)
		(layer "F.Cu")
		(net "GND")
	)
	(segment
		(start 124.674884 -260.815074)
		(end 122.954796 -260.815074)
		(width 0.508)
		(layer "F.Cu")
		(net "GND")
	)
	(segment
		(start 358.925114 -155.97505)
		(end 357.205026 -155.97505)
		(width 0.508)
		(layer "F.Cu")
		(net "GND")
	)
	(segment
		(start 84.21624 -20.4978)
		(end 85.1408 -20.4978)
		(width 0.4064)
		(layer "F.Cu")
		(net "GND")
	)
	(segment
		(start 48.623728 -118.143274)
		(end 48.623728 -117.166898)
		(width 0.508)
		(layer "F.Cu")
		(net "GND")
	)
	(segment
		(start 485.125014 -33.355026)
		(end 483.404926 -33.355026)
		(width 0.508)
		(layer "F.Cu")
		(net "GND")
	)
	(segment
		(start 123.2789 -135.65505)
		(end 122.812302 -136.121648)
		(width 0.508)
		(layer "F.Cu")
		(net "GND")
	)
	(segment
		(start 158.496 -31.1785)
		(end 158.496 -30.3276)
		(width 0.508)
		(layer "F.Cu")
		(net "GND")
	)
	(segment
		(start 222.18396 -166.41826)
		(end 223.19996 -166.41826)
		(width 0.508)
		(layer "F.Cu")
		(net "GND")
	)
	(segment
		(start 187.775088 -33.355026)
		(end 186.055 -33.355026)
		(width 0.508)
		(layer "F.Cu")
		(net "GND")
	)
	(segment
		(start 144.907 -30.607)
		(end 144.907 -32.004)
		(width 0.508)
		(layer "F.Cu")
		(net "GND")
	)
	(segment
		(start 384.8608 -146.1897)
		(end 384.8608 -145.3388)
		(width 0.508)
		(layer "F.Cu")
		(net "GND")
	)
	(segment
		(start 322.704968 -23.830026)
		(end 324.621144 -23.830026)
		(width 0.4572)
		(layer "F.Cu")
		(net "GND")
	)
	(segment
		(start 260.26745 -353.474528)
		(end 259.795772 -353.946206)
		(width 0.508)
		(layer "F.Cu")
		(net "GND")
	)
	(segment
		(start 211.95538 -238.93272)
		(end 211.95538 -239.88522)
		(width 0.508)
		(layer "F.Cu")
		(net "GND")
	)
	(segment
		(start 124.674884 -38.435026)
		(end 122.954796 -38.435026)
		(width 0.508)
		(layer "F.Cu")
		(net "GND")
	)
	(segment
		(start 403.796246 -101.754178)
		(end 403.801072 -101.759004)
		(width 0.508)
		(layer "F.Cu")
		(net "GND")
	)
	(segment
		(start 448.904868 -138.83005)
		(end 450.711824 -138.83005)
		(width 0.508)
		(layer "F.Cu")
		(net "GND")
	)
	(segment
		(start 333.502 -275.9202)
		(end 333.502 -277.114)
		(width 0.508)
		(layer "F.Cu")
		(net "GND")
	)
	(segment
		(start 156.224986 -263.355074)
		(end 154.504898 -263.355074)
		(width 0.508)
		(layer "F.Cu")
		(net "GND")
	)
	(segment
		(start 45.89145 -217.337386)
		(end 45.89145 -216.55405)
		(width 0.508)
		(layer "F.Cu")
		(net "GND")
	)
	(segment
		(start 40.8305 -5.2705)
		(end 40.1066 -4.5466)
		(width 0.508)
		(layer "F.Cu")
		(net "GND")
	)
	(segment
		(start 305.408076 -327.414382)
		(end 305.408076 -326.593962)
		(width 0.508)
		(layer "F.Cu")
		(net "GND")
	)
	(segment
		(start 61.574934 -145.81505)
		(end 59.854846 -145.81505)
		(width 0.508)
		(layer "F.Cu")
		(net "GND")
	)
	(segment
		(start 218.33586 -172.962316)
		(end 218.354656 -172.981112)
		(width 0.3556)
		(layer "F.Cu")
		(net "GND")
	)
	(segment
		(start 61.574934 -131.84505)
		(end 59.854846 -131.84505)
		(width 0.508)
		(layer "F.Cu")
		(net "GND")
	)
	(segment
		(start 156.224986 -38.435026)
		(end 154.504898 -38.435026)
		(width 0.508)
		(layer "F.Cu")
		(net "GND")
	)
	(segment
		(start 124.674884 -155.97505)
		(end 122.954796 -155.97505)
		(width 0.508)
		(layer "F.Cu")
		(net "GND")
	)
	(segment
		(start 93.125036 -13.035026)
		(end 91.404948 -13.035026)
		(width 0.508)
		(layer "F.Cu")
		(net "GND")
	)
	(segment
		(start 146.03476 -18.6182)
		(end 145.288 -18.6182)
		(width 0.4064)
		(layer "F.Cu")
		(net "GND")
	)
	(segment
		(start 251.497338 -227.34651)
		(end 251.497338 -226.362768)
		(width 0.4572)
		(layer "F.Cu")
		(net "GND")
	)
	(segment
		(start 387.815836 -40.975026)
		(end 387.813042 -40.972232)
		(width 0.508)
		(layer "F.Cu")
		(net "GND")
	)
	(segment
		(start 358.925114 -246.845074)
		(end 357.205026 -246.845074)
		(width 0.508)
		(layer "F.Cu")
		(net "GND")
	)
	(segment
		(start 331.47 -160.9852)
		(end 331.47 -162.179)
		(width 0.508)
		(layer "F.Cu")
		(net "GND")
	)
	(segment
		(start 384.9116 -31.2039)
		(end 384.9116 -30.3276)
		(width 0.508)
		(layer "F.Cu")
		(net "GND")
	)
	(segment
		(start 430.466754 -363.0295)
		(end 430.466754 -364.236)
		(width 0.508)
		(layer "F.Cu")
		(net "GND")
	)
	(segment
		(start 483.300024 -50.785014)
		(end 485.182926 -50.785014)
		(width 0.508)
		(layer "F.Cu")
		(net "GND")
	)
	(segment
		(start 118.618 -156.2608)
		(end 118.618 -155.144216)
		(width 0.508)
		(layer "F.Cu")
		(net "GND")
	)
	(segment
		(start 232.55732 -218.59748)
		(end 232.55732 -217.78468)
		(width 0.508)
		(layer "F.Cu")
		(net "GND")
	)
	(segment
		(start 161.9885 -147.066)
		(end 161.9885 -146.177)
		(width 0.508)
		(layer "F.Cu")
		(net "GND")
	)
	(segment
		(start 114.41176 -133.5532)
		(end 114.061494 -133.5532)
		(width 0.4064)
		(layer "F.Cu")
		(net "GND")
	)
	(segment
		(start 394.589 -275.9202)
		(end 394.589 -277.114)
		(width 0.508)
		(layer "F.Cu")
		(net "GND")
	)
	(segment
		(start 392.938 -276.098)
		(end 392.938 -277.114)
		(width 0.508)
		(layer "F.Cu")
		(net "GND")
	)
	(segment
		(start 91.35872 -30.815026)
		(end 90.806524 -31.367222)
		(width 0.508)
		(layer "F.Cu")
		(net "GND")
	)
	(segment
		(start 358.925114 -268.435074)
		(end 357.205026 -268.435074)
		(width 0.508)
		(layer "F.Cu")
		(net "GND")
	)
	(segment
		(start 51.0286 -263.779)
		(end 50.1142 -263.779)
		(width 0.508)
		(layer "F.Cu")
		(net "GND")
	)
	(segment
		(start 21.09724 -20.4978)
		(end 22.0218 -20.4978)
		(width 0.4064)
		(layer "F.Cu")
		(net "GND")
	)
	(segment
		(start 309.146194 -215.844628)
		(end 309.146194 -214.935816)
		(width 0.508)
		(layer "F.Cu")
		(net "GND")
	)
	(segment
		(start 327.375012 -128.03505)
		(end 325.654924 -128.03505)
		(width 0.508)
		(layer "F.Cu")
		(net "GND")
	)
	(segment
		(start 61.574934 -148.35505)
		(end 59.854846 -148.35505)
		(width 0.508)
		(layer "F.Cu")
		(net "GND")
	)
	(segment
		(start 374.019826 -100.709476)
		(end 374.019826 -101.813868)
		(width 0.508)
		(layer "F.Cu")
		(net "GND")
	)
	(segment
		(start 422.025064 -263.355074)
		(end 420.304976 -263.355074)
		(width 0.508)
		(layer "F.Cu")
		(net "GND")
	)
	(segment
		(start 424.021504 -368.935)
		(end 424.847004 -368.935)
		(width 0.508)
		(layer "F.Cu")
		(net "GND")
	)
	(segment
		(start 330.294996 -369.2525)
		(end 331.183996 -369.2525)
		(width 0.508)
		(layer "F.Cu")
		(net "GND")
	)
	(segment
		(start 55.499 -41.3258)
		(end 54.229 -41.3258)
		(width 0.508)
		(layer "F.Cu")
		(net "GND")
	)
	(segment
		(start 120.00484 -141.230096)
		(end 121.811796 -141.230096)
		(width 0.508)
		(layer "F.Cu")
		(net "GND")
	)
	(segment
		(start 154.399996 -237.035086)
		(end 156.282898 -237.035086)
		(width 0.508)
		(layer "F.Cu")
		(net "GND")
	)
	(segment
		(start 114.061494 -133.5532)
		(end 113.536222 -134.078472)
		(width 0.4064)
		(layer "F.Cu")
		(net "GND")
	)
	(segment
		(start 428.117 -45.9232)
		(end 428.117 -47.117)
		(width 0.508)
		(layer "F.Cu")
		(net "GND")
	)
	(segment
		(start 477.4311 -135.7884)
		(end 478.3328 -135.7884)
		(width 0.508)
		(layer "F.Cu")
		(net "GND")
	)
	(segment
		(start 362.966 -45.9232)
		(end 362.966 -47.117)
		(width 0.508)
		(layer "F.Cu")
		(net "GND")
	)
	(segment
		(start 16.3195 -24.13)
		(end 16.3195 -25.019)
		(width 0.508)
		(layer "F.Cu")
		(net "GND")
	)
	(segment
		(start 261.277862 -216.859358)
		(end 261.013194 -217.124026)
		(width 0.508)
		(layer "F.Cu")
		(net "GND")
	)
	(segment
		(start 74.813668 -100.858828)
		(end 74.813668 -101.768402)
		(width 0.508)
		(layer "F.Cu")
		(net "GND")
	)
	(segment
		(start 42.544746 -363.0295)
		(end 42.214546 -362.6993)
		(width 0.508)
		(layer "F.Cu")
		(net "GND")
	)
	(segment
		(start 451.749922 -7.035038)
		(end 453.632824 -7.035038)
		(width 0.508)
		(layer "F.Cu")
		(net "GND")
	)
	(segment
		(start 239.776 -214.8205)
		(end 239.776 -213.9696)
		(width 0.508)
		(layer "F.Cu")
		(net "GND")
	)
	(segment
		(start 61.574934 -246.845074)
		(end 59.854846 -246.845074)
		(width 0.508)
		(layer "F.Cu")
		(net "GND")
	)
	(segment
		(start 459.38567 -229.328218)
		(end 459.38567 -228.351842)
		(width 0.508)
		(layer "F.Cu")
		(net "GND")
	)
	(segment
		(start 459.616302 -229.55885)
		(end 459.552802 -229.49535)
		(width 0.508)
		(layer "F.Cu")
		(net "GND")
	)
	(segment
		(start 30.025086 -20.655026)
		(end 28.304998 -20.655026)
		(width 0.508)
		(layer "F.Cu")
		(net "GND")
	)
	(segment
		(start 322.561712 -100.669598)
		(end 322.561712 -101.77399)
		(width 0.508)
		(layer "F.Cu")
		(net "GND")
	)
	(segment
		(start 323.592444 -165.785038)
		(end 323.590666 -165.78326)
		(width 0.508)
		(layer "F.Cu")
		(net "GND")
	)
	(segment
		(start 422.025064 -33.355026)
		(end 420.737284 -33.355026)
		(width 0.508)
		(layer "F.Cu")
		(net "GND")
	)
	(segment
		(start 221.615 -226.568)
		(end 222.526606 -226.568)
		(width 0.508)
		(layer "F.Cu")
		(net "GND")
	)
	(segment
		(start 133.3373 -367.3221)
		(end 133.3373 -367.8174)
		(width 0.508)
		(layer "F.Cu")
		(net "GND")
	)
	(segment
		(start 362.6612 -131.96824)
		(end 362.6612 -132.715)
		(width 0.4064)
		(layer "F.Cu")
		(net "GND")
	)
	(segment
		(start 124.674884 -250.655074)
		(end 122.954796 -250.655074)
		(width 0.508)
		(layer "F.Cu")
		(net "GND")
	)
	(segment
		(start 61.574934 -128.03505)
		(end 59.854846 -128.03505)
		(width 0.508)
		(layer "F.Cu")
		(net "GND")
	)
	(segment
		(start 485.125014 -270.975074)
		(end 483.404926 -270.975074)
		(width 0.508)
		(layer "F.Cu")
		(net "GND")
	)
	(segment
		(start 158.158434 -155.97505)
		(end 158.162498 -155.979114)
		(width 0.4572)
		(layer "F.Cu")
		(net "GND")
	)
	(segment
		(start 327.375012 -38.435026)
		(end 325.654924 -38.435026)
		(width 0.508)
		(layer "F.Cu")
		(net "GND")
	)
	(segment
		(start 76.58735 -216.8144)
		(end 76.58735 -215.7095)
		(width 0.508)
		(layer "F.Cu")
		(net "GND")
	)
	(segment
		(start 99.9744 -358.0892)
		(end 100.4316 -357.632)
		(width 0.508)
		(layer "F.Cu")
		(net "GND")
	)
	(segment
		(start 253.259082 -227.572062)
		(end 253.259082 -227.56749)
		(width 0.4572)
		(layer "F.Cu")
		(net "GND")
	)
	(segment
		(start 283.41955 -157.097222)
		(end 282.524962 -157.097222)
		(width 0.508)
		(layer "F.Cu")
		(net "GND")
	)
	(segment
		(start 218.8464 -197.8914)
		(end 217.50274 -197.8914)
		(width 0.508)
		(layer "F.Cu")
		(net "GND")
	)
	(segment
		(start 329.692 -162.1282)
		(end 329.692 -161.29)
		(width 0.508)
		(layer "F.Cu")
		(net "GND")
	)
	(segment
		(start 74.813668 -215.844628)
		(end 74.813668 -216.754202)
		(width 0.508)
		(layer "F.Cu")
		(net "GND")
	)
	(segment
		(start 239.649 -312.3565)
		(end 239.649 -313.182)
		(width 0.508)
		(layer "F.Cu")
		(net "GND")
	)
	(segment
		(start 150.88997 -216.562686)
		(end 150.88997 -217.642186)
		(width 0.508)
		(layer "F.Cu")
		(net "GND")
	)
	(segment
		(start 108.21035 -101.7778)
		(end 108.21035 -100.6729)
		(width 0.508)
		(layer "F.Cu")
		(net "GND")
	)
	(segment
		(start 422.025064 -16.845026)
		(end 420.304976 -16.845026)
		(width 0.508)
		(layer "F.Cu")
		(net "GND")
	)
	(segment
		(start 122.849894 -235.121704)
		(end 122.821446 -235.093256)
		(width 0.508)
		(layer "F.Cu")
		(net "GND")
	)
	(segment
		(start 329.819 -46.101)
		(end 329.819 -47.117)
		(width 0.508)
		(layer "F.Cu")
		(net "GND")
	)
	(segment
		(start 390.525 -166.624)
		(end 390.525 -166.243)
		(width 0.508)
		(layer "F.Cu")
		(net "GND")
	)
	(segment
		(start 183.105044 -26.230072)
		(end 184.912 -26.230072)
		(width 0.508)
		(layer "F.Cu")
		(net "GND")
	)
	(segment
		(start 124.674884 -13.035026)
		(end 122.954796 -13.035026)
		(width 0.508)
		(layer "F.Cu")
		(net "GND")
	)
	(segment
		(start 354.25507 -141.230096)
		(end 356.062026 -141.230096)
		(width 0.508)
		(layer "F.Cu")
		(net "GND")
	)
	(segment
		(start 466.896196 -216.754202)
		(end 466.901022 -216.759028)
		(width 0.508)
		(layer "F.Cu")
		(net "GND")
	)
	(segment
		(start 385.804918 -136.430004)
		(end 387.611874 -136.430004)
		(width 0.508)
		(layer "F.Cu")
		(net "GND")
	)
	(segment
		(start 183.105044 -251.430028)
		(end 184.912 -251.430028)
		(width 0.508)
		(layer "F.Cu")
		(net "GND")
	)
	(segment
		(start 354.25507 -23.830026)
		(end 356.062026 -23.830026)
		(width 0.508)
		(layer "F.Cu")
		(net "GND")
	)
	(segment
		(start 255.934972 -374.05691)
		(end 255.934972 -375.25071)
		(width 0.508)
		(layer "F.Cu")
		(net "GND")
	)
	(segment
		(start 122.849894 -7.035038)
		(end 124.732796 -7.035038)
		(width 0.508)
		(layer "F.Cu")
		(net "GND")
	)
	(segment
		(start 156.224986 -268.435074)
		(end 154.504898 -268.435074)
		(width 0.508)
		(layer "F.Cu")
		(net "GND")
	)
	(segment
		(start 93.125036 -263.355074)
		(end 91.404948 -263.355074)
		(width 0.508)
		(layer "F.Cu")
		(net "GND")
	)
	(segment
		(start 187.775088 -13.035026)
		(end 186.055 -13.035026)
		(width 0.508)
		(layer "F.Cu")
		(net "GND")
	)
	(segment
		(start 250.022614 -143.207994)
		(end 251.038614 -143.207994)
		(width 0.508)
		(layer "F.Cu")
		(net "GND")
	)
	(segment
		(start 118.618 -155.144216)
		(end 118.625366 -155.13685)
		(width 0.508)
		(layer "F.Cu")
		(net "GND")
	)
	(segment
		(start 249.705876 -210.747864)
		(end 250.563634 -210.747864)
		(width 0.508)
		(layer "F.Cu")
		(net "GND")
	)
	(segment
		(start 187.775088 -250.655074)
		(end 186.055 -250.655074)
		(width 0.508)
		(layer "F.Cu")
		(net "GND")
	)
	(segment
		(start 106.436668 -101.692202)
		(end 106.441494 -101.697028)
		(width 0.508)
		(layer "F.Cu")
		(net "GND")
	)
	(segment
		(start 282.197048 -356.304342)
		(end 282.070048 -356.431342)
		(width 0.508)
		(layer "F.Cu")
		(net "GND")
	)
	(segment
		(start 91.300046 -280.785062)
		(end 93.182948 -280.785062)
		(width 0.508)
		(layer "F.Cu")
		(net "GND")
	)
	(segment
		(start 174.010066 -371.6655)
		(end 174.010066 -372.828566)
		(width 0.3048)
		(layer "F.Cu")
		(net "GND")
	)
	(segment
		(start 93.125036 -131.84505)
		(end 91.404948 -131.84505)
		(width 0.508)
		(layer "F.Cu")
		(net "GND")
	)
	(segment
		(start 93.125036 -246.845074)
		(end 91.404948 -246.845074)
		(width 0.508)
		(layer "F.Cu")
		(net "GND")
	)
	(segment
		(start 181.1655 -134.493)
		(end 181.1655 -135.382)
		(width 0.508)
		(layer "F.Cu")
		(net "GND")
	)
	(segment
		(start 331.3049 -250.4948)
		(end 330.5048 -250.4948)
		(width 0.508)
		(layer "F.Cu")
		(net "GND")
	)
	(segment
		(start 323.641212 -102.373684)
		(end 323.641212 -103.555038)
		(width 0.508)
		(layer "F.Cu")
		(net "GND")
	)
	(segment
		(start 422.025064 -38.435026)
		(end 420.304976 -38.435026)
		(width 0.508)
		(layer "F.Cu")
		(net "GND")
	)
	(segment
		(start 185.950098 -237.035086)
		(end 187.833 -237.035086)
		(width 0.508)
		(layer "F.Cu")
		(net "GND")
	)
	(segment
		(start 23.876 -271.3228)
		(end 22.606 -271.3228)
		(width 0.508)
		(layer "F.Cu")
		(net "GND")
	)
	(segment
		(start 84.21624 -250.4948)
		(end 85.1408 -250.4948)
		(width 0.4064)
		(layer "F.Cu")
		(net "GND")
	)
	(segment
		(start 14.64945 -216.308686)
		(end 14.64945 -217.413586)
		(width 0.508)
		(layer "F.Cu")
		(net "GND")
	)
	(segment
		(start 27.101038 -371.3861)
		(end 27.088338 -371.3988)
		(width 0.508)
		(layer "F.Cu")
		(net "GND")
	)
	(segment
		(start 185.039 -369.189)
		(end 185.547 -368.681)
		(width 0.508)
		(layer "F.Cu")
		(net "GND")
	)
	(segment
		(start 91.300046 -122.035062)
		(end 93.182948 -122.035062)
		(width 0.508)
		(layer "F.Cu")
		(net "GND")
	)
	(segment
		(start 44.81195 -216.8398)
		(end 44.81195 -215.7095)
		(width 0.508)
		(layer "F.Cu")
		(net "GND")
	)
	(segment
		(start 111.975646 -29.2989)
		(end 111.975646 -28.358592)
		(width 0.508)
		(layer "F.Cu")
		(net "GND")
	)
	(segment
		(start 357.100124 -280.785062)
		(end 358.983026 -280.785062)
		(width 0.508)
		(layer "F.Cu")
		(net "GND")
	)
	(segment
		(start 120.00484 -138.83005)
		(end 121.811796 -138.83005)
		(width 0.508)
		(layer "F.Cu")
		(net "GND")
	)
	(segment
		(start 332.359 -38.227)
		(end 333.756 -38.227)
		(width 0.508)
		(layer "F.Cu")
		(net "GND")
	)
	(segment
		(start 76.8858 -265.684)
		(end 75.692 -265.684)
		(width 0.508)
		(layer "F.Cu")
		(net "GND")
	)
	(segment
		(start 329.692 -161.29)
		(end 329.819 -161.163)
		(width 0.508)
		(layer "F.Cu")
		(net "GND")
	)
	(segment
		(start 208.9785 -208.026)
		(end 207.82661 -208.026)
		(width 0.508)
		(layer "F.Cu")
		(net "GND")
	)
	(segment
		(start 28.200096 -280.785062)
		(end 30.082998 -280.785062)
		(width 0.508)
		(layer "F.Cu")
		(net "GND")
	)
	(segment
		(start 448.904868 -251.430028)
		(end 450.711824 -251.430028)
		(width 0.508)
		(layer "F.Cu")
		(net "GND")
	)
	(segment
		(start 388.649972 -122.035062)
		(end 390.532874 -122.035062)
		(width 0.508)
		(layer "F.Cu")
		(net "GND")
	)
	(segment
		(start 147.33524 -250.4948)
		(end 148.2598 -250.4948)
		(width 0.4064)
		(layer "F.Cu")
		(net "GND")
	)
	(segment
		(start 82.91576 -18.6182)
		(end 82.169 -18.6182)
		(width 0.4064)
		(layer "F.Cu")
		(net "GND")
	)
	(segment
		(start 30.025086 -148.35505)
		(end 28.304998 -148.35505)
		(width 0.508)
		(layer "F.Cu")
		(net "GND")
	)
	(segment
		(start 333.502 -160.9852)
		(end 333.502 -163.347654)
		(width 0.508)
		(layer "F.Cu")
		(net "GND")
	)
	(segment
		(start 23.876 -41.3258)
		(end 22.606 -41.3258)
		(width 0.508)
		(layer "F.Cu")
		(net "GND")
	)
	(segment
		(start 187.775088 -131.84505)
		(end 186.055 -131.84505)
		(width 0.508)
		(layer "F.Cu")
		(net "GND")
	)
	(segment
		(start 86.5505 -249.555)
		(end 86.5505 -250.444)
		(width 0.508)
		(layer "F.Cu")
		(net "GND")
	)
	(segment
		(start 248.7295 -309.118)
		(end 249.555 -309.118)
		(width 0.508)
		(layer "F.Cu")
		(net "GND")
	)
	(segment
		(start 25.355042 -141.230096)
		(end 27.161998 -141.230096)
		(width 0.508)
		(layer "F.Cu")
		(net "GND")
	)
	(segment
		(start 91.300046 -50.785014)
		(end 93.182948 -50.785014)
		(width 0.508)
		(layer "F.Cu")
		(net "GND")
	)
	(segment
		(start 156.224986 -250.655074)
		(end 154.504898 -250.655074)
		(width 0.508)
		(layer "F.Cu")
		(net "GND")
	)
	(segment
		(start 260.931152 -373.860314)
		(end 260.931152 -372.730014)
		(width 0.508)
		(layer "F.Cu")
		(net "GND")
	)
	(segment
		(start 448.904868 -21.42998)
		(end 450.711824 -21.42998)
		(width 0.508)
		(layer "F.Cu")
		(net "GND")
	)
	(segment
		(start 390.474962 -250.655074)
		(end 388.754874 -250.655074)
		(width 0.508)
		(layer "F.Cu")
		(net "GND")
	)
	(segment
		(start 130.3655 -262.128)
		(end 130.3655 -261.239)
		(width 0.508)
		(layer "F.Cu")
		(net "GND")
	)
	(segment
		(start 190.9445 -32.131)
		(end 190.9445 -31.321502)
		(width 0.508)
		(layer "F.Cu")
		(net "GND")
	)
	(segment
		(start 258.319778 -235.17225)
		(end 257.07975 -235.17225)
		(width 0.508)
		(layer "F.Cu")
		(net "GND")
	)
	(segment
		(start 426.974 -268.224)
		(end 428.371 -268.224)
		(width 0.508)
		(layer "F.Cu")
		(net "GND")
	)
	(segment
		(start 55.88 -276.225)
		(end 55.88 -277.241)
		(width 0.508)
		(layer "F.Cu")
		(net "GND")
	)
	(segment
		(start 238.506 -227.7745)
		(end 238.506 -227.076)
		(width 0.508)
		(layer "F.Cu")
		(net "GND")
	)
	(segment
		(start 457.617068 -97.480628)
		(end 457.617068 -96.401128)
		(width 0.508)
		(layer "F.Cu")
		(net "GND")
	)
	(segment
		(start 76.8858 -35.687)
		(end 75.692 -35.687)
		(width 0.508)
		(layer "F.Cu")
		(net "GND")
	)
	(segment
		(start 30.025086 -135.65505)
		(end 28.304998 -135.65505)
		(width 0.508)
		(layer "F.Cu")
		(net "GND")
	)
	(segment
		(start 364.5408 -15.60576)
		(end 364.5408 -14.859)
		(width 0.4064)
		(layer "F.Cu")
		(net "GND")
	)
	(segment
		(start 330.5937 -16.2306)
		(end 330.5937 -15.956534)
		(width 0.508)
		(layer "F.Cu")
		(net "GND")
	)
	(segment
		(start 51.83505 -102.351586)
		(end 51.83505 -101.246686)
		(width 0.508)
		(layer "F.Cu")
		(net "GND")
	)
	(segment
		(start 468.8078 -150.622)
		(end 467.614 -150.622)
		(width 0.508)
		(layer "F.Cu")
		(net "GND")
	)
	(segment
		(start 11.796268 -216.754202)
		(end 11.801094 -216.759028)
		(width 0.508)
		(layer "F.Cu")
		(net "GND")
	)
	(segment
		(start 388.649972 -50.785014)
		(end 388.452614 -50.785014)
		(width 0.508)
		(layer "F.Cu")
		(net "GND")
	)
	(segment
		(start 74.813668 -101.768402)
		(end 74.818494 -101.773228)
		(width 0.508)
		(layer "F.Cu")
		(net "GND")
	)
	(segment
		(start 327.375012 -263.355074)
		(end 325.654924 -263.355074)
		(width 0.508)
		(layer "F.Cu")
		(net "GND")
	)
	(segment
		(start 474.0275 -20.828)
		(end 475.3356 -20.828)
		(width 0.508)
		(layer "F.Cu")
		(net "GND")
	)
	(segment
		(start 61.574934 -260.815074)
		(end 59.854846 -260.815074)
		(width 0.508)
		(layer "F.Cu")
		(net "GND")
	)
	(segment
		(start 358.925114 -40.975026)
		(end 357.205026 -40.975026)
		(width 0.508)
		(layer "F.Cu")
		(net "GND")
	)
	(segment
		(start 453.574912 -155.97505)
		(end 451.854824 -155.97505)
		(width 0.508)
		(layer "F.Cu")
		(net "GND")
	)
	(segment
		(start 124.674884 -30.815026)
		(end 122.954796 -30.815026)
		(width 0.508)
		(layer "F.Cu")
		(net "GND")
	)
	(segment
		(start 115.316 -20.4851)
		(end 115.316 -21.2852)
		(width 0.508)
		(layer "F.Cu")
		(net "GND")
	)
	(segment
		(start 479.044 -41.1988)
		(end 477.774 -41.1988)
		(width 0.508)
		(layer "F.Cu")
		(net "GND")
	)
	(segment
		(start 29.177996 -375.031)
		(end 28.685236 -374.53824)
		(width 0.4064)
		(layer "F.Cu")
		(net "GND")
	)
	(segment
		(start 321.242436 -369.75796)
		(end 321.709796 -369.2906)
		(width 0.4064)
		(layer "F.Cu")
		(net "GND")
	)
	(segment
		(start 174.0535 -254.127)
		(end 174.0535 -255.016)
		(width 0.508)
		(layer "F.Cu")
		(net "GND")
	)
	(segment
		(start 81.788 -145.542)
		(end 81.788 -146.939)
		(width 0.508)
		(layer "F.Cu")
		(net "GND")
	)
	(segment
		(start 149.6695 -249.555)
		(end 149.6695 -250.444)
		(width 0.508)
		(layer "F.Cu")
		(net "GND")
	)
	(segment
		(start 63.7286 -31.2039)
		(end 63.7286 -30.353)
		(width 0.508)
		(layer "F.Cu")
		(net "GND")
	)
	(segment
		(start 206.8957 -194.945)
		(end 205.907386 -194.945)
		(width 0.508)
		(layer "F.Cu")
		(net "GND")
	)
	(segment
		(start 156.224986 -243.035074)
		(end 153.1112 -243.035074)
		(width 0.508)
		(layer "F.Cu")
		(net "GND")
	)
	(segment
		(start 307.294026 -360.35615)
		(end 307.294026 -360.013758)
		(width 0.508)
		(layer "F.Cu")
		(net "GND")
	)
	(segment
		(start 325.550022 -50.785014)
		(end 327.432924 -50.785014)
		(width 0.508)
		(layer "F.Cu")
		(net "GND")
	)
	(segment
		(start 304.031396 -231.732074)
		(end 304.877724 -231.732074)
		(width 0.508)
		(layer "F.Cu")
		(net "GND")
	)
	(segment
		(start 47.8155 -139.065)
		(end 47.8155 -139.941554)
		(width 0.508)
		(layer "F.Cu")
		(net "GND")
	)
	(segment
		(start 321.242436 -370.2177)
		(end 321.242436 -369.75796)
		(width 0.4064)
		(layer "F.Cu")
		(net "GND")
	)
	(segment
		(start 457.3397 -135.6614)
		(end 456.7174 -136.2837)
		(width 0.508)
		(layer "F.Cu")
		(net "GND")
	)
	(segment
		(start 425.45 -38.608)
		(end 424.434 -38.608)
		(width 0.508)
		(layer "F.Cu")
		(net "GND")
	)
	(segment
		(start 362.331 -153.67)
		(end 361.315 -153.67)
		(width 0.508)
		(layer "F.Cu")
		(net "GND")
	)
	(segment
		(start 225.92284 -229.251256)
		(end 225.92284 -230.592376)
		(width 0.3556)
		(layer "F.Cu")
		(net "GND")
	)
	(segment
		(start 390.474962 -246.845074)
		(end 388.754874 -246.845074)
		(width 0.508)
		(layer "F.Cu")
		(net "GND")
	)
	(segment
		(start 61.574934 -155.97505)
		(end 59.854846 -155.97505)
		(width 0.508)
		(layer "F.Cu")
		(net "GND")
	)
	(segment
		(start 47.9425 -254.127)
		(end 47.9425 -255.016)
		(width 0.508)
		(layer "F.Cu")
		(net "GND")
	)
	(segment
		(start 403.796246 -215.844628)
		(end 403.796246 -216.754202)
		(width 0.508)
		(layer "F.Cu")
		(net "GND")
	)
	(segment
		(start 19.431 -33.782)
		(end 18.5166 -33.782)
		(width 0.508)
		(layer "F.Cu")
		(net "GND")
	)
	(segment
		(start 453.574912 -128.03505)
		(end 451.854824 -128.03505)
		(width 0.508)
		(layer "F.Cu")
		(net "GND")
	)
	(segment
		(start 86.995 -271.3228)
		(end 85.725 -271.3228)
		(width 0.508)
		(layer "F.Cu")
		(net "GND")
	)
	(segment
		(start 472.2622 -132.47624)
		(end 472.2622 -133.223)
		(width 0.4064)
		(layer "F.Cu")
		(net "GND")
	)
	(segment
		(start 321.252596 -374.35536)
		(end 321.252596 -373.5578)
		(width 0.4064)
		(layer "F.Cu")
		(net "GND")
	)
	(segment
		(start 93.125036 -135.65505)
		(end 91.404948 -135.65505)
		(width 0.508)
		(layer "F.Cu")
		(net "GND")
	)
	(segment
		(start 453.574912 -250.655074)
		(end 451.854824 -250.655074)
		(width 0.508)
		(layer "F.Cu")
		(net "GND")
	)
	(segment
		(start 30.082236 -368.9223)
		(end 30.082236 -368.36096)
		(width 0.4064)
		(layer "F.Cu")
		(net "GND")
	)
	(segment
		(start 38.956996 -364.5535)
		(end 39.753286 -364.5535)
		(width 0.508)
		(layer "F.Cu")
		(net "GND")
	)
	(segment
		(start 473.71 -260.604)
		(end 473.71 -262.001)
		(width 0.508)
		(layer "F.Cu")
		(net "GND")
	)
	(segment
		(start 137.983468 -101.773228)
		(end 137.983468 -100.858828)
		(width 0.508)
		(layer "F.Cu")
		(net "GND")
	)
	(segment
		(start 453.574912 -30.815026)
		(end 451.854824 -30.815026)
		(width 0.508)
		(layer "F.Cu")
		(net "GND")
	)
	(segment
		(start 185.950098 -50.785014)
		(end 185.950098 -52.793138)
		(width 0.508)
		(layer "F.Cu")
		(net "GND")
	)
	(segment
		(start 24.006302 -230.63835)
		(end 24.006302 -229.55885)
		(width 0.508)
		(layer "F.Cu")
		(net "GND")
	)
	(segment
		(start 451.749922 -237.035086)
		(end 453.632824 -237.035086)
		(width 0.508)
		(layer "F.Cu")
		(net "GND")
	)
	(segment
		(start 392.938 -161.163)
		(end 394.4112 -161.163)
		(width 0.508)
		(layer "F.Cu")
		(net "GND")
	)
	(segment
		(start 438.199276 -216.497154)
		(end 438.199276 -217.413586)
		(width 0.508)
		(layer "F.Cu")
		(net "GND")
	)
	(segment
		(start 152.8572 -242.781074)
		(end 152.8572 -242.697)
		(width 0.508)
		(layer "F.Cu")
		(net "GND")
	)
	(segment
		(start 150.495 -276.225)
		(end 150.495 -277.241)
		(width 0.508)
		(layer "F.Cu")
		(net "GND")
	)
	(segment
		(start 393.6238 -135.5852)
		(end 393.3444 -135.8646)
		(width 0.508)
		(layer "F.Cu")
		(net "GND")
	)
	(segment
		(start 287.683448 -350.843342)
		(end 287.556448 -350.716342)
		(width 0.2032)
		(layer "F.Cu")
		(net "GND")
	)
	(segment
		(start 19.79676 -18.6182)
		(end 19.05 -18.6182)
		(width 0.4064)
		(layer "F.Cu")
		(net "GND")
	)
	(segment
		(start 363.855 -153.289)
		(end 365.252 -153.289)
		(width 0.508)
		(layer "F.Cu")
		(net "GND")
	)
	(segment
		(start 118.0465 -249.555)
		(end 118.0465 -250.444)
		(width 0.508)
		(layer "F.Cu")
		(net "GND")
	)
	(segment
		(start 107.305094 -150.622)
		(end 107.14228 -150.784814)
		(width 0.508)
		(layer "F.Cu")
		(net "GND")
	)
	(segment
		(start 443.422786 -100.658422)
		(end 443.422786 -101.757734)
		(width 0.508)
		(layer "F.Cu")
		(net "GND")
	)
	(segment
		(start 485.125014 -148.35505)
		(end 483.404926 -148.35505)
		(width 0.508)
		(layer "F.Cu")
		(net "GND")
	)
	(segment
		(start 422.025064 -148.35505)
		(end 420.304976 -148.35505)
		(width 0.508)
		(layer "F.Cu")
		(net "GND")
	)
	(segment
		(start 403.796246 -216.754202)
		(end 403.801072 -216.759028)
		(width 0.508)
		(layer "F.Cu")
		(net "GND")
	)
	(segment
		(start 327.375012 -16.845026)
		(end 325.654924 -16.845026)
		(width 0.508)
		(layer "F.Cu")
		(net "GND")
	)
	(segment
		(start 390.474962 -268.435074)
		(end 388.754874 -268.435074)
		(width 0.508)
		(layer "F.Cu")
		(net "GND")
	)
	(segment
		(start 222.5675 -207.338422)
		(end 222.56877 -207.339692)
		(width 0.508)
		(layer "F.Cu")
		(net "GND")
	)
	(segment
		(start 222.7453 -301.8536)
		(end 222.8596 -301.9679)
		(width 0.508)
		(layer "F.Cu")
		(net "GND")
	)
	(segment
		(start 340.696296 -215.844628)
		(end 340.696296 -216.754202)
		(width 0.508)
		(layer "F.Cu")
		(net "GND")
	)
	(segment
		(start 118.618 -41.3258)
		(end 117.348 -41.3258)
		(width 0.508)
		(layer "F.Cu")
		(net "GND")
	)
	(segment
		(start 13.7668 -265.684)
		(end 12.573 -265.684)
		(width 0.508)
		(layer "F.Cu")
		(net "GND")
	)
	(segment
		(start 55.499 -156.2608)
		(end 54.229 -156.2608)
		(width 0.508)
		(layer "F.Cu")
		(net "GND")
	)
	(segment
		(start 428.301404 -364.236)
		(end 428.301404 -363.855)
		(width 0.508)
		(layer "F.Cu")
		(net "GND")
	)
	(segment
		(start 375.099326 -101.49713)
		(end 375.099326 -102.413562)
		(width 0.508)
		(layer "F.Cu")
		(net "GND")
	)
	(segment
		(start 79.4385 -139.065)
		(end 79.4385 -139.954)
		(width 0.508)
		(layer "F.Cu")
		(net "GND")
	)
	(segment
		(start 394.2842 -131.96824)
		(end 394.2842 -132.715)
		(width 0.4064)
		(layer "F.Cu")
		(net "GND")
	)
	(segment
		(start 167.549068 -216.678002)
		(end 167.553894 -216.682828)
		(width 0.508)
		(layer "F.Cu")
		(net "GND")
	)
	(segment
		(start 357.100124 -237.035086)
		(end 358.983026 -237.035086)
		(width 0.508)
		(layer "F.Cu")
		(net "GND")
	)
	(segment
		(start 17.765268 -102.43947)
		(end 17.765268 -103.26497)
		(width 0.508)
		(layer "F.Cu")
		(net "GND")
	)
	(segment
		(start 261.013194 -217.124026)
		(end 260.511544 -217.124026)
		(width 0.508)
		(layer "F.Cu")
		(net "GND")
	)
	(segment
		(start 177.53076 -133.5532)
		(end 176.784 -133.5532)
		(width 0.4064)
		(layer "F.Cu")
		(net "GND")
	)
	(segment
		(start 443.422786 -101.757734)
		(end 443.417198 -101.763322)
		(width 0.508)
		(layer "F.Cu")
		(net "GND")
	)
	(segment
		(start 417.35502 -253.830074)
		(end 419.161976 -253.830074)
		(width 0.508)
		(layer "F.Cu")
		(net "GND")
	)
	(segment
		(start 88.454992 -253.830074)
		(end 90.261948 -253.830074)
		(width 0.508)
		(layer "F.Cu")
		(net "GND")
	)
	(segment
		(start 106.360468 -216.678002)
		(end 106.365294 -216.682828)
		(width 0.508)
		(layer "F.Cu")
		(net "GND")
	)
	(segment
		(start 187.775088 -40.975026)
		(end 186.055 -40.975026)
		(width 0.508)
		(layer "F.Cu")
		(net "GND")
	)
	(segment
		(start 222.5675 -207.01)
		(end 222.5675 -207.338422)
		(width 0.508)
		(layer "F.Cu")
		(net "GND")
	)
	(segment
		(start 453.574912 -13.035026)
		(end 451.854824 -13.035026)
		(width 0.508)
		(layer "F.Cu")
		(net "GND")
	)
	(segment
		(start 187.775088 -145.81505)
		(end 186.055 -145.81505)
		(width 0.508)
		(layer "F.Cu")
		(net "GND")
	)
	(segment
		(start 48.981868 -100.782628)
		(end 48.981868 -101.717602)
		(width 0.508)
		(layer "F.Cu")
		(net "GND")
	)
	(segment
		(start 88.454992 -138.83005)
		(end 90.261948 -138.83005)
		(width 0.508)
		(layer "F.Cu")
		(net "GND")
	)
	(segment
		(start 233.8324 -309.63108)
		(end 235.41228 -309.63108)
		(width 0.3556)
		(layer "F.Cu")
		(net "GND")
	)
	(segment
		(start 263.728962 -367.004346)
		(end 263.728962 -366.194086)
		(width 0.508)
		(layer "F.Cu")
		(net "GND")
	)
	(segment
		(start 122.849894 -280.785062)
		(end 124.732796 -280.785062)
		(width 0.508)
		(layer "F.Cu")
		(net "GND")
	)
	(segment
		(start 42.214546 -362.6993)
		(end 41.242996 -362.6993)
		(width 0.508)
		(layer "F.Cu")
		(net "GND")
	)
	(segment
		(start 388.649972 -237.035086)
		(end 390.532874 -237.035086)
		(width 0.508)
		(layer "F.Cu")
		(net "GND")
	)
	(segment
		(start 453.574912 -135.65505)
		(end 453.574912 -136.838944)
		(width 0.508)
		(layer "F.Cu")
		(net "GND")
	)
	(segment
		(start 353.1616 -146.1897)
		(end 353.16668 -146.18462)
		(width 0.508)
		(layer "F.Cu")
		(net "GND")
	)
	(segment
		(start 322.704968 -253.830074)
		(end 324.511924 -253.830074)
		(width 0.508)
		(layer "F.Cu")
		(net "GND")
	)
	(segment
		(start 321.7164 -31.2039)
		(end 321.7164 -30.353)
		(width 0.508)
		(layer "F.Cu")
		(net "GND")
	)
	(segment
		(start 146.03476 -133.5532)
		(end 145.288 -133.5532)
		(width 0.4064)
		(layer "F.Cu")
		(net "GND")
	)
	(segment
		(start 218.7194 -212.87232)
		(end 217.15222 -212.87232)
		(width 0.3556)
		(layer "F.Cu")
		(net "GND")
	)
	(segment
		(start 287.048448 -347.096842)
		(end 287.048448 -346.271342)
		(width 0.508)
		(layer "F.Cu")
		(net "GND")
	)
	(segment
		(start 456.7174 -136.2837)
		(end 456.7174 -136.645142)
		(width 0.508)
		(layer "F.Cu")
		(net "GND")
	)
	(segment
		(start 311.999376 -216.497154)
		(end 311.999376 -217.413586)
		(width 0.508)
		(layer "F.Cu")
		(net "GND")
	)
	(segment
		(start 222.213932 -192.680082)
		(end 222.213932 -192.278508)
		(width 0.508)
		(layer "F.Cu")
		(net "GND")
	)
	(segment
		(start 120.00484 -251.430028)
		(end 121.811796 -251.430028)
		(width 0.508)
		(layer "F.Cu")
		(net "GND")
	)
	(segment
		(start 185.9026 -243.035074)
		(end 185.6486 -242.781074)
		(width 0.508)
		(layer "F.Cu")
		(net "GND")
	)
	(segment
		(start 76.58735 -101.8286)
		(end 76.58735 -100.7237)
		(width 0.508)
		(layer "F.Cu")
		(net "GND")
	)
	(segment
		(start 88.454992 -141.230096)
		(end 90.261948 -141.230096)
		(width 0.508)
		(layer "F.Cu")
		(net "GND")
	)
	(segment
		(start 320.78803 -101.7143)
		(end 320.792856 -101.719126)
		(width 0.508)
		(layer "F.Cu")
		(net "GND")
	)
	(segment
		(start 221.1197 -193.294)
		(end 221.600014 -193.294)
		(width 0.508)
		(layer "F.Cu")
		(net "GND")
	)
	(segment
		(start 422.025064 -260.815074)
		(end 420.304976 -260.815074)
		(width 0.508)
		(layer "F.Cu")
		(net "GND")
	)
	(segment
		(start 39.8907 -8.1534)
		(end 39.8907 -9.0043)
		(width 0.508)
		(layer "F.Cu")
		(net "GND")
	)
	(segment
		(start 150.114 -41.3258)
		(end 148.844 -41.3258)
		(width 0.508)
		(layer "F.Cu")
		(net "GND")
	)
	(segment
		(start 225.92284 -230.592376)
		(end 225.922332 -230.592884)
		(width 0.3556)
		(layer "F.Cu")
		(net "GND")
	)
	(segment
		(start 394.2842 -246.90324)
		(end 394.2842 -247.65)
		(width 0.4064)
		(layer "F.Cu")
		(net "GND")
	)
	(segment
		(start 16.3195 -139.065)
		(end 16.3195 -139.954)
		(width 0.508)
		(layer "F.Cu")
		(net "GND")
	)
	(segment
		(start 358.925114 -145.81505)
		(end 357.205026 -145.81505)
		(width 0.508)
		(layer "F.Cu")
		(net "GND")
	)
	(segment
		(start 202.260454 -244.34292)
		(end 202.260454 -243.78793)
		(width 0.3556)
		(layer "F.Cu")
		(net "GND")
	)
	(segment
		(start 36.099496 -364.236)
		(end 36.273486 -364.40999)
		(width 0.508)
		(layer "F.Cu")
		(net "GND")
	)
	(segment
		(start 249.032268 -223.4057)
		(end 249.032268 -224.2566)
		(width 0.508)
		(layer "F.Cu")
		(net "GND")
	)
	(segment
		(start 181.991 -46.228)
		(end 181.991 -47.244)
		(width 0.508)
		(layer "F.Cu")
		(net "GND")
	)
	(segment
		(start 325.550022 -237.035086)
		(end 323.596 -237.035086)
		(width 0.508)
		(layer "F.Cu")
		(net "GND")
	)
	(segment
		(start 30.025086 -250.655074)
		(end 28.304998 -250.655074)
		(width 0.508)
		(layer "F.Cu")
		(net "GND")
	)
	(segment
		(start 480.45497 -21.42998)
		(end 482.261926 -21.42998)
		(width 0.508)
		(layer "F.Cu")
		(net "GND")
	)
	(segment
		(start 147.33524 -135.4328)
		(end 148.2598 -135.4328)
		(width 0.4064)
		(layer "F.Cu")
		(net "GND")
	)
	(segment
		(start 188.806328 -369.487196)
		(end 189.151768 -369.487196)
		(width 0.4064)
		(layer "F.Cu")
		(net "GND")
	)
	(segment
		(start 485.125014 -38.435026)
		(end 483.404926 -38.435026)
		(width 0.508)
		(layer "F.Cu")
		(net "GND")
	)
	(segment
		(start 109.28985 -101.435154)
		(end 109.28985 -102.351586)
		(width 0.508)
		(layer "F.Cu")
		(net "GND")
	)
	(segment
		(start 372.246144 -215.844628)
		(end 372.246144 -216.754202)
		(width 0.508)
		(layer "F.Cu")
		(net "GND")
	)
	(segment
		(start 25.355042 -256.23012)
		(end 27.161998 -256.23012)
		(width 0.508)
		(layer "F.Cu")
		(net "GND")
	)
	(segment
		(start 358.925114 -135.65505)
		(end 357.205026 -135.65505)
		(width 0.508)
		(layer "F.Cu")
		(net "GND")
	)
	(segment
		(start 327.375012 -30.815026)
		(end 325.654924 -30.815026)
		(width 0.508)
		(layer "F.Cu")
		(net "GND")
	)
	(segment
		(start 453.574912 -246.845074)
		(end 451.854824 -246.845074)
		(width 0.508)
		(layer "F.Cu")
		(net "GND")
	)
	(segment
		(start 331.47 -275.9202)
		(end 331.47 -277.114)
		(width 0.508)
		(layer "F.Cu")
		(net "GND")
	)
	(segment
		(start 354.25507 -253.830074)
		(end 356.062026 -253.830074)
		(width 0.508)
		(layer "F.Cu")
		(net "GND")
	)
	(segment
		(start 457.9874 -20.7772)
		(end 458.089 -20.8788)
		(width 0.508)
		(layer "F.Cu")
		(net "GND")
	)
	(segment
		(start 212.9536 -217.65768)
		(end 211.6582 -217.65768)
		(width 0.3556)
		(layer "F.Cu")
		(net "GND")
	)
	(segment
		(start 282.920948 -356.304342)
		(end 282.197048 -356.304342)
		(width 0.508)
		(layer "F.Cu")
		(net "GND")
	)
	(segment
		(start 156.224986 -33.355026)
		(end 154.504898 -33.355026)
		(width 0.508)
		(layer "F.Cu")
		(net "GND")
	)
	(segment
		(start 52.59324 -135.4328)
		(end 53.5178 -135.4328)
		(width 0.4064)
		(layer "F.Cu")
		(net "GND")
	)
	(segment
		(start 243.817902 -131.982718)
		(end 245.2878 -131.982718)
		(width 0.4064)
		(layer "F.Cu")
		(net "GND")
	)
	(segment
		(start 394.1953 -135.5852)
		(end 393.6238 -135.5852)
		(width 0.508)
		(layer "F.Cu")
		(net "GND")
	)
	(segment
		(start 446.9765 -147.193)
		(end 446.9765 -146.304)
		(width 0.508)
		(layer "F.Cu")
		(net "GND")
	)
	(segment
		(start 263.129522 -361.860846)
		(end 263.129522 -362.749846)
		(width 0.508)
		(layer "F.Cu")
		(net "GND")
	)
	(segment
		(start 485.125014 -131.84505)
		(end 483.404926 -131.84505)
		(width 0.508)
		(layer "F.Cu")
		(net "GND")
	)
	(segment
		(start 202.400154 -244.48262)
		(end 202.260454 -244.34292)
		(width 0.3556)
		(layer "F.Cu")
		(net "GND")
	)
	(segment
		(start 25.355042 -136.430004)
		(end 27.161998 -136.430004)
		(width 0.508)
		(layer "F.Cu")
		(net "GND")
	)
	(segment
		(start 420.737284 -33.355026)
		(end 419.914324 -34.177986)
		(width 0.508)
		(layer "F.Cu")
		(net "GND")
	)
	(segment
		(start 145.6944 -33.782)
		(end 144.7546 -33.782)
		(width 0.508)
		(layer "F.Cu")
		(net "GND")
	)
	(segment
		(start 165.288468 -97.328228)
		(end 165.288468 -96.248728)
		(width 0.508)
		(layer "F.Cu")
		(net "GND")
	)
	(segment
		(start 260.404864 -226.81311)
		(end 260.413754 -226.822)
		(width 0.4572)
		(layer "F.Cu")
		(net "GND")
	)
	(segment
		(start 26.510996 -371.3988)
		(end 26.434796 -371.475)
		(width 0.508)
		(layer "F.Cu")
		(net "GND")
	)
	(segment
		(start 262.6614 -380.216156)
		(end 262.6614 -381.143256)
		(width 0.508)
		(layer "F.Cu")
		(net "GND")
	)
	(segment
		(start 358.925114 -20.655026)
		(end 357.205026 -20.655026)
		(width 0.508)
		(layer "F.Cu")
		(net "GND")
	)
	(segment
		(start 327.375012 -145.81505)
		(end 325.654924 -145.81505)
		(width 0.508)
		(layer "F.Cu")
		(net "GND")
	)
	(segment
		(start 364.6805 -20.574)
		(end 365.633 -20.574)
		(width 0.508)
		(layer "F.Cu")
		(net "GND")
	)
	(segment
		(start 458.506068 -101.849428)
		(end 458.506068 -100.935028)
		(width 0.508)
		(layer "F.Cu")
		(net "GND")
	)
	(segment
		(start 358.925114 -16.845026)
		(end 357.205026 -16.845026)
		(width 0.508)
		(layer "F.Cu")
		(net "GND")
	)
	(segment
		(start 330.589636 -364.25886)
		(end 330.589636 -363.56163)
		(width 0.508)
		(layer "F.Cu")
		(net "GND")
	)
	(segment
		(start 325.550022 -280.785062)
		(end 327.432924 -280.785062)
		(width 0.508)
		(layer "F.Cu")
		(net "GND")
	)
	(segment
		(start 23.4315 -19.558)
		(end 23.4315 -20.447)
		(width 0.508)
		(layer "F.Cu")
		(net "GND")
	)
	(segment
		(start 151.554942 -136.430004)
		(end 153.361898 -136.430004)
		(width 0.508)
		(layer "F.Cu")
		(net "GND")
	)
	(segment
		(start 425.7802 -16.90624)
		(end 425.7802 -17.653)
		(width 0.4064)
		(layer "F.Cu")
		(net "GND")
	)
	(segment
		(start 118.872 -46.228)
		(end 118.872 -47.244)
		(width 0.508)
		(layer "F.Cu")
		(net "GND")
	)
	(segment
		(start 395.4018 -12.17676)
		(end 395.4018 -11.43)
		(width 0.4064)
		(layer "F.Cu")
		(net "GND")
	)
	(segment
		(start 140.0048 -151.853646)
		(end 140.024104 -151.87295)
		(width 0.508)
		(layer "F.Cu")
		(net "GND")
	)
	(segment
		(start 474.88856 -246.23776)
		(end 475.1832 -246.5324)
		(width 0.4064)
		(layer "F.Cu")
		(net "GND")
	)
	(segment
		(start 171.5008 -265.684)
		(end 170.307 -265.684)
		(width 0.508)
		(layer "F.Cu")
		(net "GND")
	)
	(segment
		(start 232.22204 -234.71505)
		(end 232.208832 -234.728258)
		(width 0.508)
		(layer "F.Cu")
		(net "GND")
	)
	(segment
		(start 124.674884 -40.975026)
		(end 122.954796 -40.975026)
		(width 0.508)
		(layer "F.Cu")
		(net "GND")
	)
	(segment
		(start 361.315 -161.163)
		(end 361.315 -162.179)
		(width 0.508)
		(layer "F.Cu")
		(net "GND")
	)
	(segment
		(start 455.93 -276.098)
		(end 455.93 -277.114)
		(width 0.508)
		(layer "F.Cu")
		(net "GND")
	)
	(segment
		(start 59.749944 -280.785062)
		(end 61.632846 -280.785062)
		(width 0.508)
		(layer "F.Cu")
		(net "GND")
	)
	(segment
		(start 16.3195 -254.127)
		(end 16.3195 -255.016)
		(width 0.508)
		(layer "F.Cu")
		(net "GND")
	)
	(segment
		(start 354.25507 -138.83005)
		(end 356.062026 -138.83005)
		(width 0.508)
		(layer "F.Cu")
		(net "GND")
	)
	(segment
		(start 390.474962 -263.355074)
		(end 388.754874 -263.355074)
		(width 0.508)
		(layer "F.Cu")
		(net "GND")
	)
	(segment
		(start 42.544746 -364.236)
		(end 42.544746 -363.0295)
		(width 0.508)
		(layer "F.Cu")
		(net "GND")
	)
	(segment
		(start 342.469978 -101.813868)
		(end 342.46947 -101.814376)
		(width 0.508)
		(layer "F.Cu")
		(net "GND")
	)
	(segment
		(start 123.299982 -153.43505)
		(end 122.74931 -153.985722)
		(width 0.508)
		(layer "F.Cu")
		(net "GND")
	)
	(segment
		(start 187.775088 -260.815074)
		(end 186.055 -260.815074)
		(width 0.508)
		(layer "F.Cu")
		(net "GND")
	)
	(segment
		(start 327.437496 -364.236)
		(end 327.437496 -363.3978)
		(width 0.508)
		(layer "F.Cu")
		(net "GND")
	)
	(segment
		(start 485.125014 -155.97505)
		(end 483.404926 -155.97505)
		(width 0.508)
		(layer "F.Cu")
		(net "GND")
	)
	(segment
		(start 18.669 -260.604)
		(end 18.669 -262.001)
		(width 0.508)
		(layer "F.Cu")
		(net "GND")
	)
	(segment
		(start 44.972732 -211.201)
		(end 44.845732 -211.074)
		(width 0.508)
		(layer "F.Cu")
		(net "GND")
	)
	(segment
		(start 166.177468 -101.692202)
		(end 166.182294 -101.697028)
		(width 0.508)
		(layer "F.Cu")
		(net "GND")
	)
	(segment
		(start 251.504196 -226.35591)
		(end 250.645422 -226.35591)
		(width 0.4572)
		(layer "F.Cu")
		(net "GND")
	)
	(segment
		(start 56.90489 -253.830074)
		(end 58.711846 -253.830074)
		(width 0.508)
		(layer "F.Cu")
		(net "GND")
	)
	(segment
		(start 67.1703 -262.128)
		(end 67.1703 -261.2898)
		(width 0.508)
		(layer "F.Cu")
		(net "GND")
	)
	(segment
		(start 333.0448 -130.66776)
		(end 333.0448 -129.921)
		(width 0.4064)
		(layer "F.Cu")
		(net "GND")
	)
	(segment
		(start 440.487054 -119.011446)
		(end 440.654186 -119.178578)
		(width 0.508)
		(layer "F.Cu")
		(net "GND")
	)
	(segment
		(start 88.454992 -256.23012)
		(end 90.261948 -256.23012)
		(width 0.508)
		(layer "F.Cu")
		(net "GND")
	)
	(segment
		(start 388.649972 -7.035038)
		(end 390.532874 -7.035038)
		(width 0.508)
		(layer "F.Cu")
		(net "GND")
	)
	(segment
		(start 479.298 -161.163)
		(end 479.298 -162.179)
		(width 0.508)
		(layer "F.Cu")
		(net "GND")
	)
	(segment
		(start 153.1112 -243.035074)
		(end 152.8572 -242.781074)
		(width 0.508)
		(layer "F.Cu")
		(net "GND")
	)
	(segment
		(start 222.710248 -226.384358)
		(end 222.980758 -226.384358)
		(width 0.508)
		(layer "F.Cu")
		(net "GND")
	)
	(segment
		(start 181.6862 -271.3228)
		(end 180.4162 -271.3228)
		(width 0.508)
		(layer "F.Cu")
		(net "GND")
	)
	(segment
		(start 19.4056 -148.717)
		(end 18.4912 -148.717)
		(width 0.508)
		(layer "F.Cu")
		(net "GND")
	)
	(segment
		(start 306.316634 -359.423462)
		(end 306.70373 -359.423462)
		(width 0.508)
		(layer "F.Cu")
		(net "GND")
	)
	(segment
		(start 185.950098 -165.785038)
		(end 187.833 -165.785038)
		(width 0.508)
		(layer "F.Cu")
		(net "GND")
	)
	(segment
		(start 362.966 -160.9852)
		(end 362.966 -162.179)
		(width 0.508)
		(layer "F.Cu")
		(net "GND")
	)
	(segment
		(start 457.2762 -131.96824)
		(end 457.2762 -132.715)
		(width 0.4064)
		(layer "F.Cu")
		(net "GND")
	)
	(segment
		(start 156.224986 -131.84505)
		(end 154.504898 -131.84505)
		(width 0.508)
		(layer "F.Cu")
		(net "GND")
	)
	(segment
		(start 396.621 -160.9852)
		(end 396.621 -162.52444)
		(width 0.508)
		(layer "F.Cu")
		(net "GND")
	)
	(segment
		(start 61.574934 -30.815026)
		(end 59.854846 -30.815026)
		(width 0.508)
		(layer "F.Cu")
		(net "GND")
	)
	(segment
		(start 485.125014 -250.655074)
		(end 483.404926 -250.655074)
		(width 0.508)
		(layer "F.Cu")
		(net "GND")
	)
	(segment
		(start 420.200074 -280.785062)
		(end 422.082976 -280.785062)
		(width 0.508)
		(layer "F.Cu")
		(net "GND")
	)
	(segment
		(start 98.8695 -147.066)
		(end 98.8695 -146.177)
		(width 0.508)
		(layer "F.Cu")
		(net "GND")
	)
	(segment
		(start 61.574934 -13.035026)
		(end 59.854846 -13.035026)
		(width 0.508)
		(layer "F.Cu")
		(net "GND")
	)
	(segment
		(start 327.375012 -260.815074)
		(end 325.654924 -260.815074)
		(width 0.508)
		(layer "F.Cu")
		(net "GND")
	)
	(segment
		(start 424.434 -161.163)
		(end 424.434 -162.179)
		(width 0.508)
		(layer "F.Cu")
		(net "GND")
	)
	(segment
		(start 228.6127 -302.6918)
		(end 229.616 -302.6918)
		(width 0.508)
		(layer "F.Cu")
		(net "GND")
	)
	(segment
		(start 358.925114 -270.975074)
		(end 357.205026 -270.975074)
		(width 0.508)
		(layer "F.Cu")
		(net "GND")
	)
	(segment
		(start 156.224986 -153.43505)
		(end 158.15945 -153.43505)
		(width 0.4572)
		(layer "F.Cu")
		(net "GND")
	)
	(segment
		(start 330.294996 -364.5535)
		(end 330.589636 -364.25886)
		(width 0.508)
		(layer "F.Cu")
		(net "GND")
	)
	(segment
		(start 209.3595 -225.679)
		(end 208.5086 -225.679)
		(width 0.508)
		(layer "F.Cu")
		(net "GND")
	)
	(segment
		(start 124.674884 -246.845074)
		(end 122.954796 -246.845074)
		(width 0.508)
		(layer "F.Cu")
		(net "GND")
	)
	(segment
		(start 45.89145 -216.55405)
		(end 45.8216 -216.4842)
		(width 0.508)
		(layer "F.Cu")
		(net "GND")
	)
	(segment
		(start 332.359 -153.289)
		(end 333.756 -153.289)
		(width 0.508)
		(layer "F.Cu")
		(net "GND")
	)
	(segment
		(start 245.549674 -138.615674)
		(end 245.9228 -138.9888)
		(width 0.4064)
		(layer "F.Cu")
		(net "GND")
	)
	(segment
		(start 187.775088 -246.845074)
		(end 186.055 -246.845074)
		(width 0.508)
		(layer "F.Cu")
		(net "GND")
	)
	(segment
		(start 422.025064 -20.655026)
		(end 420.304976 -20.655026)
		(width 0.508)
		(layer "F.Cu")
		(net "GND")
	)
	(segment
		(start 216.8906 -213.13394)
		(end 216.8906 -213.1568)
		(width 0.3556)
		(layer "F.Cu")
		(net "GND")
	)
	(segment
		(start 36.099496 -368.935)
		(end 36.924996 -368.935)
		(width 0.508)
		(layer "F.Cu")
		(net "GND")
	)
	(segment
		(start 357.100124 -7.035038)
		(end 358.983026 -7.035038)
		(width 0.508)
		(layer "F.Cu")
		(net "GND")
	)
	(segment
		(start 213.4108 -203.327)
		(end 213.4108 -202.629262)
		(width 0.508)
		(layer "F.Cu")
		(net "GND")
	)
	(segment
		(start 183.105044 -256.23012)
		(end 184.912 -256.23012)
		(width 0.508)
		(layer "F.Cu")
		(net "GND")
	)
	(segment
		(start 364.998 -45.9232)
		(end 364.998 -47.117)
		(width 0.508)
		(layer "F.Cu")
		(net "GND")
	)
	(segment
		(start 261.5184 -216.8017)
		(end 261.460742 -216.859358)
		(width 0.508)
		(layer "F.Cu")
		(net "GND")
	)
	(segment
		(start 40.8305 -6.3754)
		(end 40.1828 -6.3754)
		(width 0.508)
		(layer "F.Cu")
		(net "GND")
	)
	(segment
		(start 453.574912 -33.355026)
		(end 451.854824 -33.355026)
		(width 0.508)
		(layer "F.Cu")
		(net "GND")
	)
	(segment
		(start 239.780064 -368.863118)
		(end 239.780826 -368.86388)
		(width 0.508)
		(layer "F.Cu")
		(net "GND")
	)
	(segment
		(start 213.789006 -204.342746)
		(end 213.8172 -204.342746)
		(width 0.508)
		(layer "F.Cu")
		(net "GND")
	)
	(segment
		(start 51.41976 -248.6152)
		(end 50.673 -248.6152)
		(width 0.4064)
		(layer "F.Cu")
		(net "GND")
	)
	(segment
		(start 396.621 -275.9202)
		(end 396.621 -277.114)
		(width 0.508)
		(layer "F.Cu")
		(net "GND")
	)
	(segment
		(start 93.125036 -38.435026)
		(end 91.404948 -38.435026)
		(width 0.508)
		(layer "F.Cu")
		(net "GND")
	)
	(segment
		(start 48.85436 -118.373906)
		(end 48.79086 -118.310406)
		(width 0.508)
		(layer "F.Cu")
		(net "GND")
	)
	(segment
		(start 256.4765 -216.129616)
		(end 256.4384 -216.167716)
		(width 0.3048)
		(layer "F.Cu")
		(net "GND")
	)
	(segment
		(start 342.469978 -100.709476)
		(end 342.469978 -101.813868)
		(width 0.508)
		(layer "F.Cu")
		(net "GND")
	)
	(segment
		(start 181.6862 -41.3258)
		(end 180.4162 -41.3258)
		(width 0.508)
		(layer "F.Cu")
		(net "GND")
	)
	(segment
		(start 362.966 -275.9202)
		(end 362.966 -277.114)
		(width 0.508)
		(layer "F.Cu")
		(net "GND")
	)
	(segment
		(start 149.81047 -217.0684)
		(end 149.81047 -215.9635)
		(width 0.508)
		(layer "F.Cu")
		(net "GND")
	)
	(segment
		(start 447.015616 -100.662486)
		(end 447.015616 -101.764338)
		(width 0.508)
		(layer "F.Cu")
		(net "GND")
	)
	(segment
		(start 340.696296 -101.754178)
		(end 340.701122 -101.759004)
		(width 0.508)
		(layer "F.Cu")
		(net "GND")
	)
	(segment
		(start 234.696 -224.8535)
		(end 235.7755 -224.8535)
		(width 0.508)
		(layer "F.Cu")
		(net "GND")
	)
	(segment
		(start 385.804918 -141.230096)
		(end 387.611874 -141.230096)
		(width 0.508)
		(layer "F.Cu")
		(net "GND")
	)
	(segment
		(start 453.574912 -145.81505)
		(end 451.854824 -145.81505)
		(width 0.508)
		(layer "F.Cu")
		(net "GND")
	)
	(segment
		(start 156.224986 -20.655026)
		(end 154.504898 -20.655026)
		(width 0.508)
		(layer "F.Cu")
		(net "GND")
	)
	(segment
		(start 67.2465 -147.066)
		(end 67.247008 -147.065492)
		(width 0.508)
		(layer "F.Cu")
		(net "GND")
	)
	(segment
		(start 122.849894 -165.785038)
		(end 124.732796 -165.785038)
		(width 0.508)
		(layer "F.Cu")
		(net "GND")
	)
	(segment
		(start 321.7164 -146.1897)
		(end 323.141594 -146.1897)
		(width 0.508)
		(layer "F.Cu")
		(net "GND")
	)
	(segment
		(start 477.4692 -250.1265)
		(end 478.3074 -250.1265)
		(width 0.508)
		(layer "F.Cu")
		(net "GND")
	)
	(segment
		(start 422.0972 -237.0836)
		(end 422.048686 -237.035086)
		(width 0.508)
		(layer "F.Cu")
		(net "GND")
	)
	(segment
		(start 468.669878 -216.813892)
		(end 468.66937 -216.8144)
		(width 0.508)
		(layer "F.Cu")
		(net "GND")
	)
	(segment
		(start 456.355704 -374.8405)
		(end 455.733404 -374.2182)
		(width 0.4064)
		(layer "F.Cu")
		(net "GND")
	)
	(segment
		(start 374.019826 -216.813892)
		(end 374.019318 -216.8144)
		(width 0.508)
		(layer "F.Cu")
		(net "GND")
	)
	(segment
		(start 354.25507 -136.430004)
		(end 356.062026 -136.430004)
		(width 0.508)
		(layer "F.Cu")
		(net "GND")
	)
	(segment
		(start 453.574912 -16.845026)
		(end 451.854824 -16.845026)
		(width 0.508)
		(layer "F.Cu")
		(net "GND")
	)
	(segment
		(start 185.950098 -280.785062)
		(end 187.833 -280.785062)
		(width 0.508)
		(layer "F.Cu")
		(net "GND")
	)
	(segment
		(start 417.35502 -136.430004)
		(end 419.161976 -136.430004)
		(width 0.508)
		(layer "F.Cu")
		(net "GND")
	)
	(segment
		(start 330.835 -268.605)
		(end 329.819 -268.605)
		(width 0.508)
		(layer "F.Cu")
		(net "GND")
	)
	(segment
		(start 55.753 -46.228)
		(end 55.753 -47.244)
		(width 0.508)
		(layer "F.Cu")
		(net "GND")
	)
	(segment
		(start 88.454992 -23.830026)
		(end 90.261948 -23.830026)
		(width 0.508)
		(layer "F.Cu")
		(net "GND")
	)
	(segment
		(start 118.0465 -134.493)
		(end 118.0465 -135.382)
		(width 0.508)
		(layer "F.Cu")
		(net "GND")
	)
	(segment
		(start 174.0535 -139.065)
		(end 174.0535 -139.338558)
		(width 0.508)
		(layer "F.Cu")
		(net "GND")
	)
	(segment
		(start 405.569928 -215.7095)
		(end 405.569928 -216.813892)
		(width 0.508)
		(layer "F.Cu")
		(net "GND")
	)
	(segment
		(start 14.912086 -99.869498)
		(end 14.916912 -99.874324)
		(width 0.508)
		(layer "F.Cu")
		(net "GND")
	)
	(segment
		(start 50.4825 -20.955)
		(end 51.435 -20.955)
		(width 0.508)
		(layer "F.Cu")
		(net "GND")
	)
	(segment
		(start 79.4385 -254.127)
		(end 79.4385 -255.016)
		(width 0.508)
		(layer "F.Cu")
		(net "GND")
	)
	(segment
		(start 394.4112 -161.163)
		(end 394.589 -160.9852)
		(width 0.508)
		(layer "F.Cu")
		(net "GND")
	)
	(segment
		(start 225.749104 -354.68179)
		(end 225.749104 -356.165912)
		(width 0.508)
		(layer "F.Cu")
		(net "GND")
	)
	(segment
		(start 330.835 -38.608)
		(end 329.819 -38.608)
		(width 0.508)
		(layer "F.Cu")
		(net "GND")
	)
	(segment
		(start 422.048686 -237.035086)
		(end 420.200074 -237.035086)
		(width 0.508)
		(layer "F.Cu")
		(net "GND")
	)
	(segment
		(start 256.69748 -217.45702)
		(end 256.69748 -216.426796)
		(width 0.3048)
		(layer "F.Cu")
		(net "GND")
	)
	(segment
		(start 459.167738 -231.086914)
		(end 458.752956 -231.086914)
		(width 0.508)
		(layer "F.Cu")
		(net "GND")
	)
	(segment
		(start 473.71 -31.578296)
		(end 472.647518 -30.515814)
		(width 0.508)
		(layer "F.Cu")
		(net "GND")
	)
	(segment
		(start 156.224986 -13.035026)
		(end 154.504898 -13.035026)
		(width 0.508)
		(layer "F.Cu")
		(net "GND")
	)
	(segment
		(start 459.434946 -38.227)
		(end 460.07147 -37.590476)
		(width 0.508)
		(layer "F.Cu")
		(net "GND")
	)
	(segment
		(start 327.375012 -131.84505)
		(end 325.654924 -131.84505)
		(width 0.508)
		(layer "F.Cu")
		(net "GND")
	)
	(segment
		(start 122.849894 -50.785014)
		(end 124.732796 -50.785014)
		(width 0.508)
		(layer "F.Cu")
		(net "GND")
	)
	(segment
		(start 426.085 -45.9232)
		(end 426.085 -47.117)
		(width 0.508)
		(layer "F.Cu")
		(net "GND")
	)
	(segment
		(start 180.6448 -161.163)
		(end 180.4162 -161.3916)
		(width 0.508)
		(layer "F.Cu")
		(net "GND")
	)
	(segment
		(start 453.574912 -263.355074)
		(end 451.854824 -263.355074)
		(width 0.508)
		(layer "F.Cu")
		(net "GND")
	)
	(segment
		(start 230.8225 -197.612)
		(end 230.1494 -197.612)
		(width 0.508)
		(layer "F.Cu")
		(net "GND")
	)
	(segment
		(start 158.15945 -153.43505)
		(end 158.166562 -153.442162)
		(width 0.4572)
		(layer "F.Cu")
		(net "GND")
	)
	(segment
		(start 185.950098 -7.035038)
		(end 187.833 -7.035038)
		(width 0.508)
		(layer "F.Cu")
		(net "GND")
	)
	(segment
		(start 156.224986 -128.03505)
		(end 154.504898 -128.03505)
		(width 0.508)
		(layer "F.Cu")
		(net "GND")
	)
	(segment
		(start 30.025086 -128.03505)
		(end 28.304998 -128.03505)
		(width 0.508)
		(layer "F.Cu")
		(net "GND")
	)
	(segment
		(start 187.775088 -135.65505)
		(end 186.055 -135.65505)
		(width 0.508)
		(layer "F.Cu")
		(net "GND")
	)
	(segment
		(start 332.0288 -12.17676)
		(end 332.0288 -11.43)
		(width 0.4064)
		(layer "F.Cu")
		(net "GND")
	)
	(segment
		(start 390.474962 -128.03505)
		(end 388.754874 -128.03505)
		(width 0.508)
		(layer "F.Cu")
		(net "GND")
	)
	(segment
		(start 461.35925 -101.587554)
		(end 461.35925 -102.503986)
		(width 0.508)
		(layer "F.Cu")
		(net "GND")
	)
	(segment
		(start 24.006302 -230.63835)
		(end 23.557738 -231.086914)
		(width 0.508)
		(layer "F.Cu")
		(net "GND")
	)
	(segment
		(start 257.07975 -233.2355)
		(end 257.07975 -235.17225)
		(width 0.508)
		(layer "F.Cu")
		(net "GND")
	)
	(segment
		(start 183.517032 -372.6942)
		(end 181.7497 -372.6942)
		(width 0.508)
		(layer "F.Cu")
		(net "GND")
	)
	(segment
		(start 56.90489 -26.230072)
		(end 58.711846 -26.230072)
		(width 0.508)
		(layer "F.Cu")
		(net "GND")
	)
	(segment
		(start 252.102112 -369.464844)
		(end 252.102112 -369.818412)
		(width 0.3048)
		(layer "F.Cu")
		(net "GND")
	)
	(segment
		(start 156.224986 -155.97505)
		(end 158.158434 -155.97505)
		(width 0.4572)
		(layer "F.Cu")
		(net "GND")
	)
	(segment
		(start 453.574912 -260.815074)
		(end 451.854824 -260.815074)
		(width 0.508)
		(layer "F.Cu")
		(net "GND")
	)
	(segment
		(start 221.600014 -193.294)
		(end 222.213932 -192.680082)
		(width 0.508)
		(layer "F.Cu")
		(net "GND")
	)
	(segment
		(start 256.944114 -227.34143)
		(end 257.800348 -227.34143)
		(width 0.4572)
		(layer "F.Cu")
		(net "GND")
	)
	(segment
		(start 459.359 -15.4813)
		(end 459.9178 -15.4813)
		(width 0.508)
		(layer "F.Cu")
		(net "GND")
	)
	(segment
		(start 353.314 -261.2009)
		(end 353.314 -260.2992)
		(width 0.508)
		(layer "F.Cu")
		(net "GND")
	)
	(segment
		(start 330.1492 -13.47724)
		(end 330.1492 -14.224)
		(width 0.4064)
		(layer "F.Cu")
		(net "GND")
	)
	(segment
		(start 190.673736 -365.298736)
		(end 190.720218 -365.252254)
		(width 0.4064)
		(layer "F.Cu")
		(net "GND")
	)
	(segment
		(start 112.0902 -32.004)
		(end 113.284 -32.004)
		(width 0.508)
		(layer "F.Cu")
		(net "GND")
	)
	(segment
		(start 471.3605 -139.065)
		(end 471.3605 -139.954)
		(width 0.508)
		(layer "F.Cu")
		(net "GND")
	)
	(segment
		(start 437.119776 -216.813892)
		(end 437.119268 -216.8144)
		(width 0.508)
		(layer "F.Cu")
		(net "GND")
	)
	(segment
		(start 485.125014 -30.815026)
		(end 483.404926 -30.815026)
		(width 0.508)
		(layer "F.Cu")
		(net "GND")
	)
	(segment
		(start 361.8738 -250.5456)
		(end 361.7214 -250.698)
		(width 0.508)
		(layer "F.Cu")
		(net "GND")
	)
	(segment
		(start 39.8907 -9.0043)
		(end 39.9796 -9.0932)
		(width 0.508)
		(layer "F.Cu")
		(net "GND")
	)
	(segment
		(start 55.499 -271.3228)
		(end 54.229 -271.3228)
		(width 0.508)
		(layer "F.Cu")
		(net "GND")
	)
	(segment
		(start 16.685768 -99.615498)
		(end 16.685768 -100.735384)
		(width 0.508)
		(layer "F.Cu")
		(net "GND")
	)
	(segment
		(start 390.474962 -38.435026)
		(end 388.754874 -38.435026)
		(width 0.508)
		(layer "F.Cu")
		(net "GND")
	)
	(segment
		(start 88.454992 -26.230072)
		(end 90.261948 -26.230072)
		(width 0.508)
		(layer "F.Cu")
		(net "GND")
	)
	(segment
		(start 208.59496 -167.802814)
		(end 209.001614 -168.209468)
		(width 0.508)
		(layer "F.Cu")
		(net "GND")
	)
	(segment
		(start 422.025064 -135.65505)
		(end 420.304976 -135.65505)
		(width 0.508)
		(layer "F.Cu")
		(net "GND")
	)
	(segment
		(start 23.557738 -231.086914)
		(end 23.142956 -231.086914)
		(width 0.508)
		(layer "F.Cu")
		(net "GND")
	)
	(segment
		(start 460.9719 -6.2992)
		(end 460.9719 -5.461)
		(width 0.508)
		(layer "F.Cu")
		(net "GND")
	)
	(segment
		(start 184.810146 -23.830026)
		(end 184.813956 -23.833836)
		(width 0.508)
		(layer "F.Cu")
		(net "GND")
	)
	(segment
		(start 222.98025 -304.3301)
		(end 222.98025 -302.81245)
		(width 0.508)
		(layer "F.Cu")
		(net "GND")
	)
	(segment
		(start 212.9663 -204.343)
		(end 213.788752 -204.343)
		(width 0.508)
		(layer "F.Cu")
		(net "GND")
	)
	(segment
		(start 217.50274 -197.8914)
		(end 217.163142 -198.230998)
		(width 0.508)
		(layer "F.Cu")
		(net "GND")
	)
	(segment
		(start 35.7505 -262.128)
		(end 35.7505 -261.239)
		(width 0.508)
		(layer "F.Cu")
		(net "GND")
	)
	(segment
		(start 453.574912 -270.975074)
		(end 451.854824 -270.975074)
		(width 0.508)
		(layer "F.Cu")
		(net "GND")
	)
	(segment
		(start 361.315 -276.098)
		(end 361.315 -277.114)
		(width 0.508)
		(layer "F.Cu")
		(net "GND")
	)
	(segment
		(start 59.749944 -7.035038)
		(end 61.632846 -7.035038)
		(width 0.508)
		(layer "F.Cu")
		(net "GND")
	)
	(segment
		(start 91.300046 -7.035038)
		(end 93.182948 -7.035038)
		(width 0.508)
		(layer "F.Cu")
		(net "GND")
	)
	(segment
		(start 485.125014 -16.845026)
		(end 483.404926 -16.845026)
		(width 0.508)
		(layer "F.Cu")
		(net "GND")
	)
	(segment
		(start 82.5754 -148.717)
		(end 82.13852 -149.15388)
		(width 0.508)
		(layer "F.Cu")
		(net "GND")
	)
	(segment
		(start 422.025064 -250.655074)
		(end 420.304976 -250.655074)
		(width 0.508)
		(layer "F.Cu")
		(net "GND")
	)
	(segment
		(start 252.100588 -368.591846)
		(end 252.10008 -368.592354)
		(width 0.3048)
		(layer "F.Cu")
		(net "GND")
	)
	(segment
		(start 325.550022 -7.035038)
		(end 327.432924 -7.035038)
		(width 0.508)
		(layer "F.Cu")
		(net "GND")
	)
	(segment
		(start 91.300046 -235.064554)
		(end 91.313 -235.0516)
		(width 0.508)
		(layer "F.Cu")
		(net "GND")
	)
	(segment
		(start 67.1703 -261.2898)
		(end 67.1195 -261.239)
		(width 0.508)
		(layer "F.Cu")
		(net "GND")
	)
	(segment
		(start 395.478 -153.289)
		(end 396.875 -153.289)
		(width 0.508)
		(layer "F.Cu")
		(net "GND")
	)
	(segment
		(start 28.685236 -374.53824)
		(end 28.238196 -374.53824)
		(width 0.4064)
		(layer "F.Cu")
		(net "GND")
	)
	(segment
		(start 210.93938 -249.43562)
		(end 210.058 -250.317)
		(width 0.508)
		(layer "F.Cu")
		(net "GND")
	)
	(segment
		(start 40.252396 -359.66654)
		(end 40.254936 -359.664)
		(width 0.508)
		(layer "F.Cu")
		(net "GND")
	)
	(segment
		(start 406.258014 -217.805)
		(end 405.638 -217.805)
		(width 0.508)
		(layer "F.Cu")
		(net "GND")
	)
	(segment
		(start 426.879004 -364.5535)
		(end 427.983904 -364.5535)
		(width 0.508)
		(layer "F.Cu")
		(net "GND")
	)
	(segment
		(start 156.224986 -260.815074)
		(end 154.504898 -260.815074)
		(width 0.508)
		(layer "F.Cu")
		(net "GND")
	)
	(segment
		(start 309.1434 -341.257382)
		(end 309.1434 -342.077802)
		(width 0.508)
		(layer "F.Cu")
		(net "GND")
	)
	(segment
		(start 77.66685 -216.308686)
		(end 77.66685 -217.413586)
		(width 0.508)
		(layer "F.Cu")
		(net "GND")
	)
	(segment
		(start 183.105044 -138.83005)
		(end 184.912 -138.83005)
		(width 0.508)
		(layer "F.Cu")
		(net "GND")
	)
	(segment
		(start 453.574912 -40.975026)
		(end 451.854824 -40.975026)
		(width 0.508)
		(layer "F.Cu")
		(net "GND")
	)
	(segment
		(start 181.991 -276.225)
		(end 181.991 -277.241)
		(width 0.508)
		(layer "F.Cu")
		(net "GND")
	)
	(segment
		(start 448.904868 -23.830026)
		(end 450.711824 -23.830026)
		(width 0.508)
		(layer "F.Cu")
		(net "GND")
	)
	(segment
		(start 109.21365 -216.257886)
		(end 109.21365 -217.337386)
		(width 0.508)
		(layer "F.Cu")
		(net "GND")
	)
	(segment
		(start 40.252396 -360.5149)
		(end 40.252396 -359.66654)
		(width 0.508)
		(layer "F.Cu")
		(net "GND")
	)
	(segment
		(start 124.674884 -148.35505)
		(end 122.954796 -148.35505)
		(width 0.508)
		(layer "F.Cu")
		(net "GND")
	)
	(segment
		(start 475.1832 -246.5324)
		(end 475.1832 -247.1674)
		(width 0.4064)
		(layer "F.Cu")
		(net "GND")
	)
	(segment
		(start 244.91442 -217.33002)
		(end 244.9068 -217.3224)
		(width 0.3048)
		(layer "F.Cu")
		(net "GND")
	)
	(segment
		(start 483.300024 -237.035086)
		(end 485.182926 -237.035086)
		(width 0.508)
		(layer "F.Cu")
		(net "GND")
	)
	(segment
		(start 416.1028 -146.1897)
		(end 416.1028 -145.3388)
		(width 0.508)
		(layer "F.Cu")
		(net "GND")
	)
	(segment
		(start 176.403 -30.607)
		(end 176.403 -32.004)
		(width 0.508)
		(layer "F.Cu")
		(net "GND")
	)
	(segment
		(start 100.4316 -357.632)
		(end 102.1715 -357.632)
		(width 0.508)
		(layer "F.Cu")
		(net "GND")
	)
	(segment
		(start 25.355042 -253.830074)
		(end 27.161998 -253.830074)
		(width 0.508)
		(layer "F.Cu")
		(net "GND")
	)
	(segment
		(start 149.04847 -156.2608)
		(end 148.854922 -156.454348)
		(width 0.508)
		(layer "F.Cu")
		(net "GND")
	)
	(segment
		(start 82.5754 -33.782)
		(end 81.661 -33.782)
		(width 0.508)
		(layer "F.Cu")
		(net "GND")
	)
	(segment
		(start 462.7499 -8.128)
		(end 462.7499 -8.9916)
		(width 0.508)
		(layer "F.Cu")
		(net "GND")
	)
	(segment
		(start 426.974 -38.227)
		(end 428.371 -38.227)
		(width 0.508)
		(layer "F.Cu")
		(net "GND")
	)
	(segment
		(start 11.796268 -215.844628)
		(end 11.796268 -216.754202)
		(width 0.508)
		(layer "F.Cu")
		(net "GND")
	)
	(segment
		(start 332.105 -128.2065)
		(end 332.105 -127.381)
		(width 0.508)
		(layer "F.Cu")
		(net "GND")
	)
	(segment
		(start 40.8305 -5.3594)
		(end 40.8305 -5.2705)
		(width 0.508)
		(layer "F.Cu")
		(net "GND")
	)
	(segment
		(start 322.704968 -138.83005)
		(end 324.511924 -138.83005)
		(width 0.508)
		(layer "F.Cu")
		(net "GND")
	)
	(segment
		(start 124.674884 -153.43505)
		(end 123.299982 -153.43505)
		(width 0.508)
		(layer "F.Cu")
		(net "GND")
	)
	(segment
		(start 305.044348 -357.975408)
		(end 305.044348 -358.907842)
		(width 0.508)
		(layer "F.Cu")
		(net "GND")
	)
	(segment
		(start 36.94303 -360.84256)
		(end 35.512756 -360.84256)
		(width 0.254)
		(layer "F.Cu")
		(net "GND")
	)
	(segment
		(start 468.669878 -215.7095)
		(end 468.669878 -216.813892)
		(width 0.508)
		(layer "F.Cu")
		(net "GND")
	)
	(segment
		(start 477.75876 -7.4422)
		(end 477.012 -7.4422)
		(width 0.4064)
		(layer "F.Cu")
		(net "GND")
	)
	(segment
		(start 393.4206 -16.0782)
		(end 394.1953 -16.0782)
		(width 0.508)
		(layer "F.Cu")
		(net "GND")
	)
	(segment
		(start 36.273486 -364.40999)
		(end 36.899596 -364.40999)
		(width 0.508)
		(layer "F.Cu")
		(net "GND")
	)
	(segment
		(start 124.674884 -268.435074)
		(end 122.954796 -268.435074)
		(width 0.508)
		(layer "F.Cu")
		(net "GND")
	)
	(segment
		(start 327.375012 -243.035074)
		(end 325.654924 -243.035074)
		(width 0.508)
		(layer "F.Cu")
		(net "GND")
	)
	(segment
		(start 232.22204 -233.45648)
		(end 232.22204 -234.71505)
		(width 0.508)
		(layer "F.Cu")
		(net "GND")
	)
	(segment
		(start 390.474962 -40.975026)
		(end 387.815836 -40.975026)
		(width 0.508)
		(layer "F.Cu")
		(net "GND")
	)
	(segment
		(start 425.7802 -131.96824)
		(end 425.7802 -132.715)
		(width 0.4064)
		(layer "F.Cu")
		(net "GND")
	)
	(segment
		(start 310.919876 -215.7095)
		(end 310.919876 -214.634826)
		(width 0.508)
		(layer "F.Cu")
		(net "GND")
	)
	(segment
		(start 396.621 -45.9232)
		(end 396.621 -47.117)
		(width 0.508)
		(layer "F.Cu")
		(net "GND")
	)
	(segment
		(start 405.569928 -216.813892)
		(end 405.56942 -216.8144)
		(width 0.508)
		(layer "F.Cu")
		(net "GND")
	)
	(segment
		(start 322.704968 -136.430004)
		(end 324.511924 -136.430004)
		(width 0.508)
		(layer "F.Cu")
		(net "GND")
	)
	(segment
		(start 124.674884 -243.035074)
		(end 126.9492 -243.035074)
		(width 0.508)
		(layer "F.Cu")
		(net "GND")
	)
	(segment
		(start 222.4405 -221.996)
		(end 223.203262 -221.996)
		(width 0.508)
		(layer "F.Cu")
		(net "GND")
	)
	(segment
		(start 244.729 -312.3565)
		(end 244.729 -313.182)
		(width 0.508)
		(layer "F.Cu")
		(net "GND")
	)
	(segment
		(start 151.554942 -256.23012)
		(end 153.361898 -256.23012)
		(width 0.508)
		(layer "F.Cu")
		(net "GND")
	)
	(segment
		(start 51.0032 -148.717)
		(end 50.0888 -148.717)
		(width 0.508)
		(layer "F.Cu")
		(net "GND")
	)
	(segment
		(start 327.375012 -40.975026)
		(end 325.654924 -40.975026)
		(width 0.508)
		(layer "F.Cu")
		(net "GND")
	)
	(segment
		(start 440.487054 -118.03507)
		(end 440.487054 -119.011446)
		(width 0.508)
		(layer "F.Cu")
		(net "GND")
	)
	(segment
		(start 277.8506 -328.17435)
		(end 279.55875 -328.17435)
		(width 0.3048)
		(layer "F.Cu")
		(net "GND")
	)
	(segment
		(start 244.416834 -138.615674)
		(end 245.549674 -138.615674)
		(width 0.4064)
		(layer "F.Cu")
		(net "GND")
	)
	(segment
		(start 327.375012 -246.845074)
		(end 325.654924 -246.845074)
		(width 0.508)
		(layer "F.Cu")
		(net "GND")
	)
	(segment
		(start 422.025064 -153.43505)
		(end 420.304976 -153.43505)
		(width 0.508)
		(layer "F.Cu")
		(net "GND")
	)
	(segment
		(start 218.33586 -172.28058)
		(end 218.33586 -172.962316)
		(width 0.3556)
		(layer "F.Cu")
		(net "GND")
	)
	(segment
		(start 120.00484 -21.42998)
		(end 121.811796 -21.42998)
		(width 0.508)
		(layer "F.Cu")
		(net "GND")
	)
	(segment
		(start 237.363 -223.52)
		(end 237.363 -222.5675)
		(width 0.508)
		(layer "F.Cu")
		(net "GND")
	)
	(segment
		(start 245.8847 -303.149)
		(end 246.7102 -303.149)
		(width 0.508)
		(layer "F.Cu")
		(net "GND")
	)
	(segment
		(start 23.876 -156.2608)
		(end 22.606 -156.2608)
		(width 0.508)
		(layer "F.Cu")
		(net "GND")
	)
	(segment
		(start 358.925114 -13.035026)
		(end 357.205026 -13.035026)
		(width 0.508)
		(layer "F.Cu")
		(net "GND")
	)
	(segment
		(start 24.257 -46.228)
		(end 24.257 -47.244)
		(width 0.508)
		(layer "F.Cu")
		(net "GND")
	)
	(segment
		(start 55.0545 -249.555)
		(end 55.0545 -250.444)
		(width 0.508)
		(layer "F.Cu")
		(net "GND")
	)
	(segment
		(start 144.907 -146.939)
		(end 143.594074 -146.939)
		(width 0.508)
		(layer "F.Cu")
		(net "GND")
	)
	(segment
		(start 485.125014 -260.815074)
		(end 483.404926 -260.815074)
		(width 0.508)
		(layer "F.Cu")
		(net "GND")
	)
	(segment
		(start 417.35502 -251.430028)
		(end 419.161976 -251.430028)
		(width 0.508)
		(layer "F.Cu")
		(net "GND")
	)
	(segment
		(start 451.749922 -122.035062)
		(end 453.632824 -122.035062)
		(width 0.508)
		(layer "F.Cu")
		(net "GND")
	)
	(segment
		(start 422.025064 -246.845074)
		(end 420.304976 -246.845074)
		(width 0.508)
		(layer "F.Cu")
		(net "GND")
	)
	(segment
		(start 234.2134 -193.2305)
		(end 233.2736 -193.2305)
		(width 0.508)
		(layer "F.Cu")
		(net "GND")
	)
	(segment
		(start 61.574934 -20.655026)
		(end 59.854846 -20.655026)
		(width 0.508)
		(layer "F.Cu")
		(net "GND")
	)
	(segment
		(start 426.72 -243.1415)
		(end 426.72 -242.316)
		(width 0.508)
		(layer "F.Cu")
		(net "GND")
	)
	(segment
		(start 474.5228 -263.779)
		(end 473.583 -263.779)
		(width 0.508)
		(layer "F.Cu")
		(net "GND")
	)
	(segment
		(start 187.424568 -370.787676)
		(end 186.926728 -370.787676)
		(width 0.4064)
		(layer "F.Cu")
		(net "GND")
	)
	(segment
		(start 440.654186 -119.178578)
		(end 440.717686 -119.242078)
		(width 0.508)
		(layer "F.Cu")
		(net "GND")
	)
	(segment
		(start 393.954 -153.67)
		(end 392.938 -153.67)
		(width 0.508)
		(layer "F.Cu")
		(net "GND")
	)
	(segment
		(start 474.599 -148.717)
		(end 473.6338 -148.717)
		(width 0.508)
		(layer "F.Cu")
		(net "GND")
	)
	(segment
		(start 232.208832 -234.728258)
		(end 232.208832 -234.766866)
		(width 0.508)
		(layer "F.Cu")
		(net "GND")
	)
	(segment
		(start 364.5408 -245.60276)
		(end 364.5408 -244.856)
		(width 0.4064)
		(layer "F.Cu")
		(net "GND")
	)
	(segment
		(start 113.301018 -148.717)
		(end 113.168684 -148.849334)
		(width 0.508)
		(layer "F.Cu")
		(net "GND")
	)
	(segment
		(start 19.3802 -263.7536)
		(end 18.4404 -263.7536)
		(width 0.508)
		(layer "F.Cu")
		(net "GND")
	)
	(segment
		(start 354.25507 -26.230072)
		(end 356.062026 -26.230072)
		(width 0.508)
		(layer "F.Cu")
		(net "GND")
	)
	(segment
		(start 154.399996 -50.785014)
		(end 156.282898 -50.785014)
		(width 0.508)
		(layer "F.Cu")
		(net "GND")
	)
	(segment
		(start 61.574934 -270.975074)
		(end 59.854846 -270.975074)
		(width 0.508)
		(layer "F.Cu")
		(net "GND")
	)
	(segment
		(start 459.613 -160.9852)
		(end 459.613 -162.179)
		(width 0.508)
		(layer "F.Cu")
		(net "GND")
	)
	(segment
		(start 463.6897 -4.826)
		(end 464.1723 -5.3086)
		(width 0.508)
		(layer "F.Cu")
		(net "GND")
	)
	(segment
		(start 425.1452 -250.5202)
		(end 424.8912 -250.7742)
		(width 0.508)
		(layer "F.Cu")
		(net "GND")
	)
	(segment
		(start 128.8415 -374.523)
		(end 128.8415 -375.412)
		(width 0.508)
		(layer "F.Cu")
		(net "GND")
	)
	(segment
		(start 82.91576 -133.5532)
		(end 82.169 -133.5532)
		(width 0.4064)
		(layer "F.Cu")
		(net "GND")
	)
	(segment
		(start 56.90489 -141.230096)
		(end 58.711846 -141.230096)
		(width 0.508)
		(layer "F.Cu")
		(net "GND")
	)
	(segment
		(start 428.117 -275.9202)
		(end 428.117 -277.114)
		(width 0.508)
		(layer "F.Cu")
		(net "GND")
	)
	(segment
		(start 422.025064 -13.035026)
		(end 420.304976 -13.035026)
		(width 0.508)
		(layer "F.Cu")
		(net "GND")
	)
	(segment
		(start 428.117 -160.9852)
		(end 428.117 -162.179)
		(width 0.508)
		(layer "F.Cu")
		(net "GND")
	)
	(segment
		(start 320.261996 -376.2756)
		(end 319.642236 -375.65584)
		(width 0.4064)
		(layer "F.Cu")
		(net "GND")
	)
	(segment
		(start 456.946 -153.67)
		(end 455.93 -153.67)
		(width 0.508)
		(layer "F.Cu")
		(net "GND")
	)
	(segment
		(start 13.56995 -216.8144)
		(end 13.56995 -215.7095)
		(width 0.508)
		(layer "F.Cu")
		(net "GND")
	)
	(segment
		(start 477.9645 -20.701)
		(end 478.7138 -20.701)
		(width 0.508)
		(layer "F.Cu")
		(net "GND")
	)
	(segment
		(start 304.138076 -327.414382)
		(end 304.138076 -326.593962)
		(width 0.508)
		(layer "F.Cu")
		(net "GND")
	)
	(segment
		(start 385.804918 -21.42998)
		(end 387.611874 -21.42998)
		(width 0.508)
		(layer "F.Cu")
		(net "GND")
	)
	(segment
		(start 243.713 -312.3565)
		(end 243.713 -313.182)
		(width 0.508)
		(layer "F.Cu")
		(net "GND")
	)
	(segment
		(start 483.300024 -280.785062)
		(end 485.182926 -280.785062)
		(width 0.508)
		(layer "F.Cu")
		(net "GND")
	)
	(segment
		(start 284.000448 -347.096842)
		(end 284.000448 -346.271342)
		(width 0.508)
		(layer "F.Cu")
		(net "GND")
	)
	(segment
		(start 177.2158 -263.779)
		(end 176.276 -263.779)
		(width 0.508)
		(layer "F.Cu")
		(net "GND")
	)
	(segment
		(start 424.434 -276.098)
		(end 424.434 -277.114)
		(width 0.508)
		(layer "F.Cu")
		(net "GND")
	)
	(segment
		(start 254.141478 -227.34905)
		(end 253.477522 -227.34905)
		(width 0.4572)
		(layer "F.Cu")
		(net "GND")
	)
	(segment
		(start 183.105044 -253.830074)
		(end 184.912 -253.830074)
		(width 0.508)
		(layer "F.Cu")
		(net "GND")
	)
	(segment
		(start 150.495 -161.163)
		(end 150.495 -162.179)
		(width 0.508)
		(layer "F.Cu")
		(net "GND")
	)
	(segment
		(start 30.117796 -373.23776)
		(end 30.117796 -372.3386)
		(width 0.4064)
		(layer "F.Cu")
		(net "GND")
	)
	(segment
		(start 110.9345 -139.065)
		(end 110.9345 -139.954)
		(width 0.508)
		(layer "F.Cu")
		(net "GND")
	)
	(segment
		(start 340.696296 -100.844604)
		(end 340.696296 -101.754178)
		(width 0.508)
		(layer "F.Cu")
		(net "GND")
	)
	(segment
		(start 456.355704 -375.15546)
		(end 456.355704 -374.8405)
		(width 0.4064)
		(layer "F.Cu")
		(net "GND")
	)
	(segment
		(start 286.851344 -350.716342)
		(end 287.556448 -350.716342)
		(width 0.2032)
		(layer "F.Cu")
		(net "GND")
	)
	(segment
		(start 364.998 -160.9852)
		(end 364.998 -162.179)
		(width 0.508)
		(layer "F.Cu")
		(net "GND")
	)
	(segment
		(start 82.5246 -263.779)
		(end 81.5848 -263.779)
		(width 0.508)
		(layer "F.Cu")
		(net "GND")
	)
	(segment
		(start 402.907246 -97.390204)
		(end 402.907246 -96.310704)
		(width 0.508)
		(layer "F.Cu")
		(net "GND")
	)
	(segment
		(start 189.81166 -30.18028)
		(end 189.81166 -30.188662)
		(width 0.508)
		(layer "F.Cu")
		(net "GND")
	)
	(segment
		(start 56.90489 -251.430028)
		(end 58.711846 -251.430028)
		(width 0.508)
		(layer "F.Cu")
		(net "GND")
	)
	(segment
		(start 238.506 -226.3775)
		(end 238.8235 -226.06)
		(width 0.508)
		(layer "F.Cu")
		(net "GND")
	)
	(segment
		(start 52.578 -19.6215)
		(end 52.578 -20.447)
		(width 0.508)
		(layer "F.Cu")
		(net "GND")
	)
	(segment
		(start 261.75081 -224.340674)
		(end 261.75081 -223.90481)
		(width 0.508)
		(layer "F.Cu")
		(net "GND")
	)
	(segment
		(start 151.554942 -21.42998)
		(end 153.361898 -21.42998)
		(width 0.508)
		(layer "F.Cu")
		(net "GND")
	)
	(segment
		(start 327.375012 -153.43505)
		(end 325.654924 -153.43505)
		(width 0.508)
		(layer "F.Cu")
		(net "GND")
	)
	(segment
		(start 55.753 -161.163)
		(end 55.753 -162.179)
		(width 0.508)
		(layer "F.Cu")
		(net "GND")
	)
	(segment
		(start 251.4854 -210.7565)
		(end 251.476764 -210.747864)
		(width 0.508)
		(layer "F.Cu")
		(net "GND")
	)
	(segment
		(start 208.714594 -223.585024)
		(end 208.504282 -223.374712)
		(width 0.508)
		(layer "F.Cu")
		(net "GND")
	)
	(segment
		(start 327.375012 -33.355026)
		(end 325.654924 -33.355026)
		(width 0.508)
		(layer "F.Cu")
		(net "GND")
	)
	(segment
		(start 453.574912 -153.43505)
		(end 451.854824 -153.43505)
		(width 0.508)
		(layer "F.Cu")
		(net "GND")
	)
	(segment
		(start 454.717404 -371.4369)
		(end 454.717404 -370.4844)
		(width 0.508)
		(layer "F.Cu")
		(net "GND")
	)
	(segment
		(start 313.8424 -327.414382)
		(end 313.8424 -326.593962)
		(width 0.508)
		(layer "F.Cu")
		(net "GND")
	)
	(segment
		(start 32.4104 -31.1531)
		(end 32.4104 -30.3022)
		(width 0.508)
		(layer "F.Cu")
		(net "GND")
	)
	(segment
		(start 330.835 -153.67)
		(end 329.819 -153.67)
		(width 0.508)
		(layer "F.Cu")
		(net "GND")
	)
	(segment
		(start 395.224 -128.2065)
		(end 395.224 -127.381)
		(width 0.508)
		(layer "F.Cu")
		(net "GND")
	)
	(segment
		(start 209.330798 -223.585024)
		(end 208.714594 -223.585024)
		(width 0.508)
		(layer "F.Cu")
		(net "GND")
	)
	(segment
		(start 52.72024 -250.4948)
		(end 53.6448 -250.4948)
		(width 0.4064)
		(layer "F.Cu")
		(net "GND")
	)
	(segment
		(start 456.6666 -250.4948)
		(end 456.4126 -250.7488)
		(width 0.508)
		(layer "F.Cu")
		(net "GND")
	)
	(segment
		(start 86.995 -41.3258)
		(end 85.725 -41.3258)
		(width 0.508)
		(layer "F.Cu")
		(net "GND")
	)
	(segment
		(start 189.695328 -368.943636)
		(end 189.695328 -368.562636)
		(width 0.4064)
		(layer "F.Cu")
		(net "GND")
	)
	(segment
		(start 457.581 -160.9852)
		(end 457.581 -162.179)
		(width 0.508)
		(layer "F.Cu")
		(net "GND")
	)
	(segment
		(start 358.925114 -30.815026)
		(end 357.205026 -30.815026)
		(width 0.508)
		(layer "F.Cu")
		(net "GND")
	)
	(segment
		(start 181.4195 -368.2238)
		(end 182.2704 -368.2238)
		(width 0.508)
		(layer "F.Cu")
		(net "GND")
	)
	(segment
		(start 187.775088 -20.655026)
		(end 186.055 -20.655026)
		(width 0.508)
		(layer "F.Cu")
		(net "GND")
	)
	(segment
		(start 456.946 -268.605)
		(end 455.93 -268.605)
		(width 0.508)
		(layer "F.Cu")
		(net "GND")
	)
	(segment
		(start 208.59496 -167.43426)
		(end 208.59496 -167.802814)
		(width 0.508)
		(layer "F.Cu")
		(net "GND")
	)
	(segment
		(start 118.872 -161.163)
		(end 118.872 -162.179)
		(width 0.508)
		(layer "F.Cu")
		(net "GND")
	)
	(segment
		(start 58.674 -21.082)
		(end 58.674 -20.828)
		(width 0.508)
		(layer "F.Cu")
		(net "GND")
	)
	(segment
		(start 241.681 -312.3565)
		(end 241.681 -313.182)
		(width 0.508)
		(layer "F.Cu")
		(net "GND")
	)
	(segment
		(start 447.8782 -261.2009)
		(end 447.8782 -260.2992)
		(width 0.508)
		(layer "F.Cu")
		(net "GND")
	)
	(segment
		(start 13.7668 -35.687)
		(end 12.573 -35.687)
		(width 0.508)
		(layer "F.Cu")
		(net "GND")
	)
	(segment
		(start 448.904868 -136.430004)
		(end 448.904868 -135.565134)
		(width 0.508)
		(layer "F.Cu")
		(net "GND")
	)
	(segment
		(start 264.192258 -361.315)
		(end 264.192258 -362.331)
		(width 0.508)
		(layer "F.Cu")
		(net "GND")
	)
	(segment
		(start 304.519076 -341.257382)
		(end 304.519076 -342.077802)
		(width 0.508)
		(layer "F.Cu")
		(net "GND")
	)
	(segment
		(start 310.82742 -327.414382)
		(end 310.82742 -326.593962)
		(width 0.508)
		(layer "F.Cu")
		(net "GND")
	)
	(segment
		(start 257.800348 -227.34143)
		(end 257.811778 -227.33)
		(width 0.4572)
		(layer "F.Cu")
		(net "GND")
	)
	(segment
		(start 358.925114 -250.655074)
		(end 357.205026 -250.655074)
		(width 0.508)
		(layer "F.Cu")
		(net "GND")
	)
	(segment
		(start 56.90489 -23.830026)
		(end 58.711846 -23.830026)
		(width 0.508)
		(layer "F.Cu")
		(net "GND")
	)
	(segment
		(start 339.807296 -97.390204)
		(end 339.807296 -96.310704)
		(width 0.508)
		(layer "F.Cu")
		(net "GND")
	)
	(segment
		(start 458.47 -153.289)
		(end 459.867 -153.289)
		(width 0.508)
		(layer "F.Cu")
		(net "GND")
	)
	(segment
		(start 253.477522 -227.34905)
		(end 253.259082 -227.56749)
		(width 0.4572)
		(layer "F.Cu")
		(net "GND")
	)
	(segment
		(start 466.896196 -215.844628)
		(end 466.896196 -216.754202)
		(width 0.508)
		(layer "F.Cu")
		(net "GND")
	)
	(segment
		(start 333.0448 -245.60276)
		(end 333.0448 -244.856)
		(width 0.4064)
		(layer "F.Cu")
		(net "GND")
	)
	(segment
		(start 459.9178 -15.4813)
		(end 460.1718 -15.2273)
		(width 0.508)
		(layer "F.Cu")
		(net "GND")
	)
	(segment
		(start 483.300024 -122.035062)
		(end 485.182926 -122.035062)
		(width 0.508)
		(layer "F.Cu")
		(net "GND")
	)
	(segment
		(start 118.618 -271.3228)
		(end 117.348 -271.3228)
		(width 0.508)
		(layer "F.Cu")
		(net "GND")
	)
	(segment
		(start 259.490972 -373.54891)
		(end 259.541772 -373.59971)
		(width 0.508)
		(layer "F.Cu")
		(net "GND")
	)
	(segment
		(start 189.81166 -30.188662)
		(end 190.9445 -31.321502)
		(width 0.508)
		(layer "F.Cu")
		(net "GND")
	)
	(segment
		(start 331.089 -9.7155)
		(end 331.089 -8.89)
		(width 0.508)
		(layer "F.Cu")
		(net "GND")
	)
	(segment
		(start 440.717686 -119.242078)
		(end 440.717686 -120.321578)
		(width 0.508)
		(layer "F.Cu")
		(net "GND")
	)
	(segment
		(start 88.454992 -21.42998)
		(end 90.261948 -21.42998)
		(width 0.508)
		(layer "F.Cu")
		(net "GND")
	)
	(segment
		(start 371.357144 -97.390204)
		(end 371.357144 -96.310704)
		(width 0.508)
		(layer "F.Cu")
		(net "GND")
	)
	(segment
		(start 261.986522 -363.575346)
		(end 261.986522 -362.432346)
		(width 0.508)
		(layer "F.Cu")
		(net "GND")
	)
	(segment
		(start 480.45497 -136.430004)
		(end 482.261926 -136.430004)
		(width 0.508)
		(layer "F.Cu")
		(net "GND")
	)
	(segment
		(start 331.1652 -246.90324)
		(end 331.1652 -247.65)
		(width 0.4064)
		(layer "F.Cu")
		(net "GND")
	)
	(segment
		(start 406.649428 -101.49713)
		(end 406.649428 -102.413562)
		(width 0.508)
		(layer "F.Cu")
		(net "GND")
	)
	(segment
		(start 161.9885 -262.128)
		(end 161.9885 -261.239)
		(width 0.508)
		(layer "F.Cu")
		(net "GND")
	)
	(segment
		(start 238.9505 -225.933)
		(end 238.9505 -225.044)
		(width 0.508)
		(layer "F.Cu")
		(net "GND")
	)
	(segment
		(start 363.855 -38.227)
		(end 365.252 -38.227)
		(width 0.508)
		(layer "F.Cu")
		(net "GND")
	)
	(segment
		(start 464.1723 -6.3754)
		(end 463.7786 -6.3754)
		(width 0.508)
		(layer "F.Cu")
		(net "GND")
	)
	(segment
		(start 279.999948 -352.367342)
		(end 279.174448 -352.367342)
		(width 0.508)
		(layer "F.Cu")
		(net "GND")
	)
	(segment
		(start 308.257194 -212.390228)
		(end 308.257194 -211.310728)
		(width 0.508)
		(layer "F.Cu")
		(net "GND")
	)
	(segment
		(start 281.178 -337.185)
		(end 281.178 -336.169)
		(width 0.508)
		(layer "F.Cu")
		(net "GND")
	)
	(segment
		(start 427.5201 -20.574)
		(end 428.427134 -20.574)
		(width 0.508)
		(layer "F.Cu")
		(net "GND")
	)
	(segment
		(start 30.025086 -155.97505)
		(end 28.304998 -155.97505)
		(width 0.508)
		(layer "F.Cu")
		(net "GND")
	)
	(segment
		(start 394.589 -160.9852)
		(end 394.589 -162.179)
		(width 0.508)
		(layer "F.Cu")
		(net "GND")
	)
	(segment
		(start 76.8858 -150.622)
		(end 75.692 -150.622)
		(width 0.508)
		(layer "F.Cu")
		(net "GND")
	)
	(segment
		(start 479.5266 -9.78916)
		(end 479.5266 -10.4902)
		(width 0.4064)
		(layer "F.Cu")
		(net "GND")
	)
	(segment
		(start 187.775088 -16.845026)
		(end 186.055 -16.845026)
		(width 0.508)
		(layer "F.Cu")
		(net "GND")
	)
	(segment
		(start 384.9116 -261.2009)
		(end 384.9116 -260.35)
		(width 0.508)
		(layer "F.Cu")
		(net "GND")
	)
	(segment
		(start 120.00484 -253.830074)
		(end 121.811796 -253.830074)
		(width 0.508)
		(layer "F.Cu")
		(net "GND")
	)
	(segment
		(start 24.257 -276.225)
		(end 24.257 -277.241)
		(width 0.508)
		(layer "F.Cu")
		(net "GND")
	)
	(segment
		(start 245.393972 -135.665718)
		(end 244.377972 -135.665718)
		(width 0.508)
		(layer "F.Cu")
		(net "GND")
	)
	(segment
		(start 417.35502 -141.230096)
		(end 419.161976 -141.230096)
		(width 0.508)
		(layer "F.Cu")
		(net "GND")
	)
	(segment
		(start 108.3818 -150.622)
		(end 107.305094 -150.622)
		(width 0.508)
		(layer "F.Cu")
		(net "GND")
	)
	(segment
		(start 459.613 -275.9202)
		(end 459.613 -277.114)
		(width 0.508)
		(layer "F.Cu")
		(net "GND")
	)
	(segment
		(start 422.025064 -145.81505)
		(end 419.822122 -145.81505)
		(width 0.508)
		(layer "F.Cu")
		(net "GND")
	)
	(segment
		(start 134.239 -366.9284)
		(end 133.731 -366.9284)
		(width 0.508)
		(layer "F.Cu")
		(net "GND")
	)
	(segment
		(start 244.348 -214.8205)
		(end 244.348 -213.9696)
		(width 0.508)
		(layer "F.Cu")
		(net "GND")
	)
	(segment
		(start 124.674884 -33.355026)
		(end 122.954796 -33.355026)
		(width 0.508)
		(layer "F.Cu")
		(net "GND")
	)
	(segment
		(start 357.100124 -165.785038)
		(end 358.983026 -165.785038)
		(width 0.508)
		(layer "F.Cu")
		(net "GND")
	)
	(segment
		(start 208.90738 -248.33072)
		(end 208.90738 -249.29338)
		(width 0.508)
		(layer "F.Cu")
		(net "GND")
	)
	(segment
		(start 61.574934 -38.435026)
		(end 59.854846 -38.435026)
		(width 0.508)
		(layer "F.Cu")
		(net "GND")
	)
	(segment
		(start 312.5724 -327.414382)
		(end 312.5724 -326.593962)
		(width 0.508)
		(layer "F.Cu")
		(net "GND")
	)
	(segment
		(start 451.749922 -280.785062)
		(end 453.632824 -280.785062)
		(width 0.508)
		(layer "F.Cu")
		(net "GND")
	)
	(segment
		(start 61.574934 -16.845026)
		(end 59.854846 -16.845026)
		(width 0.508)
		(layer "F.Cu")
		(net "GND")
	)
	(segment
		(start 187.775088 -153.43505)
		(end 189.574424 -153.43505)
		(width 0.508)
		(layer "F.Cu")
		(net "GND")
	)
	(segment
		(start 364.5408 -130.66776)
		(end 364.5408 -129.921)
		(width 0.4064)
		(layer "F.Cu")
		(net "GND")
	)
	(segment
		(start 330.5937 -15.956534)
		(end 329.85837 -15.221204)
		(width 0.508)
		(layer "F.Cu")
		(net "GND")
	)
	(segment
		(start 203.04506 -244.48262)
		(end 202.400154 -244.48262)
		(width 0.3556)
		(layer "F.Cu")
		(net "GND")
	)
	(segment
		(start 171.5008 -150.622)
		(end 170.307 -150.622)
		(width 0.508)
		(layer "F.Cu")
		(net "GND")
	)
	(segment
		(start 331.47 -45.9232)
		(end 331.47 -47.117)
		(width 0.508)
		(layer "F.Cu")
		(net "GND")
	)
	(segment
		(start 108.3818 -35.687)
		(end 107.188 -35.687)
		(width 0.508)
		(layer "F.Cu")
		(net "GND")
	)
	(segment
		(start 426.72 -128.2065)
		(end 426.72 -127.381)
		(width 0.508)
		(layer "F.Cu")
		(net "GND")
	)
	(segment
		(start 320.78803 -100.804726)
		(end 320.78803 -101.7143)
		(width 0.508)
		(layer "F.Cu")
		(net "GND")
	)
	(segment
		(start 140.0048 -265.684)
		(end 138.811 -265.684)
		(width 0.508)
		(layer "F.Cu")
		(net "GND")
	)
	(segment
		(start 363.601 -128.2065)
		(end 363.601 -127.381)
		(width 0.508)
		(layer "F.Cu")
		(net "GND")
	)
	(segment
		(start 279.999948 -350.335342)
		(end 279.174448 -350.335342)
		(width 0.508)
		(layer "F.Cu")
		(net "GND")
	)
	(segment
		(start 93.125036 -145.81505)
		(end 94.779846 -145.81505)
		(width 0.508)
		(layer "F.Cu")
		(net "GND")
	)
	(segment
		(start 306.68976 -360.960416)
		(end 307.294026 -360.35615)
		(width 0.508)
		(layer "F.Cu")
		(net "GND")
	)
	(segment
		(start 394.462 -9.7155)
		(end 394.462 -8.89)
		(width 0.508)
		(layer "F.Cu")
		(net "GND")
	)
	(segment
		(start 474.1418 -131.17576)
		(end 474.1418 -130.2512)
		(width 0.4064)
		(layer "F.Cu")
		(net "GND")
	)
	(segment
		(start 358.925114 -260.815074)
		(end 357.205026 -260.815074)
		(width 0.508)
		(layer "F.Cu")
		(net "GND")
	)
	(segment
		(start 260.320282 -366.940846)
		(end 259.510022 -366.940846)
		(width 0.4064)
		(layer "F.Cu")
		(net "GND")
	)
	(segment
		(start 105.471468 -211.298028)
		(end 105.471468 -212.312504)
		(width 0.508)
		(layer "F.Cu")
		(net "GND")
	)
	(segment
		(start 333.502 -45.9232)
		(end 333.502 -47.117)
		(width 0.508)
		(layer "F.Cu")
		(net "GND")
	)
	(segment
		(start 458.298804 -376.047)
		(end 457.656184 -376.68962)
		(width 0.4064)
		(layer "F.Cu")
		(net "GND")
	)
	(segment
		(start 140.83665 -101.511354)
		(end 140.83665 -102.427786)
		(width 0.508)
		(layer "F.Cu")
		(net "GND")
	)
	(segment
		(start 213.676738 -239.37722)
		(end 213.681564 -239.372394)
		(width 0.508)
		(layer "F.Cu")
		(net "GND")
	)
	(segment
		(start 322.704968 -256.23012)
		(end 324.511924 -256.23012)
		(width 0.508)
		(layer "F.Cu")
		(net "GND")
	)
	(segment
		(start 94.779846 -145.81505)
		(end 95.062294 -145.532602)
		(width 0.508)
		(layer "F.Cu")
		(net "GND")
	)
	(segment
		(start 223.203262 -221.996)
		(end 223.31807 -221.881192)
		(width 0.508)
		(layer "F.Cu")
		(net "GND")
	)
	(segment
		(start 480.45497 -256.23012)
		(end 482.261926 -256.23012)
		(width 0.508)
		(layer "F.Cu")
		(net "GND")
	)
	(segment
		(start 137.094468 -97.404428)
		(end 137.094468 -96.324928)
		(width 0.508)
		(layer "F.Cu")
		(net "GND")
	)
	(segment
		(start 485.125014 -135.65505)
		(end 483.404926 -135.65505)
		(width 0.508)
		(layer "F.Cu")
		(net "GND")
	)
	(segment
		(start 93.125036 -260.815074)
		(end 91.404948 -260.815074)
		(width 0.508)
		(layer "F.Cu")
		(net "GND")
	)
	(segment
		(start 35.7505 -147.066)
		(end 35.7505 -146.177)
		(width 0.508)
		(layer "F.Cu")
		(net "GND")
	)
	(segment
		(start 402.907246 -212.390228)
		(end 402.907246 -211.310728)
		(width 0.508)
		(layer "F.Cu")
		(net "GND")
	)
	(segment
		(start 256.5273 -213.95944)
		(end 256.5273 -212.852)
		(width 0.508)
		(layer "F.Cu")
		(net "GND")
	)
	(segment
		(start 325.550022 -165.785038)
		(end 323.592444 -165.785038)
		(width 0.508)
		(layer "F.Cu")
		(net "GND")
	)
	(segment
		(start 425.8437 -135.6614)
		(end 425.2468 -135.6614)
		(width 0.508)
		(layer "F.Cu")
		(net "GND")
	)
	(segment
		(start 174.010066 -372.828566)
		(end 174.2059 -373.0244)
		(width 0.3048)
		(layer "F.Cu")
		(net "GND")
	)
	(segment
		(start 120.00484 -26.230072)
		(end 121.811796 -26.230072)
		(width 0.508)
		(layer "F.Cu")
		(net "GND")
	)
	(segment
		(start 93.125036 -33.355026)
		(end 91.404948 -33.355026)
		(width 0.508)
		(layer "F.Cu")
		(net "GND")
	)
	(segment
		(start 50.292 -260.604)
		(end 50.292 -262.001)
		(width 0.508)
		(layer "F.Cu")
		(net "GND")
	)
	(segment
		(start 437.119776 -215.7095)
		(end 437.119776 -216.813892)
		(width 0.508)
		(layer "F.Cu")
		(net "GND")
	)
	(segment
		(start 331.0509 -135.636)
		(end 330.2254 -135.636)
		(width 0.508)
		(layer "F.Cu")
		(net "GND")
	)
	(segment
		(start 480.45497 -26.230072)
		(end 482.261926 -26.230072)
		(width 0.508)
		(layer "F.Cu")
		(net "GND")
	)
	(segment
		(start 54.9275 -134.493)
		(end 54.9275 -135.382)
		(width 0.508)
		(layer "F.Cu")
		(net "GND")
	)
	(segment
		(start 48.79086 -118.310406)
		(end 48.623728 -118.143274)
		(width 0.508)
		(layer "F.Cu")
		(net "GND")
	)
	(segment
		(start 427.6598 -130.66776)
		(end 427.6598 -129.921)
		(width 0.4064)
		(layer "F.Cu")
		(net "GND")
	)
	(segment
		(start 395.224 -243.1415)
		(end 395.224 -242.316)
		(width 0.508)
		(layer "F.Cu")
		(net "GND")
	)
	(segment
		(start 145.669 -263.779)
		(end 144.7546 -263.779)
		(width 0.508)
		(layer "F.Cu")
		(net "GND")
	)
	(segment
		(start 235.41228 -309.63108)
		(end 235.839 -310.0578)
		(width 0.3556)
		(layer "F.Cu")
		(net "GND")
	)
	(segment
		(start 322.561712 -101.77399)
		(end 322.561204 -101.774498)
		(width 0.508)
		(layer "F.Cu")
		(net "GND")
	)
	(segment
		(start 185.736738 -122.035062)
		(end 184.0484 -123.7234)
		(width 0.508)
		(layer "F.Cu")
		(net "GND")
	)
	(segment
		(start 458.216 -243.1415)
		(end 458.216 -242.316)
		(width 0.508)
		(layer "F.Cu")
		(net "GND")
	)
	(segment
		(start 30.025086 -260.815074)
		(end 28.304998 -260.815074)
		(width 0.508)
		(layer "F.Cu")
		(net "GND")
	)
	(segment
		(start 181.1655 -249.555)
		(end 181.1655 -250.444)
		(width 0.508)
		(layer "F.Cu")
		(net "GND")
	)
	(segment
		(start 48.85436 -119.453406)
		(end 48.405796 -119.90197)
		(width 0.508)
		(layer "F.Cu")
		(net "GND")
	)
	(segment
		(start 24.257 -161.163)
		(end 24.257 -162.179)
		(width 0.508)
		(layer "F.Cu")
		(net "GND")
	)
	(segment
		(start 358.925114 -131.84505)
		(end 357.205026 -131.84505)
		(width 0.508)
		(layer "F.Cu")
		(net "GND")
	)
	(segment
		(start 114.0714 -33.782)
		(end 113.157 -33.782)
		(width 0.508)
		(layer "F.Cu")
		(net "GND")
	)
	(segment
		(start 422.025064 -243.035074)
		(end 420.304976 -243.035074)
		(width 0.508)
		(layer "F.Cu")
		(net "GND")
	)
	(segment
		(start 422.025064 -268.435074)
		(end 420.304976 -268.435074)
		(width 0.508)
		(layer "F.Cu")
		(net "GND")
	)
	(segment
		(start 222.56877 -207.339692)
		(end 222.56877 -208.025492)
		(width 0.508)
		(layer "F.Cu")
		(net "GND")
	)
	(segment
		(start 25.355042 -138.83005)
		(end 27.161998 -138.83005)
		(width 0.508)
		(layer "F.Cu")
		(net "GND")
	)
	(segment
		(start 149.6695 -19.558)
		(end 149.6695 -20.447)
		(width 0.508)
		(layer "F.Cu")
		(net "GND")
	)
	(segment
		(start 396.1638 -130.66776)
		(end 396.1638 -129.921)
		(width 0.4064)
		(layer "F.Cu")
		(net "GND")
	)
	(segment
		(start 459.613 -45.9232)
		(end 459.613 -47.117)
		(width 0.508)
		(layer "F.Cu")
		(net "GND")
	)
	(segment
		(start 310.918352 -214.633302)
		(end 310.918352 -214.6046)
		(width 0.508)
		(layer "F.Cu")
		(net "GND")
	)
	(segment
		(start 358.925114 -243.035074)
		(end 357.205026 -243.035074)
		(width 0.508)
		(layer "F.Cu")
		(net "GND")
	)
	(segment
		(start 372.246144 -101.754178)
		(end 372.25097 -101.759004)
		(width 0.508)
		(layer "F.Cu")
		(net "GND")
	)
	(segment
		(start 340.696296 -216.754202)
		(end 340.701122 -216.759028)
		(width 0.508)
		(layer "F.Cu")
		(net "GND")
	)
	(segment
		(start 417.35502 -138.83005)
		(end 419.161976 -138.83005)
		(width 0.508)
		(layer "F.Cu")
		(net "GND")
	)
	(segment
		(start 213.99246 -162.98926)
		(end 214.90432 -162.98926)
		(width 0.508)
		(layer "F.Cu")
		(net "GND")
	)
	(segment
		(start 147.33524 -20.4978)
		(end 148.2598 -20.4978)
		(width 0.4064)
		(layer "F.Cu")
		(net "GND")
	)
	(segment
		(start 207.89138 -234.74172)
		(end 207.88884 -234.73918)
		(width 0.508)
		(layer "F.Cu")
		(net "GND")
	)
	(segment
		(start 393.319 -15.9766)
		(end 393.4206 -16.0782)
		(width 0.508)
		(layer "F.Cu")
		(net "GND")
	)
	(segment
		(start 30.025086 -30.815026)
		(end 28.304998 -30.815026)
		(width 0.508)
		(layer "F.Cu")
		(net "GND")
	)
	(segment
		(start 114.1476 -148.717)
		(end 113.301018 -148.717)
		(width 0.508)
		(layer "F.Cu")
		(net "GND")
	)
	(segment
		(start 183.105044 -136.430004)
		(end 184.912 -136.430004)
		(width 0.508)
		(layer "F.Cu")
		(net "GND")
	)
	(segment
		(start 150.495 -46.228)
		(end 150.495 -47.244)
		(width 0.508)
		(layer "F.Cu")
		(net "GND")
	)
	(segment
		(start 187.790328 -371.407436)
		(end 187.790328 -371.153436)
		(width 0.4064)
		(layer "F.Cu")
		(net "GND")
	)
	(segment
		(start 457.581 -275.9202)
		(end 457.581 -277.114)
		(width 0.508)
		(layer "F.Cu")
		(net "GND")
	)
	(segment
		(start 154.399996 -165.785038)
		(end 156.282898 -165.785038)
		(width 0.508)
		(layer "F.Cu")
		(net "GND")
	)
	(segment
		(start 207.82661 -208.026)
		(end 207.82534 -208.02727)
		(width 0.508)
		(layer "F.Cu")
		(net "GND")
	)
	(segment
		(start 45.2628 -35.687)
		(end 44.069 -35.687)
		(width 0.508)
		(layer "F.Cu")
		(net "GND")
	)
	(segment
		(start 122.849894 -237.035086)
		(end 122.849894 -235.121704)
		(width 0.508)
		(layer "F.Cu")
		(net "GND")
	)
	(segment
		(start 86.5505 -134.493)
		(end 86.5505 -135.382)
		(width 0.508)
		(layer "F.Cu")
		(net "GND")
	)
	(segment
		(start 210.93938 -248.33072)
		(end 210.93938 -249.43562)
		(width 0.508)
		(layer "F.Cu")
		(net "GND")
	)
	(segment
		(start 459.616302 -230.63835)
		(end 459.167738 -231.086914)
		(width 0.508)
		(layer "F.Cu")
		(net "GND")
	)
	(segment
		(start 133.731 -366.9284)
		(end 133.3373 -367.3221)
		(width 0.508)
		(layer "F.Cu")
		(net "GND")
	)
	(segment
		(start 151.554942 -23.830026)
		(end 153.361898 -23.830026)
		(width 0.508)
		(layer "F.Cu")
		(net "GND")
	)
	(segment
		(start 474.1418 -246.23776)
		(end 474.88856 -246.23776)
		(width 0.4064)
		(layer "F.Cu")
		(net "GND")
	)
	(segment
		(start 324.781672 -21.42998)
		(end 324.789292 -21.42236)
		(width 0.4572)
		(layer "F.Cu")
		(net "GND")
	)
	(segment
		(start 189.151768 -369.487196)
		(end 189.695328 -368.943636)
		(width 0.4064)
		(layer "F.Cu")
		(net "GND")
	)
	(segment
		(start 480.45497 -251.430028)
		(end 482.261926 -251.430028)
		(width 0.508)
		(layer "F.Cu")
		(net "GND")
	)
	(segment
		(start 327.375012 -155.97505)
		(end 325.654924 -155.97505)
		(width 0.508)
		(layer "F.Cu")
		(net "GND")
	)
	(segment
		(start 299.392848 -349.746062)
		(end 299.392848 -348.633542)
		(width 0.3556)
		(layer "F.Cu")
		(net "GND")
	)
	(segment
		(start 474.5736 -33.655)
		(end 473.6592 -33.655)
		(width 0.508)
		(layer "F.Cu")
		(net "GND")
	)
	(segment
		(start 50.165 -30.607)
		(end 50.165 -32.004)
		(width 0.508)
		(layer "F.Cu")
		(net "GND")
	)
	(segment
		(start 151.554942 -26.230072)
		(end 153.361898 -26.230072)
		(width 0.508)
		(layer "F.Cu")
		(net "GND")
	)
	(segment
		(start 473.71 -31.877)
		(end 473.71 -31.578296)
		(width 0.508)
		(layer "F.Cu")
		(net "GND")
	)
	(segment
		(start 59.749944 -122.035062)
		(end 61.632846 -122.035062)
		(width 0.508)
		(layer "F.Cu")
		(net "GND")
	)
	(segment
		(start 228.96449 -354.673662)
		(end 228.96449 -356.157784)
		(width 0.508)
		(layer "F.Cu")
		(net "GND")
	)
	(segment
		(start 385.804918 -23.830026)
		(end 387.611874 -23.830026)
		(width 0.508)
		(layer "F.Cu")
		(net "GND")
	)
	(segment
		(start 422.025064 -30.815026)
		(end 420.304976 -30.815026)
		(width 0.508)
		(layer "F.Cu")
		(net "GND")
	)
	(segment
		(start 304.049176 -233.195114)
		(end 304.895504 -233.195114)
		(width 0.508)
		(layer "F.Cu")
		(net "GND")
	)
	(segment
		(start 428.427134 -20.574)
		(end 428.42942 -20.571714)
		(width 0.508)
		(layer "F.Cu")
		(net "GND")
	)
	(segment
		(start 221.1197 -196.723)
		(end 222.123 -196.723)
		(width 0.508)
		(layer "F.Cu")
		(net "GND")
	)
	(segment
		(start 448.904868 -253.830074)
		(end 450.711824 -253.830074)
		(width 0.508)
		(layer "F.Cu")
		(net "GND")
	)
	(segment
		(start 478.9932 -156.2608)
		(end 477.647 -156.2608)
		(width 0.508)
		(layer "F.Cu")
		(net "GND")
	)
	(segment
		(start 395.478 -38.227)
		(end 396.875 -38.227)
		(width 0.508)
		(layer "F.Cu")
		(net "GND")
	)
	(segment
		(start 388.452614 -50.785014)
		(end 386.8674 -49.1998)
		(width 0.508)
		(layer "F.Cu")
		(net "GND")
	)
	(segment
		(start 485.125014 -20.655026)
		(end 483.404926 -20.655026)
		(width 0.508)
		(layer "F.Cu")
		(net "GND")
	)
	(segment
		(start 169.32275 -216.7636)
		(end 169.32275 -215.6587)
		(width 0.508)
		(layer "F.Cu")
		(net "GND")
	)
	(segment
		(start 176.7205 -20.955)
		(end 177.673 -20.955)
		(width 0.508)
		(layer "F.Cu")
		(net "GND")
	)
	(segment
		(start 33.688528 -363.0041)
		(end 33.310322 -362.625894)
		(width 0.508)
		(layer "F.Cu")
		(net "GND")
	)
	(segment
		(start 252.10008 -369.462812)
		(end 252.102112 -369.464844)
		(width 0.3048)
		(layer "F.Cu")
		(net "GND")
	)
	(segment
		(start 390.474962 -260.815074)
		(end 388.754874 -260.815074)
		(width 0.508)
		(layer "F.Cu")
		(net "GND")
	)
	(segment
		(start 245.745 -312.3565)
		(end 245.745 -313.182)
		(width 0.508)
		(layer "F.Cu")
		(net "GND")
	)
	(segment
		(start 453.574912 -131.84505)
		(end 451.854824 -131.84505)
		(width 0.508)
		(layer "F.Cu")
		(net "GND")
	)
	(segment
		(start 244.945662 -195.58254)
		(end 245.582694 -196.219572)
		(width 0.508)
		(layer "F.Cu")
		(net "GND")
	)
	(segment
		(start 23.942802 -229.49535)
		(end 23.77567 -229.328218)
		(width 0.508)
		(layer "F.Cu")
		(net "GND")
	)
	(segment
		(start 390.474962 -20.655026)
		(end 388.754874 -20.655026)
		(width 0.508)
		(layer "F.Cu")
		(net "GND")
	)
	(segment
		(start 88.454992 -136.430004)
		(end 90.261948 -136.430004)
		(width 0.508)
		(layer "F.Cu")
		(net "GND")
	)
	(segment
		(start 425.7421 -250.5202)
		(end 425.1452 -250.5202)
		(width 0.508)
		(layer "F.Cu")
		(net "GND")
	)
	(segment
		(start 342.469978 -216.813892)
		(end 342.46947 -216.8144)
		(width 0.508)
		(layer "F.Cu")
		(net "GND")
	)
	(segment
		(start 485.125014 -40.975026)
		(end 483.404926 -40.975026)
		(width 0.508)
		(layer "F.Cu")
		(net "GND")
	)
	(segment
		(start 186.748928 -366.670336)
		(end 186.748928 -365.590836)
		(width 0.508)
		(layer "F.Cu")
		(net "GND")
	)
	(segment
		(start 21.09724 -135.4328)
		(end 22.0218 -135.4328)
		(width 0.4064)
		(layer "F.Cu")
		(net "GND")
	)
	(segment
		(start 468.8078 -265.684)
		(end 467.614 -265.684)
		(width 0.508)
		(layer "F.Cu")
		(net "GND")
	)
	(segment
		(start 469.749378 -216.497154)
		(end 469.749378 -217.413586)
		(width 0.508)
		(layer "F.Cu")
		(net "GND")
	)
	(segment
		(start 61.574934 -40.975026)
		(end 59.854846 -40.975026)
		(width 0.508)
		(layer "F.Cu")
		(net "GND")
	)
	(segment
		(start 39.753286 -364.5535)
		(end 39.795196 -364.51159)
		(width 0.508)
		(layer "F.Cu")
		(net "GND")
	)
	(segment
		(start 77.66685 -102.427786)
		(end 77.66685 -101.322886)
		(width 0.508)
		(layer "F.Cu")
		(net "GND")
	)
	(segment
		(start 91.300046 -237.035086)
		(end 91.300046 -235.064554)
		(width 0.508)
		(layer "F.Cu")
		(net "GND")
	)
	(segment
		(start 191.2747 -262.128)
		(end 191.2747 -261.239)
		(width 0.508)
		(layer "F.Cu")
		(net "GND")
	)
	(segment
		(start 238.506 -227.076)
		(end 238.506 -226.3775)
		(width 0.508)
		(layer "F.Cu")
		(net "GND")
	)
	(segment
		(start 354.25507 -256.23012)
		(end 356.062026 -256.23012)
		(width 0.508)
		(layer "F.Cu")
		(net "GND")
	)
	(segment
		(start 460.27975 -100.7999)
		(end 460.27975 -101.904292)
		(width 0.508)
		(layer "F.Cu")
		(net "GND")
	)
	(segment
		(start 374.019826 -215.7095)
		(end 374.019826 -216.813892)
		(width 0.508)
		(layer "F.Cu")
		(net "GND")
	)
	(segment
		(start 93.125036 -30.815026)
		(end 91.35872 -30.815026)
		(width 0.508)
		(layer "F.Cu")
		(net "GND")
	)
	(segment
		(start 363.855 -268.224)
		(end 365.252 -268.224)
		(width 0.508)
		(layer "F.Cu")
		(net "GND")
	)
	(segment
		(start 30.025086 -270.975074)
		(end 28.304998 -270.975074)
		(width 0.508)
		(layer "F.Cu")
		(net "GND")
	)
	(segment
		(start 93.125036 -270.975074)
		(end 91.404948 -270.975074)
		(width 0.508)
		(layer "F.Cu")
		(net "GND")
	)
	(segment
		(start 233.26852 -233.467656)
		(end 233.26852 -234.504738)
		(width 0.508)
		(layer "F.Cu")
		(net "GND")
	)
	(segment
		(start 166.177468 -100.782628)
		(end 166.177468 -101.692202)
		(width 0.508)
		(layer "F.Cu")
		(net "GND")
	)
	(segment
		(start 240.6904 -202.66152)
		(end 239.79632 -202.66152)
		(width 0.3556)
		(layer "F.Cu")
		(net "GND")
	)
	(segment
		(start 425.45 -268.605)
		(end 424.434 -268.605)
		(width 0.508)
		(layer "F.Cu")
		(net "GND")
	)
	(segment
		(start 93.125036 -153.43505)
		(end 91.404948 -153.43505)
		(width 0.508)
		(layer "F.Cu")
		(net "GND")
	)
	(segment
		(start 212.97138 -239.37722)
		(end 213.676738 -239.37722)
		(width 0.508)
		(layer "F.Cu")
		(net "GND")
	)
	(segment
		(start 426.974 -153.289)
		(end 428.371 -153.289)
		(width 0.508)
		(layer "F.Cu")
		(net "GND")
	)
	(segment
		(start 485.125014 -246.845074)
		(end 483.404926 -246.845074)
		(width 0.508)
		(layer "F.Cu")
		(net "GND")
	)
	(segment
		(start 485.125014 -13.035026)
		(end 483.404926 -13.035026)
		(width 0.508)
		(layer "F.Cu")
		(net "GND")
	)
	(segment
		(start 207.82534 -208.02727)
		(end 207.813148 -208.02727)
		(width 0.508)
		(layer "F.Cu")
		(net "GND")
	)
	(segment
		(start 238.8235 -226.06)
		(end 238.9505 -225.933)
		(width 0.508)
		(layer "F.Cu")
		(net "GND")
	)
	(segment
		(start 374.019826 -101.813868)
		(end 374.019318 -101.814376)
		(width 0.508)
		(layer "F.Cu")
		(net "GND")
	)
	(segment
		(start 179.7558 -15.98676)
		(end 180.848 -15.98676)
		(width 0.3048)
		(layer "F.Cu")
		(net "GND")
	)
	(segment
		(start 156.224986 -270.975074)
		(end 154.504898 -270.975074)
		(width 0.508)
		(layer "F.Cu")
		(net "GND")
	)
	(segment
		(start 333.502 -163.347654)
		(end 333.495142 -163.354512)
		(width 0.508)
		(layer "F.Cu")
		(net "GND")
	)
	(segment
		(start 310.919876 -214.634826)
		(end 310.918352 -214.633302)
		(width 0.508)
		(layer "F.Cu")
		(net "GND")
	)
	(segment
		(start 361.8738 -135.6106)
		(end 361.7976 -135.6868)
		(width 0.508)
		(layer "F.Cu")
		(net "GND")
	)
	(segment
		(start 358.925114 -263.355074)
		(end 357.205026 -263.355074)
		(width 0.508)
		(layer "F.Cu")
		(net "GND")
	)
	(segment
		(start 457.656184 -376.68962)
		(end 457.656184 -377.03506)
		(width 0.4064)
		(layer "F.Cu")
		(net "GND")
	)
	(segment
		(start 447.9544 -31.2039)
		(end 447.9544 -30.3276)
		(width 0.508)
		(layer "F.Cu")
		(net "GND")
	)
	(segment
		(start 91.371674 -243.035074)
		(end 91.1352 -242.7986)
		(width 0.508)
		(layer "F.Cu")
		(net "GND")
	)
	(segment
		(start 342.469978 -215.7095)
		(end 342.469978 -216.813892)
		(width 0.508)
		(layer "F.Cu")
		(net "GND")
	)
	(segment
		(start 440.269122 -120.770142)
		(end 440.717686 -120.321578)
		(width 0.508)
		(layer "F.Cu")
		(net "GND")
	)
	(segment
		(start 363.601 -243.1415)
		(end 363.601 -242.316)
		(width 0.508)
		(layer "F.Cu")
		(net "GND")
	)
	(segment
		(start 74.813668 -216.754202)
		(end 74.818494 -216.759028)
		(width 0.508)
		(layer "F.Cu")
		(net "GND")
	)
	(segment
		(start 257.458972 -373.54891)
		(end 257.408172 -373.59971)
		(width 0.508)
		(layer "F.Cu")
		(net "GND")
	)
	(segment
		(start 426.085 -160.9852)
		(end 426.085 -162.179)
		(width 0.508)
		(layer "F.Cu")
		(net "GND")
	)
	(segment
		(start 24.006302 -229.55885)
		(end 23.942802 -229.49535)
		(width 0.508)
		(layer "F.Cu")
		(net "GND")
	)
	(segment
		(start 323.141594 -146.1897)
		(end 323.141594 -146.19605)
		(width 0.508)
		(layer "F.Cu")
		(net "GND")
	)
	(segment
		(start 309.146194 -214.935816)
		(end 309.140606 -214.930228)
		(width 0.508)
		(layer "F.Cu")
		(net "GND")
	)
	(segment
		(start 390.474962 -131.84505)
		(end 388.754874 -131.84505)
		(width 0.508)
		(layer "F.Cu")
		(net "GND")
	)
	(segment
		(start 187.775088 -155.97505)
		(end 189.454282 -155.97505)
		(width 0.508)
		(layer "F.Cu")
		(net "GND")
	)
	(segment
		(start 390.474962 -270.975074)
		(end 388.754874 -270.975074)
		(width 0.508)
		(layer "F.Cu")
		(net "GND")
	)
	(segment
		(start 256.928874 -228.36505)
		(end 257.760978 -228.36505)
		(width 0.4572)
		(layer "F.Cu")
		(net "GND")
	)
	(segment
		(start 390.474962 -243.035074)
		(end 388.754874 -243.035074)
		(width 0.508)
		(layer "F.Cu")
		(net "GND")
	)
	(segment
		(start 48.405796 -119.90197)
		(end 47.991014 -119.90197)
		(width 0.508)
		(layer "F.Cu")
		(net "GND")
	)
	(segment
		(start 451.749922 -50.785014)
		(end 453.632824 -50.785014)
		(width 0.508)
		(layer "F.Cu")
		(net "GND")
	)
	(segment
		(start 244.82298 -195.58254)
		(end 244.945662 -195.58254)
		(width 0.508)
		(layer "F.Cu")
		(net "GND")
	)
	(segment
		(start 222.526606 -226.568)
		(end 222.710248 -226.384358)
		(width 0.508)
		(layer "F.Cu")
		(net "GND")
	)
	(segment
		(start 23.4315 -249.555)
		(end 23.4315 -250.444)
		(width 0.508)
		(layer "F.Cu")
		(net "GND")
	)
	(segment
		(start 448.098672 -102.188772)
		(end 448.098672 -102.997254)
		(width 0.508)
		(layer "F.Cu")
		(net "GND")
	)
	(segment
		(start 372.246144 -100.844604)
		(end 372.246144 -101.754178)
		(width 0.508)
		(layer "F.Cu")
		(net "GND")
	)
	(segment
		(start 30.025086 -40.975026)
		(end 28.304998 -40.975026)
		(width 0.508)
		(layer "F.Cu")
		(net "GND")
	)
	(segment
		(start 304.877724 -231.732074)
		(end 304.885598 -231.7242)
		(width 0.508)
		(layer "F.Cu")
		(net "GND")
	)
	(segment
		(start 30.025086 -246.845074)
		(end 28.304998 -246.845074)
		(width 0.508)
		(layer "F.Cu")
		(net "GND")
	)
	(segment
		(start 58.32602 -21.42998)
		(end 58.674 -21.082)
		(width 0.508)
		(layer "F.Cu")
		(net "GND")
	)
	(segment
		(start 167.95115 -101.787452)
		(end 167.95115 -100.6729)
		(width 0.508)
		(layer "F.Cu")
		(net "GND")
	)
	(segment
		(start 427.6598 -15.60576)
		(end 427.6598 -14.859)
		(width 0.4064)
		(layer "F.Cu")
		(net "GND")
	)
	(segment
		(start 456.0824 -11.4046)
		(end 456.524614 -10.962386)
		(width 0.3048)
		(layer "F.Cu")
		(net "GND")
	)
	(segment
		(start 181.8259 -374.8532)
		(end 183.1594 -374.8532)
		(width 0.508)
		(layer "F.Cu")
		(net "GND")
	)
	(segment
		(start 417.35502 -21.42998)
		(end 419.161976 -21.42998)
		(width 0.508)
		(layer "F.Cu")
		(net "GND")
	)
	(segment
		(start 108.3818 -265.684)
		(end 107.188 -265.684)
		(width 0.508)
		(layer "F.Cu")
		(net "GND")
	)
	(segment
		(start 390.525 -166.243)
		(end 390.067038 -165.785038)
		(width 0.508)
		(layer "F.Cu")
		(net "GND")
	)
	(segment
		(start 170.40225 -216.257886)
		(end 170.40225 -217.337386)
		(width 0.508)
		(layer "F.Cu")
		(net "GND")
	)
	(segment
		(start 330.2254 -135.636)
		(end 330.1746 -135.6868)
		(width 0.508)
		(layer "F.Cu")
		(net "GND")
	)
	(segment
		(start 254.127254 -282.320746)
		(end 254.428498 -282.320746)
		(width 0.508)
		(layer "F.Cu")
		(net "GND")
	)
	(segment
		(start 206.8957 -197.231)
		(end 205.9178 -197.231)
		(width 0.508)
		(layer "F.Cu")
		(net "GND")
	)
	(segment
		(start 61.574934 -153.43505)
		(end 59.854846 -153.43505)
		(width 0.508)
		(layer "F.Cu")
		(net "GND")
	)
	(segment
		(start 93.125036 -268.435074)
		(end 91.404948 -268.435074)
		(width 0.508)
		(layer "F.Cu")
		(net "GND")
	)
	(segment
		(start 485.125014 -145.81505)
		(end 483.404926 -145.81505)
		(width 0.508)
		(layer "F.Cu")
		(net "GND")
	)
	(segment
		(start 154.399996 -280.785062)
		(end 156.282898 -280.785062)
		(width 0.508)
		(layer "F.Cu")
		(net "GND")
	)
	(segment
		(start 133.2865 -372.618)
		(end 133.155944 -372.487444)
		(width 0.508)
		(layer "F.Cu")
		(net "GND")
	)
	(segment
		(start 447.018664 -100.659438)
		(end 447.015616 -100.662486)
		(width 0.508)
		(layer "F.Cu")
		(net "GND")
	)
	(segment
		(start 184.476644 -21.42998)
		(end 185.217054 -22.17039)
		(width 0.508)
		(layer "F.Cu")
		(net "GND")
	)
	(segment
		(start 354.25507 -251.430028)
		(end 356.062026 -251.430028)
		(width 0.508)
		(layer "F.Cu")
		(net "GND")
	)
	(segment
		(start 184.813956 -23.833836)
		(end 184.819544 -23.833836)
		(width 0.508)
		(layer "F.Cu")
		(net "GND")
	)
	(segment
		(start 35.512756 -360.84256)
		(end 35.502596 -360.8324)
		(width 0.254)
		(layer "F.Cu")
		(net "GND")
	)
	(segment
		(start 133.155944 -372.487444)
		(end 133.155944 -371.772688)
		(width 0.508)
		(layer "F.Cu")
		(net "GND")
	)
	(segment
		(start 214.90432 -162.98926)
		(end 215.1253 -162.76828)
		(width 0.508)
		(layer "F.Cu")
		(net "GND")
	)
	(segment
		(start 322.704968 -251.430028)
		(end 324.511924 -251.430028)
		(width 0.508)
		(layer "F.Cu")
		(net "GND")
	)
	(segment
		(start 422.025064 -128.03505)
		(end 420.304976 -128.03505)
		(width 0.508)
		(layer "F.Cu")
		(net "GND")
	)
	(segment
		(start 130.3655 -147.066)
		(end 130.3655 -145.860008)
		(width 0.508)
		(layer "F.Cu")
		(net "GND")
	)
	(segment
		(start 252.10008 -368.592354)
		(end 252.10008 -369.462812)
		(width 0.3048)
		(layer "F.Cu")
		(net "GND")
	)
	(segment
		(start 48.092868 -97.328228)
		(end 48.092868 -96.248728)
		(width 0.508)
		(layer "F.Cu")
		(net "GND")
	)
	(segment
		(start 385.804918 -253.830074)
		(end 387.611874 -253.830074)
		(width 0.508)
		(layer "F.Cu")
		(net "GND")
	)
	(segment
		(start 457.653644 -369.37696)
		(end 458.070204 -368.9604)
		(width 0.4064)
		(layer "F.Cu")
		(net "GND")
	)
	(segment
		(start 479.298 -46.101)
		(end 478.282 -46.101)
		(width 0.508)
		(layer "F.Cu")
		(net "GND")
	)
	(segment
		(start 327.375012 -13.035026)
		(end 325.654924 -13.035026)
		(width 0.508)
		(layer "F.Cu")
		(net "GND")
	)
	(segment
		(start 485.125014 -243.035074)
		(end 483.404926 -243.035074)
		(width 0.508)
		(layer "F.Cu")
		(net "GND")
	)
	(segment
		(start 213.681564 -239.372394)
		(end 213.93658 -239.372394)
		(width 0.508)
		(layer "F.Cu")
		(net "GND")
	)
	(segment
		(start 420.200074 -50.785014)
		(end 422.082976 -50.785014)
		(width 0.508)
		(layer "F.Cu")
		(net "GND")
	)
	(segment
		(start 183.105044 -141.230096)
		(end 184.912 -141.230096)
		(width 0.508)
		(layer "F.Cu")
		(net "GND")
	)
	(segment
		(start 187.775088 -148.35505)
		(end 186.055 -148.35505)
		(width 0.508)
		(layer "F.Cu")
		(net "GND")
	)
	(segment
		(start 187.775088 -38.435026)
		(end 186.055 -38.435026)
		(width 0.508)
		(layer "F.Cu")
		(net "GND")
	)
	(segment
		(start 88.454992 -251.430028)
		(end 90.261948 -251.430028)
		(width 0.508)
		(layer "F.Cu")
		(net "GND")
	)
	(segment
		(start 246.7102 -303.149)
		(end 246.8118 -303.0474)
		(width 0.508)
		(layer "F.Cu")
		(net "GND")
	)
	(segment
		(start 30.025086 -268.435074)
		(end 28.304998 -268.435074)
		(width 0.508)
		(layer "F.Cu")
		(net "GND")
	)
	(segment
		(start 28.200096 -237.035086)
		(end 30.082998 -237.035086)
		(width 0.508)
		(layer "F.Cu")
		(net "GND")
	)
	(segment
		(start 38.2778 -7.4422)
		(end 38.2778 -8.4074)
		(width 0.508)
		(layer "F.Cu")
		(net "GND")
	)
	(segment
		(start 390.474962 -16.845026)
		(end 388.754874 -16.845026)
		(width 0.508)
		(layer "F.Cu")
		(net "GND")
	)
	(segment
		(start 362.6612 -246.90324)
		(end 362.6612 -247.65)
		(width 0.4064)
		(layer "F.Cu")
		(net "GND")
	)
	(segment
		(start 395.478 -268.224)
		(end 396.875 -268.224)
		(width 0.508)
		(layer "F.Cu")
		(net "GND")
	)
	(segment
		(start 457.9874 -19.9517)
		(end 457.9874 -20.7772)
		(width 0.508)
		(layer "F.Cu")
		(net "GND")
	)
	(segment
		(start 178.83124 -250.4948)
		(end 179.7558 -250.4948)
		(width 0.4064)
		(layer "F.Cu")
		(net "GND")
	)
	(segment
		(start 385.804918 -26.230072)
		(end 387.611874 -26.230072)
		(width 0.508)
		(layer "F.Cu")
		(net "GND")
	)
	(segment
		(start 260.14045 -377.714256)
		(end 260.14045 -376.476006)
		(width 0.508)
		(layer "F.Cu")
		(net "GND")
	)
	(segment
		(start 113.284 -260.604)
		(end 113.284 -262.001)
		(width 0.508)
		(layer "F.Cu")
		(net "GND")
	)
	(segment
		(start 124.674884 -270.975074)
		(end 122.954796 -270.975074)
		(width 0.508)
		(layer "F.Cu")
		(net "GND")
	)
	(segment
		(start 42.631868 -214.574628)
		(end 43.768772 -214.574628)
		(width 0.508)
		(layer "F.Cu")
		(net "GND")
	)
	(segment
		(start 253.80569 -228.029262)
		(end 253.716282 -228.029262)
		(width 0.4572)
		(layer "F.Cu")
		(net "GND")
	)
	(segment
		(start 448.094354 -102.184454)
		(end 448.098672 -102.188772)
		(width 0.508)
		(layer "F.Cu")
		(net "GND")
	)
	(segment
		(start 115.71224 -250.4948)
		(end 116.6368 -250.4948)
		(width 0.4064)
		(layer "F.Cu")
		(net "GND")
	)
	(segment
		(start 105.547668 -97.328228)
		(end 105.547668 -96.248728)
		(width 0.508)
		(layer "F.Cu")
		(net "GND")
	)
	(segment
		(start 177.53076 -248.6152)
		(end 176.784 -248.6152)
		(width 0.4064)
		(layer "F.Cu")
		(net "GND")
	)
	(segment
		(start 10.907268 -212.390228)
		(end 10.907268 -211.310728)
		(width 0.508)
		(layer "F.Cu")
		(net "GND")
	)
	(segment
		(start 461.264 -17.81556)
		(end 462.3308 -17.81556)
		(width 0.3048)
		(layer "F.Cu")
		(net "GND")
	)
	(segment
		(start 93.125036 -148.35505)
		(end 91.404948 -148.35505)
		(width 0.508)
		(layer "F.Cu")
		(net "GND")
	)
	(segment
		(start 126.9746 -31.1785)
		(end 126.9746 -30.3276)
		(width 0.508)
		(layer "F.Cu")
		(net "GND")
	)
	(segment
		(start 151.554942 -253.830074)
		(end 153.361898 -253.830074)
		(width 0.508)
		(layer "F.Cu")
		(net "GND")
	)
	(segment
		(start 140.0048 -35.687)
		(end 138.811 -35.687)
		(width 0.508)
		(layer "F.Cu")
		(net "GND")
	)
	(segment
		(start 25.355042 -26.230072)
		(end 27.161998 -26.230072)
		(width 0.508)
		(layer "F.Cu")
		(net "GND")
	)
	(segment
		(start 355.078538 -50.785014)
		(end 355.075998 -50.787554)
		(width 0.508)
		(layer "F.Cu")
		(net "GND")
	)
	(segment
		(start 177.2412 -33.782)
		(end 176.3268 -33.782)
		(width 0.508)
		(layer "F.Cu")
		(net "GND")
	)
	(segment
		(start 422.025064 -131.84505)
		(end 420.304976 -131.84505)
		(width 0.508)
		(layer "F.Cu")
		(net "GND")
	)
	(segment
		(start 124.674884 -20.655026)
		(end 122.954796 -20.655026)
		(width 0.508)
		(layer "F.Cu")
		(net "GND")
	)
	(segment
		(start 156.224986 -148.35505)
		(end 158.236158 -148.35505)
		(width 0.4572)
		(layer "F.Cu")
		(net "GND")
	)
	(segment
		(start 230.1494 -197.612)
		(end 229.8954 -197.358)
		(width 0.508)
		(layer "F.Cu")
		(net "GND")
	)
	(segment
		(start 95.377 -31.2039)
		(end 95.377 -30.3276)
		(width 0.508)
		(layer "F.Cu")
		(net "GND")
	)
	(segment
		(start 53.5178 -15.98676)
		(end 54.6354 -15.98676)
		(width 0.3048)
		(layer "F.Cu")
		(net "GND")
	)
	(segment
		(start 456.946 -38.608)
		(end 455.93 -38.608)
		(width 0.508)
		(layer "F.Cu")
		(net "GND")
	)
	(segment
		(start 93.125036 -20.655026)
		(end 91.404948 -20.655026)
		(width 0.508)
		(layer "F.Cu")
		(net "GND")
	)
	(segment
		(start 183.896 -366.649)
		(end 183.896 -365.6838)
		(width 0.508)
		(layer "F.Cu")
		(net "GND")
	)
	(segment
		(start 314.0964 -341.257382)
		(end 314.0964 -342.077802)
		(width 0.508)
		(layer "F.Cu")
		(net "GND")
	)
	(segment
		(start 50.165 -145.542)
		(end 50.165 -146.939)
		(width 0.508)
		(layer "F.Cu")
		(net "GND")
	)
	(segment
		(start 87.376 -46.228)
		(end 87.376 -47.244)
		(width 0.508)
		(layer "F.Cu")
		(net "GND")
	)
	(segment
		(start 460.27975 -101.904292)
		(end 460.279242 -101.9048)
		(width 0.508)
		(layer "F.Cu")
		(net "GND")
	)
	(segment
		(start 424.434 -46.101)
		(end 424.434 -48.420528)
		(width 0.508)
		(layer "F.Cu")
		(net "GND")
	)
	(segment
		(start 253.492 -282.956)
		(end 254.127254 -282.320746)
		(width 0.508)
		(layer "F.Cu")
		(net "GND")
	)
	(segment
		(start 322.704968 -26.230072)
		(end 320.666872 -26.230072)
		(width 0.4572)
		(layer "F.Cu")
		(net "GND")
	)
	(segment
		(start 213.54796 -164.00526)
		(end 215.09228 -164.00526)
		(width 0.508)
		(layer "F.Cu")
		(net "GND")
	)
	(segment
		(start 48.981868 -101.717602)
		(end 48.986694 -101.722428)
		(width 0.508)
		(layer "F.Cu")
		(net "GND")
	)
	(segment
		(start 251.497338 -226.362768)
		(end 251.504196 -226.35591)
		(width 0.4572)
		(layer "F.Cu")
		(net "GND")
	)
	(segment
		(start 419.822122 -145.81505)
		(end 419.813232 -145.80616)
		(width 0.508)
		(layer "F.Cu")
		(net "GND")
	)
	(segment
		(start 56.90489 -21.42998)
		(end 58.32602 -21.42998)
		(width 0.508)
		(layer "F.Cu")
		(net "GND")
	)
	(segment
		(start 261.75081 -223.90481)
		(end 261.239 -223.393)
		(width 0.508)
		(layer "F.Cu")
		(net "GND")
	)
	(segment
		(start 32.974534 -10.385044)
		(end 32.584644 -10.385044)
		(width 0.3048)
		(layer "F.Cu")
		(net "GND")
	)
	(segment
		(start 420.200074 -165.785038)
		(end 422.082976 -165.785038)
		(width 0.508)
		(layer "F.Cu")
		(net "GND")
	)
	(segment
		(start 82.13852 -149.15388)
		(end 82.13852 -149.720808)
		(width 0.508)
		(layer "F.Cu")
		(net "GND")
	)
	(segment
		(start 116.2558 -15.98676)
		(end 117.3734 -15.98676)
		(width 0.3048)
		(layer "F.Cu")
		(net "GND")
	)
	(segment
		(start 151.554942 -141.230096)
		(end 153.361898 -141.230096)
		(width 0.508)
		(layer "F.Cu")
		(net "GND")
	)
	(segment
		(start 30.025086 -33.355026)
		(end 28.304998 -33.355026)
		(width 0.508)
		(layer "F.Cu")
		(net "GND")
	)
	(segment
		(start 44.972732 -212.323172)
		(end 44.972732 -211.201)
		(width 0.508)
		(layer "F.Cu")
		(net "GND")
	)
	(segment
		(start 232.13949 -354.673662)
		(end 232.13949 -356.157784)
		(width 0.508)
		(layer "F.Cu")
		(net "GND")
	)
	(segment
		(start 453.574912 -243.035074)
		(end 451.854824 -243.035074)
		(width 0.508)
		(layer "F.Cu")
		(net "GND")
	)
	(segment
		(start 426.72 -13.1445)
		(end 426.72 -12.319)
		(width 0.508)
		(layer "F.Cu")
		(net "GND")
	)
	(segment
		(start 156.224986 -135.65505)
		(end 154.504898 -135.65505)
		(width 0.508)
		(layer "F.Cu")
		(net "GND")
	)
	(segment
		(start 40.1828 -6.3754)
		(end 40.0304 -6.223)
		(width 0.508)
		(layer "F.Cu")
		(net "GND")
	)
	(segment
		(start 253.716282 -228.029262)
		(end 253.259082 -227.572062)
		(width 0.4572)
		(layer "F.Cu")
		(net "GND")
	)
	(segment
		(start 61.574934 -33.355026)
		(end 59.854846 -33.355026)
		(width 0.508)
		(layer "F.Cu")
		(net "GND")
	)
	(segment
		(start 28.200096 -7.035038)
		(end 30.082998 -7.035038)
		(width 0.508)
		(layer "F.Cu")
		(net "GND")
	)
	(segment
		(start 461.645 -7.3406)
		(end 461.645 -8.3058)
		(width 0.508)
		(layer "F.Cu")
		(net "GND")
	)
	(segment
		(start 343.549478 -216.497154)
		(end 343.549478 -217.413586)
		(width 0.508)
		(layer "F.Cu")
		(net "GND")
	)
	(segment
		(start 28.200096 -165.785038)
		(end 30.082998 -165.785038)
		(width 0.508)
		(layer "F.Cu")
		(net "GND")
	)
	(segment
		(start 453.574912 -148.35505)
		(end 451.854824 -148.35505)
		(width 0.508)
		(layer "F.Cu")
		(net "GND")
	)
	(segment
		(start 390.474962 -33.355026)
		(end 388.754874 -33.355026)
		(width 0.508)
		(layer "F.Cu")
		(net "GND")
	)
	(segment
		(start 480.45497 -138.83005)
		(end 482.261926 -138.83005)
		(width 0.508)
		(layer "F.Cu")
		(net "GND")
	)
	(segment
		(start 248.7295 -307.086)
		(end 249.555 -307.086)
		(width 0.508)
		(layer "F.Cu")
		(net "GND")
	)
	(segment
		(start 181.991 -161.163)
		(end 180.6448 -161.163)
		(width 0.508)
		(layer "F.Cu")
		(net "GND")
	)
	(segment
		(start 87.376 -276.225)
		(end 87.376 -277.241)
		(width 0.508)
		(layer "F.Cu")
		(net "GND")
	)
	(segment
		(start 304.895504 -233.195114)
		(end 304.903378 -233.18724)
		(width 0.508)
		(layer "F.Cu")
		(net "GND")
	)
	(segment
		(start 124.674884 -131.84505)
		(end 122.954796 -131.84505)
		(width 0.508)
		(layer "F.Cu")
		(net "GND")
	)
	(segment
		(start 339.807296 -212.390228)
		(end 339.807296 -211.56549)
		(width 0.508)
		(layer "F.Cu")
		(net "GND")
	)
	(segment
		(start 362.331 -38.608)
		(end 361.315 -38.608)
		(width 0.508)
		(layer "F.Cu")
		(net "GND")
	)
	(segment
		(start 156.224986 -30.815026)
		(end 154.504898 -30.815026)
		(width 0.508)
		(layer "F.Cu")
		(net "GND")
	)
	(segment
		(start 254.141478 -228.36505)
		(end 253.80569 -228.029262)
		(width 0.4572)
		(layer "F.Cu")
		(net "GND")
	)
	(segment
		(start 51.0032 -33.782)
		(end 50.038 -33.782)
		(width 0.508)
		(layer "F.Cu")
		(net "GND")
	)
	(segment
		(start 457.581 -45.9232)
		(end 457.581 -47.117)
		(width 0.508)
		(layer "F.Cu")
		(net "GND")
	)
	(segment
		(start 390.474962 -13.035026)
		(end 388.754874 -13.035026)
		(width 0.508)
		(layer "F.Cu")
		(net "GND")
	)
	(segment
		(start 322.704968 -21.42998)
		(end 324.781672 -21.42998)
		(width 0.4572)
		(layer "F.Cu")
		(net "GND")
	)
	(segment
		(start 480.45497 -23.830026)
		(end 482.261926 -23.830026)
		(width 0.508)
		(layer "F.Cu")
		(net "GND")
	)
	(segment
		(start 14.912086 -100.870512)
		(end 14.912086 -99.869498)
		(width 0.508)
		(layer "F.Cu")
		(net "GND")
	)
	(segment
		(start 25.355042 -23.830026)
		(end 27.161998 -23.830026)
		(width 0.508)
		(layer "F.Cu")
		(net "GND")
	)
	(segment
		(start 189.454282 -155.97505)
		(end 189.952122 -155.47721)
		(width 0.508)
		(layer "F.Cu")
		(net "GND")
	)
	(segment
		(start 259.534406 -227.82911)
		(end 260.36651 -227.82911)
		(width 0.4572)
		(layer "F.Cu")
		(net "GND")
	)
	(segment
		(start 455.93 -161.163)
		(end 455.93 -162.179)
		(width 0.508)
		(layer "F.Cu")
		(net "GND")
	)
	(segment
		(start 479.05924 -9.3218)
		(end 479.5266 -9.78916)
		(width 0.4064)
		(layer "F.Cu")
		(net "GND")
	)
	(segment
		(start 23.77567 -229.328218)
		(end 23.77567 -228.351842)
		(width 0.508)
		(layer "F.Cu")
		(net "GND")
	)
	(segment
		(start 51.6382 -17.28724)
		(end 51.6382 -18.2118)
		(width 0.4064)
		(layer "F.Cu")
		(net "GND")
	)
	(segment
		(start 248.970038 -135.479282)
		(end 249.986038 -135.479282)
		(width 0.508)
		(layer "F.Cu")
		(net "GND")
	)
	(segment
		(start 61.574934 -135.65505)
		(end 59.854846 -135.65505)
		(width 0.508)
		(layer "F.Cu")
		(net "GND")
	)
	(segment
		(start 459.616302 -230.63835)
		(end 459.616302 -229.55885)
		(width 0.508)
		(layer "F.Cu")
		(net "GND")
	)
	(segment
		(start 435.346094 -215.844628)
		(end 435.346094 -216.754202)
		(width 0.508)
		(layer "F.Cu")
		(net "GND")
	)
	(segment
		(start 286.032448 -347.096842)
		(end 286.032448 -346.271342)
		(width 0.508)
		(layer "F.Cu")
		(net "GND")
	)
	(segment
		(start 218.354656 -172.981112)
		(end 218.354656 -173.590712)
		(width 0.3556)
		(layer "F.Cu")
		(net "GND")
	)
	(segment
		(start 181.6862 -156.2608)
		(end 180.4162 -156.2608)
		(width 0.508)
		(layer "F.Cu")
		(net "GND")
	)
	(segment
		(start 327.375012 -270.975074)
		(end 325.654924 -270.975074)
		(width 0.508)
		(layer "F.Cu")
		(net "GND")
	)
	(segment
		(start 353.16668 -146.18462)
		(end 354.10394 -146.18462)
		(width 0.508)
		(layer "F.Cu")
		(net "GND")
	)
	(segment
		(start 424.021504 -364.236)
		(end 424.021504 -363.0168)
		(width 0.508)
		(layer "F.Cu")
		(net "GND")
	)
	(segment
		(start 477.668844 -271.344644)
		(end 477.647 -271.3228)
		(width 0.508)
		(layer "F.Cu")
		(net "GND")
	)
	(segment
		(start 93.125036 -250.655074)
		(end 91.404948 -250.655074)
		(width 0.508)
		(layer "F.Cu")
		(net "GND")
	)
	(segment
		(start 183.105044 -23.830026)
		(end 184.810146 -23.830026)
		(width 0.508)
		(layer "F.Cu")
		(net "GND")
	)
	(segment
		(start 256.4765 -215.011)
		(end 256.4765 -216.129616)
		(width 0.3048)
		(layer "F.Cu")
		(net "GND")
	)
	(segment
		(start 61.574934 -268.435074)
		(end 59.854846 -268.435074)
		(width 0.508)
		(layer "F.Cu")
		(net "GND")
	)
	(segment
		(start 485.125014 -263.355074)
		(end 483.404926 -263.355074)
		(width 0.508)
		(layer "F.Cu")
		(net "GND")
	)
	(segment
		(start 252.102112 -369.818412)
		(end 252.2474 -369.9637)
		(width 0.3048)
		(layer "F.Cu")
		(net "GND")
	)
	(segment
		(start 434.457094 -212.390228)
		(end 434.457094 -211.310728)
		(width 0.508)
		(layer "F.Cu")
		(net "GND")
	)
	(segment
		(start 385.804918 -251.430028)
		(end 387.611874 -251.430028)
		(width 0.508)
		(layer "F.Cu")
		(net "GND")
	)
	(segment
		(start 485.125014 -128.03505)
		(end 483.404926 -128.03505)
		(width 0.508)
		(layer "F.Cu")
		(net "GND")
	)
	(segment
		(start 390.474962 -145.81505)
		(end 388.754874 -145.81505)
		(width 0.508)
		(layer "F.Cu")
		(net "GND")
	)
	(segment
		(start 448.904868 -26.230072)
		(end 450.711824 -26.230072)
		(width 0.508)
		(layer "F.Cu")
		(net "GND")
	)
	(segment
		(start 453.574912 -38.435026)
		(end 451.854824 -38.435026)
		(width 0.508)
		(layer "F.Cu")
		(net "GND")
	)
	(segment
		(start 327.375012 -20.655026)
		(end 325.654924 -20.655026)
		(width 0.508)
		(layer "F.Cu")
		(net "GND")
	)
	(segment
		(start 237.551214 -194.01028)
		(end 237.881922 -193.679572)
		(width 0.508)
		(layer "F.Cu")
		(net "GND")
	)
	(segment
		(start 30.025086 -243.035074)
		(end 28.304998 -243.035074)
		(width 0.508)
		(layer "F.Cu")
		(net "GND")
	)
	(segment
		(start 390.067038 -165.785038)
		(end 388.649972 -165.785038)
		(width 0.508)
		(layer "F.Cu")
		(net "GND")
	)
	(segment
		(start 385.804918 -256.23012)
		(end 387.611874 -256.23012)
		(width 0.508)
		(layer "F.Cu")
		(net "GND")
	)
	(segment
		(start 287.683448 -351.548446)
		(end 287.683448 -350.843342)
		(width 0.2032)
		(layer "F.Cu")
		(net "GND")
	)
	(segment
		(start 332.359 -268.224)
		(end 333.756 -268.224)
		(width 0.508)
		(layer "F.Cu")
		(net "GND")
	)
	(segment
		(start 353.3648 -31.2039)
		(end 353.3648 -30.353)
		(width 0.508)
		(layer "F.Cu")
		(net "GND")
	)
	(segment
		(start 362.331 -268.605)
		(end 361.315 -268.605)
		(width 0.508)
		(layer "F.Cu")
		(net "GND")
	)
	(segment
		(start 18.669 -145.542)
		(end 18.669 -146.939)
		(width 0.508)
		(layer "F.Cu")
		(net "GND")
	)
	(segment
		(start 473.71 -145.542)
		(end 473.71 -146.939)
		(width 0.508)
		(layer "F.Cu")
		(net "GND")
	)
	(segment
		(start 187.775088 -243.035074)
		(end 185.9026 -243.035074)
		(width 0.508)
		(layer "F.Cu")
		(net "GND")
	)
	(segment
		(start 154.399996 -122.035062)
		(end 156.282898 -122.035062)
		(width 0.508)
		(layer "F.Cu")
		(net "GND")
	)
	(segment
		(start 176.403 -145.542)
		(end 176.403 -146.939)
		(width 0.508)
		(layer "F.Cu")
		(net "GND")
	)
	(segment
		(start 45.2628 -150.622)
		(end 44.069 -150.622)
		(width 0.508)
		(layer "F.Cu")
		(net "GND")
	)
	(segment
		(start 244.82298 -196.72554)
		(end 245.076726 -196.72554)
		(width 0.508)
		(layer "F.Cu")
		(net "GND")
	)
	(segment
		(start 425.2468 -135.6614)
		(end 424.9928 -135.9154)
		(width 0.508)
		(layer "F.Cu")
		(net "GND")
	)
	(segment
		(start 189.659768 -365.298736)
		(end 190.673736 -365.298736)
		(width 0.4064)
		(layer "F.Cu")
		(net "GND")
	)
	(segment
		(start 18.669 -30.607)
		(end 18.669 -32.004)
		(width 0.508)
		(layer "F.Cu")
		(net "GND")
	)
	(segment
		(start 221.375224 -327.66762)
		(end 221.375224 -326.131174)
		(width 0.508)
		(layer "F.Cu")
		(net "GND")
	)
	(segment
		(start 120.00484 -256.23012)
		(end 121.811796 -256.23012)
		(width 0.508)
		(layer "F.Cu")
		(net "GND")
	)
	(segment
		(start 21.09724 -250.4948)
		(end 22.0218 -250.4948)
		(width 0.4064)
		(layer "F.Cu")
		(net "GND")
	)
	(segment
		(start 466.007196 -212.390228)
		(end 466.007196 -211.310728)
		(width 0.508)
		(layer "F.Cu")
		(net "GND")
	)
	(segment
		(start 245.076726 -196.72554)
		(end 245.582694 -196.219572)
		(width 0.508)
		(layer "F.Cu")
		(net "GND")
	)
	(segment
		(start 169.03065 -101.442012)
		(end 169.03065 -102.351586)
		(width 0.508)
		(layer "F.Cu")
		(net "GND")
	)
	(segment
		(start 124.674884 -135.65505)
		(end 123.2789 -135.65505)
		(width 0.508)
		(layer "F.Cu")
		(net "GND")
	)
	(segment
		(start 427.6598 -245.60276)
		(end 427.6598 -244.856)
		(width 0.4064)
		(layer "F.Cu")
		(net "GND")
	)
	(segment
		(start 388.649972 -280.785062)
		(end 390.532874 -280.785062)
		(width 0.508)
		(layer "F.Cu")
		(net "GND")
	)
	(segment
		(start 224.550224 -327.66762)
		(end 224.550224 -326.131174)
		(width 0.508)
		(layer "F.Cu")
		(net "GND")
	)
	(segment
		(start 241.046 -307.904896)
		(end 241.046 -308.558692)
		(width 0.2032)
		(layer "F.Cu")
		(net "GND")
	)
	(segment
		(start 473.202 -243.9035)
		(end 472.3384 -243.9035)
		(width 0.508)
		(layer "F.Cu")
		(net "GND")
	)
	(segment
		(start 187.775088 -270.975074)
		(end 186.055 -270.975074)
		(width 0.508)
		(layer "F.Cu")
		(net "GND")
	)
	(segment
		(start 120.00484 -136.430004)
		(end 121.811796 -136.430004)
		(width 0.508)
		(layer "F.Cu")
		(net "GND")
	)
	(segment
		(start 459.552802 -229.49535)
		(end 459.38567 -229.328218)
		(width 0.508)
		(layer "F.Cu")
		(net "GND")
	)
	(segment
		(start 124.674884 -128.03505)
		(end 122.954796 -128.03505)
		(width 0.508)
		(layer "F.Cu")
		(net "GND")
	)
	(segment
		(start 362.6739 -135.6106)
		(end 361.8738 -135.6106)
		(width 0.508)
		(layer "F.Cu")
		(net "GND")
	)
	(segment
		(start 456.524614 -10.962386)
		(end 456.524614 -10.054844)
		(width 0.3048)
		(layer "F.Cu")
		(net "GND")
	)
	(segment
		(start 426.085 -275.9202)
		(end 426.085 -277.114)
		(width 0.508)
		(layer "F.Cu")
		(net "GND")
	)
	(segment
		(start 319.642236 -375.65584)
		(end 319.372996 -375.65584)
		(width 0.4064)
		(layer "F.Cu")
		(net "GND")
	)
	(segment
		(start 239.79632 -202.66152)
		(end 239.793018 -202.658218)
		(width 0.3556)
		(layer "F.Cu")
		(net "GND")
	)
	(segment
		(start 260.511544 -215.89746)
		(end 260.511544 -217.124026)
		(width 0.508)
		(layer "F.Cu")
		(net "GND")
	)
	(segment
		(start 390.474962 -30.815026)
		(end 388.754874 -30.815026)
		(width 0.508)
		(layer "F.Cu")
		(net "GND")
	)
	(segment
		(start 247.42648 -219.7227)
		(end 247.42648 -218.16568)
		(width 0.508)
		(layer "F.Cu")
		(net "GND")
	)
	(segment
		(start 256.69748 -216.426796)
		(end 256.4384 -216.167716)
		(width 0.3048)
		(layer "F.Cu")
		(net "GND")
	)
	(segment
		(start 143.594074 -146.939)
		(end 143.580866 -146.952208)
		(width 0.508)
		(layer "F.Cu")
		(net "GND")
	)
	(segment
		(start 420.200074 -122.035062)
		(end 422.082976 -122.035062)
		(width 0.508)
		(layer "F.Cu")
		(net "GND")
	)
	(segment
		(start 56.90489 -256.23012)
		(end 58.711846 -256.23012)
		(width 0.508)
		(layer "F.Cu")
		(net "GND")
	)
	(segment
		(start 171.5008 -35.687)
		(end 170.307 -35.687)
		(width 0.508)
		(layer "F.Cu")
		(net "GND")
	)
	(segment
		(start 122.849894 -122.035062)
		(end 124.732796 -122.035062)
		(width 0.508)
		(layer "F.Cu")
		(net "GND")
	)
	(segment
		(start 394.589 -45.9232)
		(end 394.589 -48.133)
		(width 0.508)
		(layer "F.Cu")
		(net "GND")
	)
	(segment
		(start 312.9534 -341.257382)
		(end 312.9534 -342.077802)
		(width 0.508)
		(layer "F.Cu")
		(net "GND")
	)
	(segment
		(start 39.960296 -369.2525)
		(end 40.023796 -369.189)
		(width 0.508)
		(layer "F.Cu")
		(net "GND")
	)
	(segment
		(start 325.550022 -122.035062)
		(end 325.550022 -120.197372)
		(width 0.508)
		(layer "F.Cu")
		(net "GND")
	)
	(segment
		(start 354.25507 -21.42998)
		(end 356.062026 -21.42998)
		(width 0.508)
		(layer "F.Cu")
		(net "GND")
	)
	(segment
		(start 457.653644 -370.0653)
		(end 457.653644 -369.37696)
		(width 0.4064)
		(layer "F.Cu")
		(net "GND")
	)
	(segment
		(start 480.45497 -141.230096)
		(end 482.261926 -141.230096)
		(width 0.508)
		(layer "F.Cu")
		(net "GND")
	)
	(segment
		(start 393.6746 -250.5964)
		(end 393.4206 -250.8504)
		(width 0.508)
		(layer "F.Cu")
		(net "GND")
	)
	(segment
		(start 289.080448 -347.096842)
		(end 289.080448 -346.271342)
		(width 0.508)
		(layer "F.Cu")
		(net "GND")
	)
	(segment
		(start 30.025086 -263.355074)
		(end 28.304998 -263.355074)
		(width 0.508)
		(layer "F.Cu")
		(net "GND")
	)
	(segment
		(start 30.025086 -145.81505)
		(end 28.304998 -145.81505)
		(width 0.508)
		(layer "F.Cu")
		(net "GND")
	)
	(segment
		(start 93.125036 -243.035074)
		(end 91.371674 -243.035074)
		(width 0.508)
		(layer "F.Cu")
		(net "GND")
	)
	(segment
		(start 112.176814 -145.831814)
		(end 113.284 -146.939)
		(width 0.508)
		(layer "F.Cu")
		(net "GND")
	)
	(segment
		(start 252.461268 -223.4057)
		(end 252.461268 -224.2566)
		(width 0.508)
		(layer "F.Cu")
		(net "GND")
	)
	(segment
		(start 184.7215 -369.189)
		(end 185.039 -369.189)
		(width 0.508)
		(layer "F.Cu")
		(net "GND")
	)
	(segment
		(start 357.100124 -122.035062)
		(end 358.983026 -122.035062)
		(width 0.508)
		(layer "F.Cu")
		(net "GND")
	)
	(segment
		(start 156.224986 -246.845074)
		(end 154.504898 -246.845074)
		(width 0.508)
		(layer "F.Cu")
		(net "GND")
	)
	(segment
		(start 93.125036 -40.975026)
		(end 91.404948 -40.975026)
		(width 0.508)
		(layer "F.Cu")
		(net "GND")
	)
	(segment
		(start 422.025064 -270.975074)
		(end 420.304976 -270.975074)
		(width 0.508)
		(layer "F.Cu")
		(net "GND")
	)
	(segment
		(start 416.3314 -261.2009)
		(end 416.3314 -260.3246)
		(width 0.508)
		(layer "F.Cu")
		(net "GND")
	)
	(segment
		(start 463.7786 -6.3754)
		(end 463.3468 -5.9436)
		(width 0.508)
		(layer "F.Cu")
		(net "GND")
	)
	(segment
		(start 329.819 -276.098)
		(end 329.819 -277.114)
		(width 0.508)
		(layer "F.Cu")
		(net "GND")
	)
	(segment
		(start 483.300024 -165.785038)
		(end 485.182926 -165.785038)
		(width 0.508)
		(layer "F.Cu")
		(net "GND")
	)
	(segment
		(start 156.224986 -40.975026)
		(end 154.504898 -40.975026)
		(width 0.508)
		(layer "F.Cu")
		(net "GND")
	)
	(segment
		(start 154.399996 -7.035038)
		(end 156.282898 -7.035038)
		(width 0.508)
		(layer "F.Cu")
		(net "GND")
	)
	(segment
		(start 385.804918 -138.83005)
		(end 387.611874 -138.83005)
		(width 0.508)
		(layer "F.Cu")
		(net "GND")
	)
	(segment
		(start 147.103592 -211.432394)
		(end 147.103592 -212.44687)
		(width 0.508)
		(layer "F.Cu")
		(net "GND")
	)
	(segment
		(start 327.375012 -250.655074)
		(end 325.654924 -250.655074)
		(width 0.508)
		(layer "F.Cu")
		(net "GND")
	)
	(segment
		(start 127 -373.0625)
		(end 127 -373.888)
		(width 0.508)
		(layer "F.Cu")
		(net "GND")
	)
	(segment
		(start 30.025086 -38.435026)
		(end 28.304998 -38.435026)
		(width 0.508)
		(layer "F.Cu")
		(net "GND")
	)
	(segment
		(start 426.879004 -369.2525)
		(end 427.717204 -369.2525)
		(width 0.508)
		(layer "F.Cu")
		(net "GND")
	)
	(segment
		(start 156.224986 -145.81505)
		(end 154.504898 -145.81505)
		(width 0.508)
		(layer "F.Cu")
		(net "GND")
	)
	(segment
		(start 30.025086 -153.43505)
		(end 28.304998 -153.43505)
		(width 0.508)
		(layer "F.Cu")
		(net "GND")
	)
	(segment
		(start 185.6486 -242.781074)
		(end 185.6486 -242.7732)
		(width 0.508)
		(layer "F.Cu")
		(net "GND")
	)
	(segment
		(start 363.601 -13.1445)
		(end 363.601 -12.319)
		(width 0.508)
		(layer "F.Cu")
		(net "GND")
	)
	(segment
		(start 91.300046 -165.785038)
		(end 93.182948 -165.785038)
		(width 0.508)
		(layer "F.Cu")
		(net "GND")
	)
	(segment
		(start 146.03476 -248.6152)
		(end 145.288 -248.6152)
		(width 0.4064)
		(layer "F.Cu")
		(net "GND")
	)
	(segment
		(start 223.18091 -225.425)
		(end 223.489774 -225.116136)
		(width 0.508)
		(layer "F.Cu")
		(net "GND")
	)
	(segment
		(start 260.708648 -215.700356)
		(end 260.511544 -215.89746)
		(width 0.508)
		(layer "F.Cu")
		(net "GND")
	)
	(segment
		(start 244.91442 -218.70162)
		(end 244.91442 -217.33002)
		(width 0.3048)
		(layer "F.Cu")
		(net "GND")
	)
	(segment
		(start 362.6739 -250.5456)
		(end 361.8738 -250.5456)
		(width 0.508)
		(layer "F.Cu")
		(net "GND")
	)
	(segment
		(start 28.200096 -50.785014)
		(end 30.082998 -50.785014)
		(width 0.508)
		(layer "F.Cu")
		(net "GND")
	)
	(segment
		(start 178.816 -19.6215)
		(end 178.816 -20.447)
		(width 0.508)
		(layer "F.Cu")
		(net "GND")
	)
	(segment
		(start 251.476764 -210.747864)
		(end 250.563634 -210.747864)
		(width 0.508)
		(layer "F.Cu")
		(net "GND")
	)
	(segment
		(start 142.5575 -254.127)
		(end 142.5575 -255.016)
		(width 0.508)
		(layer "F.Cu")
		(net "GND")
	)
	(segment
		(start 425.45 -153.67)
		(end 424.434 -153.67)
		(width 0.508)
		(layer "F.Cu")
		(net "GND")
	)
	(segment
		(start 453.574912 -20.655026)
		(end 451.854824 -20.655026)
		(width 0.508)
		(layer "F.Cu")
		(net "GND")
	)
	(segment
		(start 140.0048 -150.622)
		(end 140.0048 -151.853646)
		(width 0.508)
		(layer "F.Cu")
		(net "GND")
	)
	(segment
		(start 306.70373 -359.423462)
		(end 307.294026 -360.013758)
		(width 0.508)
		(layer "F.Cu")
		(net "GND")
	)
	(segment
		(start 142.5575 -24.13)
		(end 142.5575 -25.019)
		(width 0.508)
		(layer "F.Cu")
		(net "GND")
	)
	(segment
		(start 19.79676 -248.6152)
		(end 19.05 -248.6152)
		(width 0.4064)
		(layer "F.Cu")
		(net "GND")
	)
	(segment
		(start 257.458972 -372.77421)
		(end 257.458972 -373.54891)
		(width 0.508)
		(layer "F.Cu")
		(net "GND")
	)
	(segment
		(start 93.125036 -16.845026)
		(end 91.404948 -16.845026)
		(width 0.508)
		(layer "F.Cu")
		(net "GND")
	)
	(segment
		(start 416.3822 -31.2039)
		(end 416.3822 -30.353)
		(width 0.508)
		(layer "F.Cu")
		(net "GND")
	)
	(segment
		(start 448.904868 -256.23012)
		(end 450.711824 -256.23012)
		(width 0.508)
		(layer "F.Cu")
		(net "GND")
	)
	(segment
		(start 217.15222 -212.87232)
		(end 216.8906 -213.13394)
		(width 0.3556)
		(layer "F.Cu")
		(net "GND")
	)
	(segment
		(start 322.704968 -141.230096)
		(end 324.511924 -141.230096)
		(width 0.508)
		(layer "F.Cu")
		(net "GND")
	)
	(segment
		(start 460.1718 -15.2273)
		(end 460.1718 -15.1257)
		(width 0.508)
		(layer "F.Cu")
		(net "GND")
	)
	(segment
		(start 61.574934 -263.355074)
		(end 59.854846 -263.355074)
		(width 0.508)
		(layer "F.Cu")
		(net "GND")
	)
	(segment
		(start 147.997418 -216.81567)
		(end 147.992592 -216.810844)
		(width 0.508)
		(layer "F.Cu")
		(net "GND")
	)
	(segment
		(start 417.35502 -23.830026)
		(end 419.161976 -23.830026)
		(width 0.508)
		(layer "F.Cu")
		(net "GND")
	)
	(segment
		(start 471.3605 -254.127)
		(end 471.3605 -255.016)
		(width 0.508)
		(layer "F.Cu")
		(net "GND")
	)
	(segment
		(start 45.3898 -265.684)
		(end 44.196 -265.684)
		(width 0.508)
		(layer "F.Cu")
		(net "GND")
	)
	(segment
		(start 264.287 -358.267)
		(end 262.454898 -358.267)
		(width 0.508)
		(layer "F.Cu")
		(net "GND")
	)
	(segment
		(start 190.0428 -146.1897)
		(end 190.0428 -145.3388)
		(width 0.508)
		(layer "F.Cu")
		(net "GND")
	)
	(segment
		(start 110.9345 -254.127)
		(end 110.9345 -255.016)
		(width 0.508)
		(layer "F.Cu")
		(net "GND")
	)
	(segment
		(start 330.5048 -250.4948)
		(end 330.3524 -250.6472)
		(width 0.508)
		(layer "F.Cu")
		(net "GND")
	)
	(segment
		(start 50.75555 -101.7778)
		(end 50.75555 -100.6729)
		(width 0.508)
		(layer "F.Cu")
		(net "GND")
	)
	(segment
		(start 396.1638 -245.60276)
		(end 396.1638 -244.856)
		(width 0.4064)
		(layer "F.Cu")
		(net "GND")
	)
	(segment
		(start 177.8762 -17.28724)
		(end 177.8762 -18.2118)
		(width 0.4064)
		(layer "F.Cu")
		(net "GND")
	)
	(segment
		(start 371.357144 -212.390228)
		(end 371.357144 -211.310728)
		(width 0.508)
		(layer "F.Cu")
		(net "GND")
	)
	(segment
		(start 459.3844 -19.11604)
		(end 459.3844 -19.8628)
		(width 0.3048)
		(layer "F.Cu")
		(net "GND")
	)
	(segment
		(start 14.023086 -97.416112)
		(end 14.023086 -96.336612)
		(width 0.508)
		(layer "F.Cu")
		(net "GND")
	)
	(segment
		(start 61.574934 -250.655074)
		(end 59.854846 -250.655074)
		(width 0.508)
		(layer "F.Cu")
		(net "GND")
	)
	(segment
		(start 327.375012 -268.435074)
		(end 325.654924 -268.435074)
		(width 0.508)
		(layer "F.Cu")
		(net "GND")
	)
	(segment
		(start 358.925114 -38.435026)
		(end 357.205026 -38.435026)
		(width 0.508)
		(layer "F.Cu")
		(net "GND")
	)
	(segment
		(start 327.375012 -135.65505)
		(end 325.654924 -135.65505)
		(width 0.508)
		(layer "F.Cu")
		(net "GND")
	)
	(segment
		(start 239.780064 -368.051588)
		(end 239.780064 -368.863118)
		(width 0.508)
		(layer "F.Cu")
		(net "GND")
	)
	(segment
		(start 185.950098 -122.035062)
		(end 185.736738 -122.035062)
		(width 0.508)
		(layer "F.Cu")
		(net "GND")
	)
	(segment
		(start 331.88275 -363.0295)
		(end 331.88275 -364.236)
		(width 0.508)
		(layer "F.Cu")
		(net "GND")
	)
	(segment
		(start 150.114 -156.2608)
		(end 149.04847 -156.2608)
		(width 0.508)
		(layer "F.Cu")
		(net "GND")
	)
	(segment
		(start 25.355042 -21.42998)
		(end 27.161998 -21.42998)
		(width 0.508)
		(layer "F.Cu")
		(net "GND")
	)
	(segment
		(start 239.793018 -202.658218)
		(end 239.395 -202.658218)
		(width 0.3556)
		(layer "F.Cu")
		(net "GND")
	)
	(segment
		(start 81.788 -30.607)
		(end 81.788 -32.004)
		(width 0.508)
		(layer "F.Cu")
		(net "GND")
	)
	(segment
		(start 218.214702 -327.668128)
		(end 218.214702 -326.131682)
		(width 0.508)
		(layer "F.Cu")
		(net "GND")
	)
	(segment
		(start 236.982 -191.184784)
		(end 236.978444 -191.181228)
		(width 0.508)
		(layer "F.Cu")
		(net "GND")
	)
	(segment
		(start 187.775088 -128.03505)
		(end 186.055 -128.03505)
		(width 0.508)
		(layer "F.Cu")
		(net "GND")
	)
	(segment
		(start 106.436668 -100.782628)
		(end 106.436668 -101.692202)
		(width 0.508)
		(layer "F.Cu")
		(net "GND")
	)
	(segment
		(start 30.025086 -131.84505)
		(end 28.304998 -131.84505)
		(width 0.508)
		(layer "F.Cu")
		(net "GND")
	)
	(segment
		(start 249.334274 -142.156434)
		(end 250.350274 -142.156434)
		(width 0.508)
		(layer "F.Cu")
		(net "GND")
	)
	(segment
		(start 37.6047 -6.4008)
		(end 37.6047 -5.326634)
		(width 0.508)
		(layer "F.Cu")
		(net "GND")
	)
	(segment
		(start 343.549478 -101.49713)
		(end 343.549478 -102.413562)
		(width 0.508)
		(layer "F.Cu")
		(net "GND")
	)
	(segment
		(start 151.554942 -251.430028)
		(end 153.361898 -251.430028)
		(width 0.508)
		(layer "F.Cu")
		(net "GND")
	)
	(segment
		(start 150.114 -271.3228)
		(end 148.844 -271.3228)
		(width 0.508)
		(layer "F.Cu")
		(net "GND")
	)
	(segment
		(start 480.45497 -253.830074)
		(end 482.261926 -253.830074)
		(width 0.508)
		(layer "F.Cu")
		(net "GND")
	)
	(segment
		(start 114.3762 -17.28724)
		(end 114.3762 -18.2118)
		(width 0.4064)
		(layer "F.Cu")
		(net "GND")
	)
	(segment
		(start 183.958992 -372.25224)
		(end 183.517032 -372.6942)
		(width 0.508)
		(layer "F.Cu")
		(net "GND")
	)
	(segment
		(start 106.360468 -215.768428)
		(end 106.360468 -216.678002)
		(width 0.508)
		(layer "F.Cu")
		(net "GND")
	)
	(segment
		(start 118.872 -276.225)
		(end 118.872 -277.241)
		(width 0.508)
		(layer "F.Cu")
		(net "GND")
	)
	(segment
		(start 453.574912 -268.435074)
		(end 451.854824 -268.435074)
		(width 0.508)
		(layer "F.Cu")
		(net "GND")
	)
	(segment
		(start 48.85436 -119.453406)
		(end 48.85436 -118.373906)
		(width 0.508)
		(layer "F.Cu")
		(net "GND")
	)
	(segment
		(start 455.93 -46.101)
		(end 455.93 -47.117)
		(width 0.508)
		(layer "F.Cu")
		(net "GND")
	)
	(segment
		(start 393.5222 -13.47724)
		(end 393.5222 -14.224)
		(width 0.4064)
		(layer "F.Cu")
		(net "GND")
	)
	(segment
		(start 260.73481 -223.89719)
		(end 261.239 -223.393)
		(width 0.508)
		(layer "F.Cu")
		(net "GND")
	)
	(segment
		(start 394.2715 -250.5964)
		(end 393.6746 -250.5964)
		(width 0.508)
		(layer "F.Cu")
		(net "GND")
	)
	(segment
		(start 485.125014 -153.43505)
		(end 483.404926 -153.43505)
		(width 0.508)
		(layer "F.Cu")
		(net "GND")
	)
	(segment
		(start 222.8596 -301.9679)
		(end 222.8596 -302.6918)
		(width 0.508)
		(layer "F.Cu")
		(net "GND")
	)
	(segment
		(start 439.85434 -120.770142)
		(end 440.269122 -120.770142)
		(width 0.508)
		(layer "F.Cu")
		(net "GND")
	)
	(segment
		(start 84.21624 -135.4328)
		(end 85.1408 -135.4328)
		(width 0.4064)
		(layer "F.Cu")
		(net "GND")
	)
	(segment
		(start 358.925114 -148.35505)
		(end 357.205026 -148.35505)
		(width 0.508)
		(layer "F.Cu")
		(net "GND")
	)
	(segment
		(start 327.437496 -368.935)
		(end 328.262996 -368.935)
		(width 0.508)
		(layer "F.Cu")
		(net "GND")
	)
	(segment
		(start 207.88884 -233.682794)
		(end 207.882236 -233.67619)
		(width 0.508)
		(layer "F.Cu")
		(net "GND")
	)
	(segment
		(start 177.2412 -148.717)
		(end 176.3268 -148.717)
		(width 0.508)
		(layer "F.Cu")
		(net "GND")
	)
	(segment
		(start 478.7138 -20.701)
		(end 478.8408 -20.574)
		(width 0.508)
		(layer "F.Cu")
		(net "GND")
	)
	(segment
		(start 187.790328 -371.153436)
		(end 187.424568 -370.787676)
		(width 0.4064)
		(layer "F.Cu")
		(net "GND")
	)
	(segment
		(start 79.4385 -24.13)
		(end 79.4385 -25.019)
		(width 0.508)
		(layer "F.Cu")
		(net "GND")
	)
	(segment
		(start 483.300024 -7.035038)
		(end 485.182926 -7.035038)
		(width 0.508)
		(layer "F.Cu")
		(net "GND")
	)
	(segment
		(start 51.29276 -133.5532)
		(end 50.546 -133.5532)
		(width 0.4064)
		(layer "F.Cu")
		(net "GND")
	)
	(segment
		(start 213.788752 -204.343)
		(end 213.789006 -204.342746)
		(width 0.508)
		(layer "F.Cu")
		(net "GND")
	)
	(segment
		(start 358.925114 -153.43505)
		(end 357.205026 -153.43505)
		(width 0.508)
		(layer "F.Cu")
		(net "GND")
	)
	(segment
		(start 358.925114 -33.355026)
		(end 357.205026 -33.355026)
		(width 0.508)
		(layer "F.Cu")
		(net "GND")
	)
	(segment
		(start 259.558282 -226.81311)
		(end 260.404864 -226.81311)
		(width 0.4572)
		(layer "F.Cu")
		(net "GND")
	)
	(segment
		(start 174.0535 -139.338558)
		(end 174.827692 -140.11275)
		(width 0.508)
		(layer "F.Cu")
		(net "GND")
	)
	(segment
		(start 28.200096 -122.035062)
		(end 30.082998 -122.035062)
		(width 0.508)
		(layer "F.Cu")
		(net "GND")
	)
	(segment
		(start 108.13415 -216.7636)
		(end 108.13415 -215.6587)
		(width 0.508)
		(layer "F.Cu")
		(net "GND")
	)
	(segment
		(start 145.669 -148.717)
		(end 144.7546 -148.717)
		(width 0.508)
		(layer "F.Cu")
		(net "GND")
	)
	(segment
		(start 364.998 -275.9202)
		(end 364.998 -277.114)
		(width 0.508)
		(layer "F.Cu")
		(net "GND")
	)
	(segment
		(start 63.457074 -243.035074)
		(end 64.0334 -243.6114)
		(width 0.508)
		(layer "F.Cu")
		(net "GND")
	)
	(segment
		(start 321.6656 -261.1755)
		(end 321.6656 -260.2738)
		(width 0.508)
		(layer "F.Cu")
		(net "GND")
	)
	(segment
		(start 261.460742 -216.859358)
		(end 261.277862 -216.859358)
		(width 0.508)
		(layer "F.Cu")
		(net "GND")
	)
	(segment
		(start 73.924668 -97.404428)
		(end 73.924668 -96.324928)
		(width 0.508)
		(layer "F.Cu")
		(net "GND")
	)
	(segment
		(start 166.660068 -212.314028)
		(end 166.660068 -211.234528)
		(width 0.508)
		(layer "F.Cu")
		(net "GND")
	)
	(segment
		(start 305.662076 -341.257382)
		(end 305.662076 -342.077802)
		(width 0.508)
		(layer "F.Cu")
		(net "GND")
	)
	(via
		(at 345.44 -267.716)
		(size 0.5588)
		(drill 0.3048)
		(layers "F.Cu" "B.Cu")
		(net "GND")
	)
	(via
		(at 108.13415 -216.7636)
		(size 0.5588)
		(drill 0.3048)
		(layers "F.Cu" "B.Cu")
		(net "GND")
	)
	(via
		(at 50.292 -50.292)
		(size 0.5588)
		(drill 0.3048)
		(layers "F.Cu" "B.Cu")
		(net "GND")
	)
	(via
		(at 1.524 -136.293352)
		(size 0.7112)
		(drill 0.4064)
		(layers "F.Cu" "B.Cu")
		(net "GND")
	)
	(via
		(at 156.282898 -280.785062)
		(size 0.5588)
		(drill 0.3048)
		(layers "F.Cu" "B.Cu")
		(net "GND")
	)
	(via
		(at 408.867864 -378.476002)
		(size 0.7112)
		(drill 0.4064)
		(layers "F.Cu" "B.Cu")
		(net "GND")
	)
	(via
		(at 458.326744 -104.852216)
		(size 0.5588)
		(drill 0.3048)
		(layers "F.Cu" "B.Cu")
		(net "GND")
	)
	(via
		(at 23.368 -192.532)
		(size 0.5588)
		(drill 0.3048)
		(layers "F.Cu" "B.Cu")
		(net "GND")
	)
	(via
		(at 208.798922 -102.691184)
		(size 0.7112)
		(drill 0.4064)
		(layers "F.Cu" "B.Cu")
		(net "GND")
	)
	(via
		(at 90.261948 -138.83005)
		(size 0.5588)
		(drill 0.3048)
		(layers "F.Cu" "B.Cu")
		(net "GND")
	)
	(via
		(at 482.261926 -251.430028)
		(size 0.5588)
		(drill 0.3048)
		(layers "F.Cu" "B.Cu")
		(net "GND")
	)
	(via
		(at 1.524 -269.643352)
		(size 0.7112)
		(drill 0.4064)
		(layers "F.Cu" "B.Cu")
		(net "GND")
	)
	(via
		(at 186.055 -246.845074)
		(size 0.5588)
		(drill 0.3048)
		(layers "F.Cu" "B.Cu")
		(net "GND")
	)
	(via
		(at 74.596752 -344.864944)
		(size 0.5588)
		(drill 0.3048)
		(layers "F.Cu" "B.Cu")
		(net "GND")
	)
	(via
		(at 89.83599 -378.476002)
		(size 0.7112)
		(drill 0.4064)
		(layers "F.Cu" "B.Cu")
		(net "GND")
	)
	(via
		(at 347.589856 -384.47599)
		(size 0.7112)
		(drill 0.4064)
		(layers "F.Cu" "B.Cu")
		(net "GND")
	)
	(via
		(at 489.926122 -167.38219)
		(size 0.7112)
		(drill 0.4064)
		(layers "F.Cu" "B.Cu")
		(net "GND")
	)
	(via
		(at 40.744648 -1.524)
		(size 0.7112)
		(drill 0.4064)
		(layers "F.Cu" "B.Cu")
		(net "GND")
	)
	(via
		(at 108.21035 -101.7778)
		(size 0.5588)
		(drill 0.3048)
		(layers "F.Cu" "B.Cu")
		(net "GND")
	)
	(via
		(at 187.452 -292.608)
		(size 0.5588)
		(drill 0.3048)
		(layers "F.Cu" "B.Cu")
		(net "GND")
	)
	(via
		(at 55.753 -162.179)
		(size 0.5588)
		(drill 0.3048)
		(layers "F.Cu" "B.Cu")
		(net "GND")
	)
	(via
		(at 419.1 -215.9)
		(size 0.5588)
		(drill 0.3048)
		(layers "F.Cu" "B.Cu")
		(net "GND")
	)
	(via
		(at 317.5 -292.1)
		(size 0.5588)
		(drill 0.3048)
		(layers "F.Cu" "B.Cu")
		(net "GND")
	)
	(via
		(at 59.854846 -135.65505)
		(size 0.5588)
		(drill 0.3048)
		(layers "F.Cu" "B.Cu")
		(net "GND")
	)
	(via
		(at 137.264648 -1.524)
		(size 0.7112)
		(drill 0.4064)
		(layers "F.Cu" "B.Cu")
		(net "GND")
	)
	(via
		(at 197.47611 -21.322538)
		(size 0.7112)
		(drill 0.4064)
		(layers "F.Cu" "B.Cu")
		(net "GND")
	)
	(via
		(at 1.524 -61.363352)
		(size 0.7112)
		(drill 0.4064)
		(layers "F.Cu" "B.Cu")
		(net "GND")
	)
	(via
		(at 483.404926 -135.65505)
		(size 0.5588)
		(drill 0.3048)
		(layers "F.Cu" "B.Cu")
		(net "GND")
	)
	(via
		(at 489.926122 -321.05219)
		(size 0.7112)
		(drill 0.4064)
		(layers "F.Cu" "B.Cu")
		(net "GND")
	)
	(via
		(at 381.508 -49.784)
		(size 0.5588)
		(drill 0.3048)
		(layers "F.Cu" "B.Cu")
		(net "GND")
	)
	(via
		(at 4.523994 -381.684022)
		(size 0.7112)
		(drill 0.4064)
		(layers "F.Cu" "B.Cu")
		(net "GND")
	)
	(via
		(at 42.014648 -1.524)
		(size 0.7112)
		(drill 0.4064)
		(layers "F.Cu" "B.Cu")
		(net "GND")
	)
	(via
		(at 5.542026 -384.47599)
		(size 0.7112)
		(drill 0.4064)
		(layers "F.Cu" "B.Cu")
		(net "GND")
	)
	(via
		(at 47.752 -236.728)
		(size 0.5588)
		(drill 0.3048)
		(layers "F.Cu" "B.Cu")
		(net "GND")
	)
	(via
		(at 324.511924 -251.430028)
		(size 0.5588)
		(drill 0.3048)
		(layers "F.Cu" "B.Cu")
		(net "GND")
	)
	(via
		(at 456.021186 -123.572778)
		(size 0.5588)
		(drill 0.3048)
		(layers "F.Cu" "B.Cu")
		(net "GND")
	)
	(via
		(at 1.524 -23.263352)
		(size 0.7112)
		(drill 0.4064)
		(layers "F.Cu" "B.Cu")
		(net "GND")
	)
	(via
		(at 413.947864 -378.476002)
		(size 0.7112)
		(drill 0.4064)
		(layers "F.Cu" "B.Cu")
		(net "GND")
	)
	(via
		(at 107.188 -265.684)
		(size 0.5588)
		(drill 0.3048)
		(layers "F.Cu" "B.Cu")
		(net "GND")
	)
	(via
		(at 429.097186 -114.987578)
		(size 0.5588)
		(drill 0.3048)
		(layers "F.Cu" "B.Cu")
		(net "GND")
	)
	(via
		(at 477.921828 -384.47599)
		(size 0.7112)
		(drill 0.4064)
		(layers "F.Cu" "B.Cu")
		(net "GND")
	)
	(via
		(at 209.804 -286.512)
		(size 0.5588)
		(drill 0.3048)
		(layers "F.Cu" "B.Cu")
		(net "GND")
	)
	(via
		(at 204.0128 -141.5796)
		(size 0.7112)
		(drill 0.4064)
		(layers "F.Cu" "B.Cu")
		(net "GND")
	)
	(via
		(at 183.958992 -372.25224)
		(size 0.5588)
		(drill 0.3048)
		(layers "F.Cu" "B.Cu")
		(net "GND")
	)
	(via
		(at 59.854846 -30.815026)
		(size 0.5588)
		(drill 0.3048)
		(layers "F.Cu" "B.Cu")
		(net "GND")
	)
	(via
		(at 429.505872 -384.47599)
		(size 0.7112)
		(drill 0.4064)
		(layers "F.Cu" "B.Cu")
		(net "GND")
	)
	(via
		(at 42.909998 -216.11463)
		(size 0.5588)
		(drill 0.3048)
		(layers "F.Cu" "B.Cu")
		(net "GND")
	)
	(via
		(at 1.524 -145.183352)
		(size 0.7112)
		(drill 0.4064)
		(layers "F.Cu" "B.Cu")
		(net "GND")
	)
	(via
		(at 406.4 -342.9)
		(size 0.5588)
		(drill 0.3048)
		(layers "F.Cu" "B.Cu")
		(net "GND")
	)
	(via
		(at 453.632824 -50.785014)
		(size 0.5588)
		(drill 0.3048)
		(layers "F.Cu" "B.Cu")
		(net "GND")
	)
	(via
		(at 1.524 -227.733352)
		(size 0.7112)
		(drill 0.4064)
		(layers "F.Cu" "B.Cu")
		(net "GND")
	)
	(via
		(at 431.8 -190.5)
		(size 0.5588)
		(drill 0.3048)
		(layers "F.Cu" "B.Cu")
		(net "GND")
	)
	(via
		(at 33.124648 -1.524)
		(size 0.7112)
		(drill 0.4064)
		(layers "F.Cu" "B.Cu")
		(net "GND")
	)
	(via
		(at 473.583 -263.779)
		(size 0.5588)
		(drill 0.3048)
		(layers "F.Cu" "B.Cu")
		(net "GND")
	)
	(via
		(at 50.546 -133.5532)
		(size 0.5588)
		(drill 0.3048)
		(layers "F.Cu" "B.Cu")
		(net "GND")
	)
	(via
		(at 318.476376 -1.524)
		(size 0.7112)
		(drill 0.4064)
		(layers "F.Cu" "B.Cu")
		(net "GND")
	)
	(via
		(at 415.544 -44.704)
		(size 0.5588)
		(drill 0.3048)
		(layers "F.Cu" "B.Cu")
		(net "GND")
	)
	(via
		(at 72.644 -155.448)
		(size 0.5588)
		(drill 0.3048)
		(layers "F.Cu" "B.Cu")
		(net "GND")
	)
	(via
		(at 138.534648 -1.524)
		(size 0.7112)
		(drill 0.4064)
		(layers "F.Cu" "B.Cu")
		(net "GND")
	)
	(via
		(at 36.72586 -115.262406)
		(size 0.5588)
		(drill 0.3048)
		(layers "F.Cu" "B.Cu")
		(net "GND")
	)
	(via
		(at 203.922122 -101.446584)
		(size 0.7112)
		(drill 0.4064)
		(layers "F.Cu" "B.Cu")
		(net "GND")
	)
	(via
		(at 187.833 -7.035038)
		(size 0.5588)
		(drill 0.3048)
		(layers "F.Cu" "B.Cu")
		(net "GND")
	)
	(via
		(at 92.376752 -344.864944)
		(size 0.5588)
		(drill 0.3048)
		(layers "F.Cu" "B.Cu")
		(net "GND")
	)
	(via
		(at 215.1253 -162.76828)
		(size 0.5588)
		(drill 0.3048)
		(layers "F.Cu" "B.Cu")
		(net "GND")
	)
	(via
		(at 99.996752 -344.864944)
		(size 0.5588)
		(drill 0.3048)
		(layers "F.Cu" "B.Cu")
		(net "GND")
	)
	(via
		(at 464.693 -381.381)
		(size 0.7112)
		(drill 0.4064)
		(layers "F.Cu" "B.Cu")
		(net "GND")
	)
	(via
		(at 489.926122 -186.43219)
		(size 0.7112)
		(drill 0.4064)
		(layers "F.Cu" "B.Cu")
		(net "GND")
	)
	(via
		(at 489.926122 -257.55219)
		(size 0.7112)
		(drill 0.4064)
		(layers "F.Cu" "B.Cu")
		(net "GND")
	)
	(via
		(at 312.523886 -13.35151)
		(size 0.7112)
		(drill 0.4064)
		(layers "F.Cu" "B.Cu")
		(net "GND")
	)
	(via
		(at 419.813232 -145.80616)
		(size 0.5588)
		(drill 0.3048)
		(layers "F.Cu" "B.Cu")
		(net "GND")
	)
	(via
		(at 202.7936 -142.7988)
		(size 0.7112)
		(drill 0.4064)
		(layers "F.Cu" "B.Cu")
		(net "GND")
	)
	(via
		(at 1.524 -255.673352)
		(size 0.7112)
		(drill 0.4064)
		(layers "F.Cu" "B.Cu")
		(net "GND")
	)
	(via
		(at 153.361898 -251.430028)
		(size 0.5588)
		(drill 0.3048)
		(layers "F.Cu" "B.Cu")
		(net "GND")
	)
	(via
		(at 50.0888 -148.717)
		(size 0.5588)
		(drill 0.3048)
		(layers "F.Cu" "B.Cu")
		(net "GND")
	)
	(via
		(at 325.654924 -131.84505)
		(size 0.5588)
		(drill 0.3048)
		(layers "F.Cu" "B.Cu")
		(net "GND")
	)
	(via
		(at 459.646782 -106.915458)
		(size 0.5588)
		(drill 0.3048)
		(layers "F.Cu" "B.Cu")
		(net "GND")
	)
	(via
		(at 489.926122 -70.86219)
		(size 0.7112)
		(drill 0.4064)
		(layers "F.Cu" "B.Cu")
		(net "GND")
	)
	(via
		(at 312.364882 -380.775972)
		(size 0.7112)
		(drill 0.4064)
		(layers "F.Cu" "B.Cu")
		(net "GND")
	)
	(via
		(at 67.73926 -122.704606)
		(size 0.5588)
		(drill 0.3048)
		(layers "F.Cu" "B.Cu")
		(net "GND")
	)
	(via
		(at 237.947962 -378.476002)
		(size 0.7112)
		(drill 0.4064)
		(layers "F.Cu" "B.Cu")
		(net "GND")
	)
	(via
		(at 489.926122 -347.72219)
		(size 0.7112)
		(drill 0.4064)
		(layers "F.Cu" "B.Cu")
		(net "GND")
	)
	(via
		(at 176.784 -133.5532)
		(size 0.5588)
		(drill 0.3048)
		(layers "F.Cu" "B.Cu")
		(net "GND")
	)
	(via
		(at 336.159856 -384.47599)
		(size 0.7112)
		(drill 0.4064)
		(layers "F.Cu" "B.Cu")
		(net "GND")
	)
	(via
		(at 420.304976 -40.975026)
		(size 0.5588)
		(drill 0.3048)
		(layers "F.Cu" "B.Cu")
		(net "GND")
	)
	(via
		(at 489.926122 -199.13219)
		(size 0.7112)
		(drill 0.4064)
		(layers "F.Cu" "B.Cu")
		(net "GND")
	)
	(via
		(at 361.7976 -135.6868)
		(size 0.5588)
		(drill 0.3048)
		(layers "F.Cu" "B.Cu")
		(net "GND")
	)
	(via
		(at 25.504648 -1.524)
		(size 0.7112)
		(drill 0.4064)
		(layers "F.Cu" "B.Cu")
		(net "GND")
	)
	(via
		(at 1.524 -174.393352)
		(size 0.7112)
		(drill 0.4064)
		(layers "F.Cu" "B.Cu")
		(net "GND")
	)
	(via
		(at 297.768772 -335.44256)
		(size 0.6604)
		(drill 0.3302)
		(layers "F.Cu" "B.Cu")
		(net "GND")
	)
	(via
		(at 79.676752 -341.054944)
		(size 0.5588)
		(drill 0.3048)
		(layers "F.Cu" "B.Cu")
		(net "GND")
	)
	(via
		(at 1.524 -286.153352)
		(size 0.7112)
		(drill 0.4064)
		(layers "F.Cu" "B.Cu")
		(net "GND")
	)
	(via
		(at 460.716376 -1.524)
		(size 0.7112)
		(drill 0.4064)
		(layers "F.Cu" "B.Cu")
		(net "GND")
	)
	(via
		(at 411.407864 -378.476002)
		(size 0.7112)
		(drill 0.4064)
		(layers "F.Cu" "B.Cu")
		(net "GND")
	)
	(via
		(at 110.9345 -139.954)
		(size 0.5588)
		(drill 0.3048)
		(layers "F.Cu" "B.Cu")
		(net "GND")
	)
	(via
		(at 461.986376 -1.524)
		(size 0.7112)
		(drill 0.4064)
		(layers "F.Cu" "B.Cu")
		(net "GND")
	)
	(via
		(at 219.964 -368.808)
		(size 0.5588)
		(drill 0.3048)
		(layers "F.Cu" "B.Cu")
		(net "GND")
	)
	(via
		(at 399.977864 -378.476002)
		(size 0.7112)
		(drill 0.4064)
		(layers "F.Cu" "B.Cu")
		(net "GND")
	)
	(via
		(at 489.926122 -153.41219)
		(size 0.7112)
		(drill 0.4064)
		(layers "F.Cu" "B.Cu")
		(net "GND")
	)
	(via
		(at 192.024 -82.804)
		(size 0.5588)
		(drill 0.3048)
		(layers "F.Cu" "B.Cu")
		(net "GND")
	)
	(via
		(at 437.896 -247.396)
		(size 0.5588)
		(drill 0.3048)
		(layers "F.Cu" "B.Cu")
		(net "GND")
	)
	(via
		(at 387.611874 -253.830074)
		(size 0.5588)
		(drill 0.3048)
		(layers "F.Cu" "B.Cu")
		(net "GND")
	)
	(via
		(at 44.196 -104.14)
		(size 0.5588)
		(drill 0.3048)
		(layers "F.Cu" "B.Cu")
		(net "GND")
	)
	(via
		(at 489.926122 -293.11219)
		(size 0.7112)
		(drill 0.4064)
		(layers "F.Cu" "B.Cu")
		(net "GND")
	)
	(via
		(at 384.8608 -145.3388)
		(size 0.5588)
		(drill 0.3048)
		(layers "F.Cu" "B.Cu")
		(net "GND")
	)
	(via
		(at 176.025048 -380.775972)
		(size 0.7112)
		(drill 0.4064)
		(layers "F.Cu" "B.Cu")
		(net "GND")
	)
	(via
		(at 1.524 -211.223352)
		(size 0.7112)
		(drill 0.4064)
		(layers "F.Cu" "B.Cu")
		(net "GND")
	)
	(via
		(at 489.926122 -106.42219)
		(size 0.7112)
		(drill 0.4064)
		(layers "F.Cu" "B.Cu")
		(net "GND")
	)
	(via
		(at 258.164076 -197.226682)
		(size 0.7112)
		(drill 0.4064)
		(layers "F.Cu" "B.Cu")
		(net "GND")
	)
	(via
		(at 288.911284 -238.694468)
		(size 0.6604)
		(drill 0.3556)
		(layers "F.Cu" "B.Cu")
		(net "GND")
	)
	(via
		(at 451.854824 -131.84505)
		(size 0.5588)
		(drill 0.3048)
		(layers "F.Cu" "B.Cu")
		(net "GND")
	)
	(via
		(at 211.95538 -239.88522)
		(size 0.5588)
		(drill 0.3048)
		(layers "F.Cu" "B.Cu")
		(net "GND")
	)
	(via
		(at 182.984648 -1.524)
		(size 0.7112)
		(drill 0.4064)
		(layers "F.Cu" "B.Cu")
		(net "GND")
	)
	(via
		(at 167.623998 -384.47599)
		(size 0.7112)
		(drill 0.4064)
		(layers "F.Cu" "B.Cu")
		(net "GND")
	)
	(via
		(at 201.7014 -304.1142)
		(size 0.7112)
		(drill 0.4064)
		(layers "F.Cu" "B.Cu")
		(net "GND")
	)
	(via
		(at 420.304976 -263.355074)
		(size 0.5588)
		(drill 0.3048)
		(layers "F.Cu" "B.Cu")
		(net "GND")
	)
	(via
		(at 50.75555 -101.7778)
		(size 0.5588)
		(drill 0.3048)
		(layers "F.Cu" "B.Cu")
		(net "GND")
	)
	(via
		(at 371.816376 -1.524)
		(size 0.7112)
		(drill 0.4064)
		(layers "F.Cu" "B.Cu")
		(net "GND")
	)
	(via
		(at 331.1652 -247.65)
		(size 0.5588)
		(drill 0.3048)
		(layers "F.Cu" "B.Cu")
		(net "GND")
	)
	(via
		(at 286.6898 -305.2318)
		(size 0.7112)
		(drill 0.4064)
		(layers "F.Cu" "B.Cu")
		(net "GND")
	)
	(via
		(at 92.814648 -1.524)
		(size 0.7112)
		(drill 0.4064)
		(layers "F.Cu" "B.Cu")
		(net "GND")
	)
	(via
		(at 1.524 -171.853352)
		(size 0.7112)
		(drill 0.4064)
		(layers "F.Cu" "B.Cu")
		(net "GND")
	)
	(via
		(at 259.510022 -366.940846)
		(size 0.5588)
		(drill 0.3048)
		(layers "F.Cu" "B.Cu")
		(net "GND")
	)
	(via
		(at 253.524004 -384.457956)
		(size 0.7112)
		(drill 0.4064)
		(layers "F.Cu" "B.Cu")
		(net "GND")
	)
	(via
		(at 419.161976 -136.430004)
		(size 0.5588)
		(drill 0.3048)
		(layers "F.Cu" "B.Cu")
		(net "GND")
	)
	(via
		(at 351.496376 -1.524)
		(size 0.7112)
		(drill 0.4064)
		(layers "F.Cu" "B.Cu")
		(net "GND")
	)
	(via
		(at 63.5 -304.8)
		(size 0.5588)
		(drill 0.3048)
		(layers "F.Cu" "B.Cu")
		(net "GND")
	)
	(via
		(at 1.524 -330.603352)
		(size 0.7112)
		(drill 0.4064)
		(layers "F.Cu" "B.Cu")
		(net "GND")
	)
	(via
		(at 45.151802 -230.51135)
		(size 0.5588)
		(drill 0.3048)
		(layers "F.Cu" "B.Cu")
		(net "GND")
	)
	(via
		(at 419.161976 -21.42998)
		(size 0.5588)
		(drill 0.3048)
		(layers "F.Cu" "B.Cu")
		(net "GND")
	)
	(via
		(at 153.361898 -136.430004)
		(size 0.5588)
		(drill 0.3048)
		(layers "F.Cu" "B.Cu")
		(net "GND")
	)
	(via
		(at 22.352 -51.816)
		(size 0.5588)
		(drill 0.3048)
		(layers "F.Cu" "B.Cu")
		(net "GND")
	)
	(via
		(at 1.524 -234.083352)
		(size 0.7112)
		(drill 0.4064)
		(layers "F.Cu" "B.Cu")
		(net "GND")
	)
	(via
		(at 148.971 -74.168)
		(size 0.5588)
		(drill 0.3048)
		(layers "F.Cu" "B.Cu")
		(net "GND")
	)
	(via
		(at 257.760978 -228.36505)
		(size 0.5588)
		(drill 0.3048)
		(layers "F.Cu" "B.Cu")
		(net "GND")
	)
	(via
		(at 323.596 -237.035086)
		(size 0.5588)
		(drill 0.3048)
		(layers "F.Cu" "B.Cu")
		(net "GND")
	)
	(via
		(at 489.926122 -214.37219)
		(size 0.7112)
		(drill 0.4064)
		(layers "F.Cu" "B.Cu")
		(net "GND")
	)
	(via
		(at 356.062026 -136.430004)
		(size 0.5588)
		(drill 0.3048)
		(layers "F.Cu" "B.Cu")
		(net "GND")
	)
	(via
		(at 414.528 -6.604)
		(size 0.5588)
		(drill 0.3048)
		(layers "F.Cu" "B.Cu")
		(net "GND")
	)
	(via
		(at 100.434648 -1.524)
		(size 0.7112)
		(drill 0.4064)
		(layers "F.Cu" "B.Cu")
		(net "GND")
	)
	(via
		(at 97.894648 -1.524)
		(size 0.7112)
		(drill 0.4064)
		(layers "F.Cu" "B.Cu")
		(net "GND")
	)
	(via
		(at 291.540692 -384.47599)
		(size 0.7112)
		(drill 0.4064)
		(layers "F.Cu" "B.Cu")
		(net "GND")
	)
	(via
		(at 130.048 -238.506)
		(size 0.5588)
		(drill 0.3048)
		(layers "F.Cu" "B.Cu")
		(net "GND")
	)
	(via
		(at 334.986376 -1.524)
		(size 0.7112)
		(drill 0.4064)
		(layers "F.Cu" "B.Cu")
		(net "GND")
	)
	(via
		(at 144.907 -30.607)
		(size 0.5588)
		(drill 0.3048)
		(layers "F.Cu" "B.Cu")
		(net "GND")
	)
	(via
		(at 113.168684 -148.849334)
		(size 0.5588)
		(drill 0.3048)
		(layers "F.Cu" "B.Cu")
		(net "GND")
	)
	(via
		(at 63.604648 -1.524)
		(size 0.7112)
		(drill 0.4064)
		(layers "F.Cu" "B.Cu")
		(net "GND")
	)
	(via
		(at 469.9 -355.6)
		(size 0.5588)
		(drill 0.3048)
		(layers "F.Cu" "B.Cu")
		(net "GND")
	)
	(via
		(at 458.216 -222.885)
		(size 0.5588)
		(drill 0.3048)
		(layers "F.Cu" "B.Cu")
		(net "GND")
	)
	(via
		(at 438.301384 -114.600228)
		(size 0.5588)
		(drill 0.3048)
		(layers "F.Cu" "B.Cu")
		(net "GND")
	)
	(via
		(at 333.756 -268.224)
		(size 0.5588)
		(drill 0.3048)
		(layers "F.Cu" "B.Cu")
		(net "GND")
	)
	(via
		(at 357.749856 -384.47599)
		(size 0.7112)
		(drill 0.4064)
		(layers "F.Cu" "B.Cu")
		(net "GND")
	)
	(via
		(at 112.69599 -378.476002)
		(size 0.7112)
		(drill 0.4064)
		(layers "F.Cu" "B.Cu")
		(net "GND")
	)
	(via
		(at 280.348436 -49.724056)
		(size 0.7112)
		(drill 0.4064)
		(layers "F.Cu" "B.Cu")
		(net "GND")
	)
	(via
		(at 59.854846 -155.97505)
		(size 0.5588)
		(drill 0.3048)
		(layers "F.Cu" "B.Cu")
		(net "GND")
	)
	(via
		(at 98.8695 -146.177)
		(size 0.5588)
		(drill 0.3048)
		(layers "F.Cu" "B.Cu")
		(net "GND")
	)
	(via
		(at 343.549478 -216.497154)
		(size 0.5588)
		(drill 0.3048)
		(layers "F.Cu" "B.Cu")
		(net "GND")
	)
	(via
		(at 465.927186 -120.194578)
		(size 0.5588)
		(drill 0.3048)
		(layers "F.Cu" "B.Cu")
		(net "GND")
	)
	(via
		(at 1.524 -88.033352)
		(size 0.7112)
		(drill 0.4064)
		(layers "F.Cu" "B.Cu")
		(net "GND")
	)
	(via
		(at 150.88997 -216.562686)
		(size 0.5588)
		(drill 0.3048)
		(layers "F.Cu" "B.Cu")
		(net "GND")
	)
	(via
		(at 489.926122 -82.29219)
		(size 0.7112)
		(drill 0.4064)
		(layers "F.Cu" "B.Cu")
		(net "GND")
	)
	(via
		(at 1.524 -168.043352)
		(size 0.7112)
		(drill 0.4064)
		(layers "F.Cu" "B.Cu")
		(net "GND")
	)
	(via
		(at 30.803596 -367.6396)
		(size 0.5588)
		(drill 0.3048)
		(layers "F.Cu" "B.Cu")
		(net "GND")
	)
	(via
		(at 396.1638 -129.921)
		(size 0.5588)
		(drill 0.3048)
		(layers "F.Cu" "B.Cu")
		(net "GND")
	)
	(via
		(at 1.524 -115.973352)
		(size 0.7112)
		(drill 0.4064)
		(layers "F.Cu" "B.Cu")
		(net "GND")
	)
	(via
		(at 489.926122 -112.77219)
		(size 0.7112)
		(drill 0.4064)
		(layers "F.Cu" "B.Cu")
		(net "GND")
	)
	(via
		(at 439.317384 -112.568228)
		(size 0.5588)
		(drill 0.3048)
		(layers "F.Cu" "B.Cu")
		(net "GND")
	)
	(via
		(at 165.204648 -1.524)
		(size 0.7112)
		(drill 0.4064)
		(layers "F.Cu" "B.Cu")
		(net "GND")
	)
	(via
		(at 489.926122 -281.68219)
		(size 0.7112)
		(drill 0.4064)
		(layers "F.Cu" "B.Cu")
		(net "GND")
	)
	(via
		(at 36.934648 -1.524)
		(size 0.7112)
		(drill 0.4064)
		(layers "F.Cu" "B.Cu")
		(net "GND")
	)
	(via
		(at 134.314692 -365.184182)
		(size 0.5588)
		(drill 0.3048)
		(layers "F.Cu" "B.Cu")
		(net "GND")
	)
	(via
		(at 127 -215.9)
		(size 0.5588)
		(drill 0.3048)
		(layers "F.Cu" "B.Cu")
		(net "GND")
	)
	(via
		(at 30.082998 -165.785038)
		(size 0.5588)
		(drill 0.3048)
		(layers "F.Cu" "B.Cu")
		(net "GND")
	)
	(via
		(at 393.7 -88.9)
		(size 0.5588)
		(drill 0.3048)
		(layers "F.Cu" "B.Cu")
		(net "GND")
	)
	(via
		(at 79.676752 -342.324944)
		(size 0.5588)
		(drill 0.3048)
		(layers "F.Cu" "B.Cu")
		(net "GND")
	)
	(via
		(at 357.205026 -145.81505)
		(size 0.5588)
		(drill 0.3048)
		(layers "F.Cu" "B.Cu")
		(net "GND")
	)
	(via
		(at 489.926122 -157.22219)
		(size 0.7112)
		(drill 0.4064)
		(layers "F.Cu" "B.Cu")
		(net "GND")
	)
	(via
		(at 208.798922 -103.910384)
		(size 0.7112)
		(drill 0.4064)
		(layers "F.Cu" "B.Cu")
		(net "GND")
	)
	(via
		(at 137.143998 -384.47599)
		(size 0.7112)
		(drill 0.4064)
		(layers "F.Cu" "B.Cu")
		(net "GND")
	)
	(via
		(at 1.524 -274.723352)
		(size 0.7112)
		(drill 0.4064)
		(layers "F.Cu" "B.Cu")
		(net "GND")
	)
	(via
		(at 383.159 -26.035)
		(size 0.5588)
		(drill 0.3048)
		(layers "F.Cu" "B.Cu")
		(net "GND")
	)
	(via
		(at 154.504898 -131.84505)
		(size 0.5588)
		(drill 0.3048)
		(layers "F.Cu" "B.Cu")
		(net "GND")
	)
	(via
		(at 45.847 -261.239)
		(size 0.5588)
		(drill 0.3048)
		(layers "F.Cu" "B.Cu")
		(net "GND")
	)
	(via
		(at 73.32599 -378.476002)
		(size 0.7112)
		(drill 0.4064)
		(layers "F.Cu" "B.Cu")
		(net "GND")
	)
	(via
		(at 453.632824 -7.035038)
		(size 0.5588)
		(drill 0.3048)
		(layers "F.Cu" "B.Cu")
		(net "GND")
	)
	(via
		(at 122.954796 -40.975026)
		(size 0.5588)
		(drill 0.3048)
		(layers "F.Cu" "B.Cu")
		(net "GND")
	)
	(via
		(at 74.59599 -378.476002)
		(size 0.7112)
		(drill 0.4064)
		(layers "F.Cu" "B.Cu")
		(net "GND")
	)
	(via
		(at 447.995802 -225.30435)
		(size 0.5588)
		(drill 0.3048)
		(layers "F.Cu" "B.Cu")
		(net "GND")
	)
	(via
		(at 418.084 -378.968)
		(size 0.7112)
		(drill 0.4064)
		(layers "F.Cu" "B.Cu")
		(net "GND")
	)
	(via
		(at 394.589 -277.114)
		(size 0.5588)
		(drill 0.3048)
		(layers "F.Cu" "B.Cu")
		(net "GND")
	)
	(via
		(at 64.0334 -243.6114)
		(size 0.5588)
		(drill 0.3048)
		(layers "F.Cu" "B.Cu")
		(net "GND")
	)
	(via
		(at 37.23386 -114.119406)
		(size 0.5588)
		(drill 0.3048)
		(layers "F.Cu" "B.Cu")
		(net "GND")
	)
	(via
		(at 319.649856 -384.47599)
		(size 0.7112)
		(drill 0.4064)
		(layers "F.Cu" "B.Cu")
		(net "GND")
	)
	(via
		(at 139.7 -304.8)
		(size 0.5588)
		(drill 0.3048)
		(layers "F.Cu" "B.Cu")
		(net "GND")
	)
	(via
		(at 249.032268 -224.2566)
		(size 0.5588)
		(drill 0.3048)
		(layers "F.Cu" "B.Cu")
		(net "GND")
	)
	(via
		(at 483.404926 -13.035026)
		(size 0.5588)
		(drill 0.3048)
		(layers "F.Cu" "B.Cu")
		(net "GND")
	)
	(via
		(at 489.926122 -314.70219)
		(size 0.7112)
		(drill 0.4064)
		(layers "F.Cu" "B.Cu")
		(net "GND")
	)
	(via
		(at 13.020802 -227.20935)
		(size 0.5588)
		(drill 0.3048)
		(layers "F.Cu" "B.Cu")
		(net "GND")
	)
	(via
		(at 489.926122 -296.92219)
		(size 0.7112)
		(drill 0.4064)
		(layers "F.Cu" "B.Cu")
		(net "GND")
	)
	(via
		(at 287.909 -304.0126)
		(size 0.7112)
		(drill 0.4064)
		(layers "F.Cu" "B.Cu")
		(net "GND")
	)
	(via
		(at 379.436376 -1.524)
		(size 0.7112)
		(drill 0.4064)
		(layers "F.Cu" "B.Cu")
		(net "GND")
	)
	(via
		(at 472.647518 -30.515814)
		(size 0.5588)
		(drill 0.3048)
		(layers "F.Cu" "B.Cu")
		(net "GND")
	)
	(via
		(at 489.926122 -271.52219)
		(size 0.7112)
		(drill 0.4064)
		(layers "F.Cu" "B.Cu")
		(net "GND")
	)
	(via
		(at 451.854824 -263.355074)
		(size 0.5588)
		(drill 0.3048)
		(layers "F.Cu" "B.Cu")
		(net "GND")
	)
	(via
		(at 362.17606 -382.298194)
		(size 0.7112)
		(drill 0.4064)
		(layers "F.Cu" "B.Cu")
		(net "GND")
	)
	(via
		(at 292.810692 -384.47599)
		(size 0.7112)
		(drill 0.4064)
		(layers "F.Cu" "B.Cu")
		(net "GND")
	)
	(via
		(at 489.926122 -16.25219)
		(size 0.7112)
		(drill 0.4064)
		(layers "F.Cu" "B.Cu")
		(net "GND")
	)
	(via
		(at 50.8 -292.1)
		(size 0.5588)
		(drill 0.3048)
		(layers "F.Cu" "B.Cu")
		(net "GND")
	)
	(via
		(at 209.9818 -65.666874)
		(size 0.6604)
		(drill 0.3556)
		(layers "F.Cu" "B.Cu")
		(net "GND")
	)
	(via
		(at 86.026752 -344.864944)
		(size 0.5588)
		(drill 0.3048)
		(layers "F.Cu" "B.Cu")
		(net "GND")
	)
	(via
		(at 419.1 -96.52)
		(size 0.5588)
		(drill 0.3048)
		(layers "F.Cu" "B.Cu")
		(net "GND")
	)
	(via
		(at 249.555 -288.671)
		(size 0.5588)
		(drill 0.3048)
		(layers "F.Cu" "B.Cu")
		(net "GND")
	)
	(via
		(at 316.357 -381.127)
		(size 0.7112)
		(drill 0.4064)
		(layers "F.Cu" "B.Cu")
		(net "GND")
	)
	(via
		(at 123.294648 -1.524)
		(size 0.7112)
		(drill 0.4064)
		(layers "F.Cu" "B.Cu")
		(net "GND")
	)
	(via
		(at 489.926122 -210.56219)
		(size 0.7112)
		(drill 0.4064)
		(layers "F.Cu" "B.Cu")
		(net "GND")
	)
	(via
		(at 489.926122 -46.73219)
		(size 0.7112)
		(drill 0.4064)
		(layers "F.Cu" "B.Cu")
		(net "GND")
	)
	(via
		(at 489.926122 -255.01219)
		(size 0.7112)
		(drill 0.4064)
		(layers "F.Cu" "B.Cu")
		(net "GND")
	)
	(via
		(at 161.9885 -261.239)
		(size 0.5588)
		(drill 0.3048)
		(layers "F.Cu" "B.Cu")
		(net "GND")
	)
	(via
		(at 122.821446 -235.093256)
		(size 0.5588)
		(drill 0.3048)
		(layers "F.Cu" "B.Cu")
		(net "GND")
	)
	(via
		(at 216.357962 -378.476002)
		(size 0.7112)
		(drill 0.4064)
		(layers "F.Cu" "B.Cu")
		(net "GND")
	)
	(via
		(at 204.602588 -49.724056)
		(size 0.7112)
		(drill 0.4064)
		(layers "F.Cu" "B.Cu")
		(net "GND")
	)
	(via
		(at 328.636376 -1.524)
		(size 0.7112)
		(drill 0.4064)
		(layers "F.Cu" "B.Cu")
		(net "GND")
	)
	(via
		(at 58.711846 -251.430028)
		(size 0.5588)
		(drill 0.3048)
		(layers "F.Cu" "B.Cu")
		(net "GND")
	)
	(via
		(at 162.664648 -1.524)
		(size 0.7112)
		(drill 0.4064)
		(layers "F.Cu" "B.Cu")
		(net "GND")
	)
	(via
		(at 250.350274 -142.156434)
		(size 0.5588)
		(drill 0.3048)
		(layers "F.Cu" "B.Cu")
		(net "GND")
	)
	(via
		(at 283.0576 -304.0634)
		(size 0.7112)
		(drill 0.4064)
		(layers "F.Cu" "B.Cu")
		(net "GND")
	)
	(via
		(at 446.090802 -225.30435)
		(size 0.5588)
		(drill 0.3048)
		(layers "F.Cu" "B.Cu")
		(net "GND")
	)
	(via
		(at 94.91599 -378.476002)
		(size 0.7112)
		(drill 0.4064)
		(layers "F.Cu" "B.Cu")
		(net "GND")
	)
	(via
		(at 96.71812 -364.388146)
		(size 0.7112)
		(drill 0.4064)
		(layers "F.Cu" "B.Cu")
		(net "GND")
	)
	(via
		(at 22.352 -121.412)
		(size 0.5588)
		(drill 0.3048)
		(layers "F.Cu" "B.Cu")
		(net "GND")
	)
	(via
		(at 124.564648 -1.524)
		(size 0.7112)
		(drill 0.4064)
		(layers "F.Cu" "B.Cu")
		(net "GND")
	)
	(via
		(at 348.956376 -1.524)
		(size 0.7112)
		(drill 0.4064)
		(layers "F.Cu" "B.Cu")
		(net "GND")
	)
	(via
		(at 261.144004 -384.457956)
		(size 0.7112)
		(drill 0.4064)
		(layers "F.Cu" "B.Cu")
		(net "GND")
	)
	(via
		(at 1.524 -260.753352)
		(size 0.7112)
		(drill 0.4064)
		(layers "F.Cu" "B.Cu")
		(net "GND")
	)
	(via
		(at 307.788056 -335.35874)
		(size 0.6604)
		(drill 0.3302)
		(layers "F.Cu" "B.Cu")
		(net "GND")
	)
	(via
		(at 406.327864 -378.476002)
		(size 0.7112)
		(drill 0.4064)
		(layers "F.Cu" "B.Cu")
		(net "GND")
	)
	(via
		(at 181.991 -47.244)
		(size 0.5588)
		(drill 0.3048)
		(layers "F.Cu" "B.Cu")
		(net "GND")
	)
	(via
		(at 67.1195 -261.239)
		(size 0.5588)
		(drill 0.3048)
		(layers "F.Cu" "B.Cu")
		(net "GND")
	)
	(via
		(at 54.864 -126.492)
		(size 0.5588)
		(drill 0.3048)
		(layers "F.Cu" "B.Cu")
		(net "GND")
	)
	(via
		(at 462.788 -366.776)
		(size 0.5588)
		(drill 0.3048)
		(layers "F.Cu" "B.Cu")
		(net "GND")
	)
	(via
		(at 144.907 -260.604)
		(size 0.5588)
		(drill 0.3048)
		(layers "F.Cu" "B.Cu")
		(net "GND")
	)
	(via
		(at 176.403 -30.607)
		(size 0.5588)
		(drill 0.3048)
		(layers "F.Cu" "B.Cu")
		(net "GND")
	)
	(via
		(at 489.926122 -209.29219)
		(size 0.7112)
		(drill 0.4064)
		(layers "F.Cu" "B.Cu")
		(net "GND")
	)
	(via
		(at 408.432 -12.7)
		(size 0.5588)
		(drill 0.3048)
		(layers "F.Cu" "B.Cu")
		(net "GND")
	)
	(via
		(at 489.926122 -98.80219)
		(size 0.7112)
		(drill 0.4064)
		(layers "F.Cu" "B.Cu")
		(net "GND")
	)
	(via
		(at 1.524 -225.193352)
		(size 0.7112)
		(drill 0.4064)
		(layers "F.Cu" "B.Cu")
		(net "GND")
	)
	(via
		(at 91.404948 -13.035026)
		(size 0.5588)
		(drill 0.3048)
		(layers "F.Cu" "B.Cu")
		(net "GND")
	)
	(via
		(at 52.174648 -1.524)
		(size 0.7112)
		(drill 0.4064)
		(layers "F.Cu" "B.Cu")
		(net "GND")
	)
	(via
		(at 8.082026 -384.47599)
		(size 0.7112)
		(drill 0.4064)
		(layers "F.Cu" "B.Cu")
		(net "GND")
	)
	(via
		(at 1.524 -38.503352)
		(size 0.7112)
		(drill 0.4064)
		(layers "F.Cu" "B.Cu")
		(net "GND")
	)
	(via
		(at 489.926122 -230.88219)
		(size 0.7112)
		(drill 0.4064)
		(layers "F.Cu" "B.Cu")
		(net "GND")
	)
	(via
		(at 325.654924 -263.355074)
		(size 0.5588)
		(drill 0.3048)
		(layers "F.Cu" "B.Cu")
		(net "GND")
	)
	(via
		(at 156.282898 -7.035038)
		(size 0.5588)
		(drill 0.3048)
		(layers "F.Cu" "B.Cu")
		(net "GND")
	)
	(via
		(at 274.32 -312.42)
		(size 0.5588)
		(drill 0.3048)
		(layers "F.Cu" "B.Cu")
		(net "GND")
	)
	(via
		(at 1.524 -121.053352)
		(size 0.7112)
		(drill 0.4064)
		(layers "F.Cu" "B.Cu")
		(net "GND")
	)
	(via
		(at 186.055 -33.355026)
		(size 0.5588)
		(drill 0.3048)
		(layers "F.Cu" "B.Cu")
		(net "GND")
	)
	(via
		(at 46.438058 -111.700056)
		(size 0.5588)
		(drill 0.3048)
		(layers "F.Cu" "B.Cu")
		(net "GND")
	)
	(via
		(at 114.3 -304.8)
		(size 0.5588)
		(drill 0.3048)
		(layers "F.Cu" "B.Cu")
		(net "GND")
	)
	(via
		(at 459.446376 -1.524)
		(size 0.7112)
		(drill 0.4064)
		(layers "F.Cu" "B.Cu")
		(net "GND")
	)
	(via
		(at 489.926122 -361.69219)
		(size 0.7112)
		(drill 0.4064)
		(layers "F.Cu" "B.Cu")
		(net "GND")
	)
	(via
		(at 489.926122 -56.89219)
		(size 0.7112)
		(drill 0.4064)
		(layers "F.Cu" "B.Cu")
		(net "GND")
	)
	(via
		(at 392.938 -39.680388)
		(size 0.5588)
		(drill 0.3048)
		(layers "F.Cu" "B.Cu")
		(net "GND")
	)
	(via
		(at 144.763998 -384.47599)
		(size 0.7112)
		(drill 0.4064)
		(layers "F.Cu" "B.Cu")
		(net "GND")
	)
	(via
		(at 1.524 -154.073352)
		(size 0.7112)
		(drill 0.4064)
		(layers "F.Cu" "B.Cu")
		(net "GND")
	)
	(via
		(at 125.834648 -1.524)
		(size 0.7112)
		(drill 0.4064)
		(layers "F.Cu" "B.Cu")
		(net "GND")
	)
	(via
		(at 357.205026 -250.655074)
		(size 0.5588)
		(drill 0.3048)
		(layers "F.Cu" "B.Cu")
		(net "GND")
	)
	(via
		(at 329.819 -142.875)
		(size 0.5588)
		(drill 0.3048)
		(layers "F.Cu" "B.Cu")
		(net "GND")
	)
	(via
		(at 420.304976 -16.845026)
		(size 0.5588)
		(drill 0.3048)
		(layers "F.Cu" "B.Cu")
		(net "GND")
	)
	(via
		(at 39.987982 -384.47599)
		(size 0.7112)
		(drill 0.4064)
		(layers "F.Cu" "B.Cu")
		(net "GND")
	)
	(via
		(at 20.701 -256.667)
		(size 0.5588)
		(drill 0.3048)
		(layers "F.Cu" "B.Cu")
		(net "GND")
	)
	(via
		(at 325.654924 -270.975074)
		(size 0.5588)
		(drill 0.3048)
		(layers "F.Cu" "B.Cu")
		(net "GND")
	)
	(via
		(at 26.434796 -371.475)
		(size 0.5588)
		(drill 0.3048)
		(layers "F.Cu" "B.Cu")
		(net "GND")
	)
	(via
		(at 434.585872 -384.47599)
		(size 0.7112)
		(drill 0.4064)
		(layers "F.Cu" "B.Cu")
		(net "GND")
	)
	(via
		(at 363.601 -12.319)
		(size 0.5588)
		(drill 0.3048)
		(layers "F.Cu" "B.Cu")
		(net "GND")
	)
	(via
		(at 325.654924 -260.815074)
		(size 0.5588)
		(drill 0.3048)
		(layers "F.Cu" "B.Cu")
		(net "GND")
	)
	(via
		(at 153.361898 -23.830026)
		(size 0.5588)
		(drill 0.3048)
		(layers "F.Cu" "B.Cu")
		(net "GND")
	)
	(via
		(at 50.038 -33.782)
		(size 0.5588)
		(drill 0.3048)
		(layers "F.Cu" "B.Cu")
		(net "GND")
	)
	(via
		(at 142.5575 -255.016)
		(size 0.5588)
		(drill 0.3048)
		(layers "F.Cu" "B.Cu")
		(net "GND")
	)
	(via
		(at 101.26599 -378.476002)
		(size 0.7112)
		(drill 0.4064)
		(layers "F.Cu" "B.Cu")
		(net "GND")
	)
	(via
		(at 405.057864 -378.476002)
		(size 0.7112)
		(drill 0.4064)
		(layers "F.Cu" "B.Cu")
		(net "GND")
	)
	(via
		(at 388.754874 -246.845074)
		(size 0.5588)
		(drill 0.3048)
		(layers "F.Cu" "B.Cu")
		(net "GND")
	)
	(via
		(at 319.746376 -1.524)
		(size 0.7112)
		(drill 0.4064)
		(layers "F.Cu" "B.Cu")
		(net "GND")
	)
	(via
		(at 233.265726 -234.507532)
		(size 0.5588)
		(drill 0.3048)
		(layers "F.Cu" "B.Cu")
		(net "GND")
	)
	(via
		(at 188.099954 -384.47599)
		(size 0.7112)
		(drill 0.4064)
		(layers "F.Cu" "B.Cu")
		(net "GND")
	)
	(via
		(at 57.785 -330.962)
		(size 0.5588)
		(drill 0.3048)
		(layers "F.Cu" "B.Cu")
		(net "GND")
	)
	(via
		(at 330.589636 -363.56163)
		(size 0.5588)
		(drill 0.3048)
		(layers "F.Cu" "B.Cu")
		(net "GND")
	)
	(via
		(at 30.584648 -1.524)
		(size 0.7112)
		(drill 0.4064)
		(layers "F.Cu" "B.Cu")
		(net "GND")
	)
	(via
		(at 1.524 -117.243352)
		(size 0.7112)
		(drill 0.4064)
		(layers "F.Cu" "B.Cu")
		(net "GND")
	)
	(via
		(at 438.301384 -115.616228)
		(size 0.5588)
		(drill 0.3048)
		(layers "F.Cu" "B.Cu")
		(net "GND")
	)
	(via
		(at 478.8408 -20.574)
		(size 0.5588)
		(drill 0.3048)
		(layers "F.Cu" "B.Cu")
		(net "GND")
	)
	(via
		(at 470.281 -43.561)
		(size 0.5588)
		(drill 0.3048)
		(layers "F.Cu" "B.Cu")
		(net "GND")
	)
	(via
		(at 64.13246 -121.688606)
		(size 0.5588)
		(drill 0.3048)
		(layers "F.Cu" "B.Cu")
		(net "GND")
	)
	(via
		(at 485.182926 -237.035086)
		(size 0.5588)
		(drill 0.3048)
		(layers "F.Cu" "B.Cu")
		(net "GND")
	)
	(via
		(at 28.304998 -13.035026)
		(size 0.5588)
		(drill 0.3048)
		(layers "F.Cu" "B.Cu")
		(net "GND")
	)
	(via
		(at 82.804 -280.924)
		(size 0.5588)
		(drill 0.3048)
		(layers "F.Cu" "B.Cu")
		(net "GND")
	)
	(via
		(at 355.219 -384.429)
		(size 0.7112)
		(drill 0.4064)
		(layers "F.Cu" "B.Cu")
		(net "GND")
	)
	(via
		(at 46.438058 -112.716056)
		(size 0.5588)
		(drill 0.3048)
		(layers "F.Cu" "B.Cu")
		(net "GND")
	)
	(via
		(at 355.6 -304.8)
		(size 0.5588)
		(drill 0.3048)
		(layers "F.Cu" "B.Cu")
		(net "GND")
	)
	(via
		(at 245.567962 -378.476002)
		(size 0.7112)
		(drill 0.4064)
		(layers "F.Cu" "B.Cu")
		(net "GND")
	)
	(via
		(at 1.524 -324.253352)
		(size 0.7112)
		(drill 0.4064)
		(layers "F.Cu" "B.Cu")
		(net "GND")
	)
	(via
		(at 44.069 -35.687)
		(size 0.5588)
		(drill 0.3048)
		(layers "F.Cu" "B.Cu")
		(net "GND")
	)
	(via
		(at 191.2747 -261.239)
		(size 0.5588)
		(drill 0.3048)
		(layers "F.Cu" "B.Cu")
		(net "GND")
	)
	(via
		(at 426.085 -47.117)
		(size 0.5588)
		(drill 0.3048)
		(layers "F.Cu" "B.Cu")
		(net "GND")
	)
	(via
		(at 41.148 -155.956)
		(size 0.5588)
		(drill 0.3048)
		(layers "F.Cu" "B.Cu")
		(net "GND")
	)
	(via
		(at 284.448758 -103.650288)
		(size 0.7112)
		(drill 0.4064)
		(layers "F.Cu" "B.Cu")
		(net "GND")
	)
	(via
		(at 1.524 -251.863352)
		(size 0.7112)
		(drill 0.4064)
		(layers "F.Cu" "B.Cu")
		(net "GND")
	)
	(via
		(at 1.524 -190.903352)
		(size 0.7112)
		(drill 0.4064)
		(layers "F.Cu" "B.Cu")
		(net "GND")
	)
	(via
		(at 312.523886 -32.40151)
		(size 0.7112)
		(drill 0.4064)
		(layers "F.Cu" "B.Cu")
		(net "GND")
	)
	(via
		(at 362.17606 -383.568194)
		(size 0.7112)
		(drill 0.4064)
		(layers "F.Cu" "B.Cu")
		(net "GND")
	)
	(via
		(at 489.926122 -28.95219)
		(size 0.7112)
		(drill 0.4064)
		(layers "F.Cu" "B.Cu")
		(net "GND")
	)
	(via
		(at 489.926122 -84.83219)
		(size 0.7112)
		(drill 0.4064)
		(layers "F.Cu" "B.Cu")
		(net "GND")
	)
	(via
		(at 25.4 -330.2)
		(size 0.5588)
		(drill 0.3048)
		(layers "F.Cu" "B.Cu")
		(net "GND")
	)
	(via
		(at 287.241742 -379.945392)
		(size 0.5588)
		(drill 0.3048)
		(layers "F.Cu" "B.Cu")
		(net "GND")
	)
	(via
		(at 152.8572 -242.697)
		(size 0.5588)
		(drill 0.3048)
		(layers "F.Cu" "B.Cu")
		(net "GND")
	)
	(via
		(at 383.032 -9.144)
		(size 0.5588)
		(drill 0.3048)
		(layers "F.Cu" "B.Cu")
		(net "GND")
	)
	(via
		(at 489.926122 -94.99219)
		(size 0.7112)
		(drill 0.4064)
		(layers "F.Cu" "B.Cu")
		(net "GND")
	)
	(via
		(at 364.5408 -14.859)
		(size 0.5588)
		(drill 0.3048)
		(layers "F.Cu" "B.Cu")
		(net "GND")
	)
	(via
		(at 1.524 -32.153352)
		(size 0.7112)
		(drill 0.4064)
		(layers "F.Cu" "B.Cu")
		(net "GND")
	)
	(via
		(at 22.352 -240.284)
		(size 0.5588)
		(drill 0.3048)
		(layers "F.Cu" "B.Cu")
		(net "GND")
	)
	(via
		(at 205.476094 -57.576212)
		(size 0.7112)
		(drill 0.4064)
		(layers "F.Cu" "B.Cu")
		(net "GND")
	)
	(via
		(at 489.926122 -340.10219)
		(size 0.7112)
		(drill 0.4064)
		(layers "F.Cu" "B.Cu")
		(net "GND")
	)
	(via
		(at 59.794648 -1.524)
		(size 0.7112)
		(drill 0.4064)
		(layers "F.Cu" "B.Cu")
		(net "GND")
	)
	(via
		(at 473.6338 -148.717)
		(size 0.5588)
		(drill 0.3048)
		(layers "F.Cu" "B.Cu")
		(net "GND")
	)
	(via
		(at 388.754874 -33.355026)
		(size 0.5588)
		(drill 0.3048)
		(layers "F.Cu" "B.Cu")
		(net "GND")
	)
	(via
		(at 427.6598 -244.856)
		(size 0.5588)
		(drill 0.3048)
		(layers "F.Cu" "B.Cu")
		(net "GND")
	)
	(via
		(at 170.434 -164.592)
		(size 0.5588)
		(drill 0.3048)
		(layers "F.Cu" "B.Cu")
		(net "GND")
	)
	(via
		(at 76.2 -355.6)
		(size 0.5588)
		(drill 0.3048)
		(layers "F.Cu" "B.Cu")
		(net "GND")
	)
	(via
		(at 250.647962 -378.476002)
		(size 0.7112)
		(drill 0.4064)
		(layers "F.Cu" "B.Cu")
		(net "GND")
	)
	(via
		(at 291.778436 -49.724056)
		(size 0.7112)
		(drill 0.4064)
		(layers "F.Cu" "B.Cu")
		(net "GND")
	)
	(via
		(at 130.429 -256.286)
		(size 0.5588)
		(drill 0.3048)
		(layers "F.Cu" "B.Cu")
		(net "GND")
	)
	(via
		(at 330.835 -38.608)
		(size 0.5588)
		(drill 0.3048)
		(layers "F.Cu" "B.Cu")
		(net "GND")
	)
	(via
		(at 238.4552 -281.7622)
		(size 0.7112)
		(drill 0.4064)
		(layers "F.Cu" "B.Cu")
		(net "GND")
	)
	(via
		(at 63.5 -177.8)
		(size 0.5588)
		(drill 0.3048)
		(layers "F.Cu" "B.Cu")
		(net "GND")
	)
	(via
		(at 122.954796 -250.655074)
		(size 0.5588)
		(drill 0.3048)
		(layers "F.Cu" "B.Cu")
		(net "GND")
	)
	(via
		(at 320.666872 -26.230072)
		(size 0.5588)
		(drill 0.3048)
		(layers "F.Cu" "B.Cu")
		(net "GND")
	)
	(via
		(at 422.082976 -122.035062)
		(size 0.5588)
		(drill 0.3048)
		(layers "F.Cu" "B.Cu")
		(net "GND")
	)
	(via
		(at 181.1655 -135.382)
		(size 0.5588)
		(drill 0.3048)
		(layers "F.Cu" "B.Cu")
		(net "GND")
	)
	(via
		(at 1.524 -222.653352)
		(size 0.7112)
		(drill 0.4064)
		(layers "F.Cu" "B.Cu")
		(net "GND")
	)
	(via
		(at 354.10394 -146.18462)
		(size 0.5588)
		(drill 0.3048)
		(layers "F.Cu" "B.Cu")
		(net "GND")
	)
	(via
		(at 9.652 -114.808)
		(size 0.5588)
		(drill 0.3048)
		(layers "F.Cu" "B.Cu")
		(net "GND")
	)
	(via
		(at 318.008 -90.932)
		(size 0.5588)
		(drill 0.3048)
		(layers "F.Cu" "B.Cu")
		(net "GND")
	)
	(via
		(at 489.926122 -150.87219)
		(size 0.7112)
		(drill 0.4064)
		(layers "F.Cu" "B.Cu")
		(net "GND")
	)
	(via
		(at 481.036376 -1.524)
		(size 0.7112)
		(drill 0.4064)
		(layers "F.Cu" "B.Cu")
		(net "GND")
	)
	(via
		(at 324.511924 -256.23012)
		(size 0.5588)
		(drill 0.3048)
		(layers "F.Cu" "B.Cu")
		(net "GND")
	)
	(via
		(at 1.524 -156.613352)
		(size 0.7112)
		(drill 0.4064)
		(layers "F.Cu" "B.Cu")
		(net "GND")
	)
	(via
		(at 122.024648 -1.524)
		(size 0.7112)
		(drill 0.4064)
		(layers "F.Cu" "B.Cu")
		(net "GND")
	)
	(via
		(at 425.45 -153.67)
		(size 0.5588)
		(drill 0.3048)
		(layers "F.Cu" "B.Cu")
		(net "GND")
	)
	(via
		(at 475.273878 -383.31394)
		(size 0.7112)
		(drill 0.4064)
		(layers "F.Cu" "B.Cu")
		(net "GND")
	)
	(via
		(at 488.656376 -1.524)
		(size 0.7112)
		(drill 0.4064)
		(layers "F.Cu" "B.Cu")
		(net "GND")
	)
	(via
		(at 457.2762 -132.715)
		(size 0.5588)
		(drill 0.3048)
		(layers "F.Cu" "B.Cu")
		(net "GND")
	)
	(via
		(at 305.044348 -358.907842)
		(size 0.5588)
		(drill 0.3048)
		(layers "F.Cu" "B.Cu")
		(net "GND")
	)
	(via
		(at 437.896 -107.188)
		(size 0.5588)
		(drill 0.3048)
		(layers "F.Cu" "B.Cu")
		(net "GND")
	)
	(via
		(at 144.884648 -1.524)
		(size 0.7112)
		(drill 0.4064)
		(layers "F.Cu" "B.Cu")
		(net "GND")
	)
	(via
		(at 398.707864 -378.476002)
		(size 0.7112)
		(drill 0.4064)
		(layers "F.Cu" "B.Cu")
		(net "GND")
	)
	(via
		(at 422.082976 -280.785062)
		(size 0.5588)
		(drill 0.3048)
		(layers "F.Cu" "B.Cu")
		(net "GND")
	)
	(via
		(at 1.524 -281.073352)
		(size 0.7112)
		(drill 0.4064)
		(layers "F.Cu" "B.Cu")
		(net "GND")
	)
	(via
		(at 357.846376 -1.524)
		(size 0.7112)
		(drill 0.4064)
		(layers "F.Cu" "B.Cu")
		(net "GND")
	)
	(via
		(at 483.616 -382.016)
		(size 0.5588)
		(drill 0.3048)
		(layers "F.Cu" "B.Cu")
		(net "GND")
	)
	(via
		(at 1.524 -348.383352)
		(size 0.7112)
		(drill 0.4064)
		(layers "F.Cu" "B.Cu")
		(net "GND")
	)
	(via
		(at 489.926122 -79.75219)
		(size 0.7112)
		(drill 0.4064)
		(layers "F.Cu" "B.Cu")
		(net "GND")
	)
	(via
		(at 458.216 -242.316)
		(size 0.5588)
		(drill 0.3048)
		(layers "F.Cu" "B.Cu")
		(net "GND")
	)
	(via
		(at 489.926122 -309.62219)
		(size 0.7112)
		(drill 0.4064)
		(layers "F.Cu" "B.Cu")
		(net "GND")
	)
	(via
		(at 140.953998 -384.47599)
		(size 0.7112)
		(drill 0.4064)
		(layers "F.Cu" "B.Cu")
		(net "GND")
	)
	(via
		(at 260.36651 -227.82911)
		(size 0.5588)
		(drill 0.3048)
		(layers "F.Cu" "B.Cu")
		(net "GND")
	)
	(via
		(at 402.907246 -211.310728)
		(size 0.5588)
		(drill 0.3048)
		(layers "F.Cu" "B.Cu")
		(net "GND")
	)
	(via
		(at 53.848 -59.944)
		(size 0.5588)
		(drill 0.3048)
		(layers "F.Cu" "B.Cu")
		(net "GND")
	)
	(via
		(at 225.247962 -378.476002)
		(size 0.7112)
		(drill 0.4064)
		(layers "F.Cu" "B.Cu")
		(net "GND")
	)
	(via
		(at 459.3844 -19.8628)
		(size 0.5588)
		(drill 0.3048)
		(layers "F.Cu" "B.Cu")
		(net "GND")
	)
	(via
		(at 312.523886 -17.16151)
		(size 0.7112)
		(drill 0.4064)
		(layers "F.Cu" "B.Cu")
		(net "GND")
	)
	(via
		(at 197.47611 -4.812538)
		(size 0.7112)
		(drill 0.4064)
		(layers "F.Cu" "B.Cu")
		(net "GND")
	)
	(via
		(at 81.788 -260.604)
		(size 0.5588)
		(drill 0.3048)
		(layers "F.Cu" "B.Cu")
		(net "GND")
	)
	(via
		(at 235.204 -360.68)
		(size 0.5588)
		(drill 0.3048)
		(layers "F.Cu" "B.Cu")
		(net "GND")
	)
	(via
		(at 471.3605 -139.954)
		(size 0.5588)
		(drill 0.3048)
		(layers "F.Cu" "B.Cu")
		(net "GND")
	)
	(via
		(at 118.0465 -135.382)
		(size 0.5588)
		(drill 0.3048)
		(layers "F.Cu" "B.Cu")
		(net "GND")
	)
	(via
		(at 288.9504 -133.8834)
		(size 0.6604)
		(drill 0.3556)
		(layers "F.Cu" "B.Cu")
		(net "GND")
	)
	(via
		(at 444.487808 -103.08082)
		(size 0.5588)
		(drill 0.3048)
		(layers "F.Cu" "B.Cu")
		(net "GND")
	)
	(via
		(at 322.561204 -101.774498)
		(size 0.5588)
		(drill 0.3048)
		(layers "F.Cu" "B.Cu")
		(net "GND")
	)
	(via
		(at 489.926122 -277.87219)
		(size 0.7112)
		(drill 0.4064)
		(layers "F.Cu" "B.Cu")
		(net "GND")
	)
	(via
		(at 282.888436 -49.724056)
		(size 0.7112)
		(drill 0.4064)
		(layers "F.Cu" "B.Cu")
		(net "GND")
	)
	(via
		(at 12.573 -35.687)
		(size 0.5588)
		(drill 0.3048)
		(layers "F.Cu" "B.Cu")
		(net "GND")
	)
	(via
		(at 357.205026 -263.355074)
		(size 0.5588)
		(drill 0.3048)
		(layers "F.Cu" "B.Cu")
		(net "GND")
	)
	(via
		(at 112.176814 -145.831814)
		(size 0.5588)
		(drill 0.3048)
		(layers "F.Cu" "B.Cu")
		(net "GND")
	)
	(via
		(at 83.82 -256.667)
		(size 0.5588)
		(drill 0.3048)
		(layers "F.Cu" "B.Cu")
		(net "GND")
	)
	(via
		(at 67.73926 -121.688606)
		(size 0.5588)
		(drill 0.3048)
		(layers "F.Cu" "B.Cu")
		(net "GND")
	)
	(via
		(at 59.854846 -16.845026)
		(size 0.5588)
		(drill 0.3048)
		(layers "F.Cu" "B.Cu")
		(net "GND")
	)
	(via
		(at 442.205872 -384.47599)
		(size 0.7112)
		(drill 0.4064)
		(layers "F.Cu" "B.Cu")
		(net "GND")
	)
	(via
		(at 1.524 -322.983352)
		(size 0.7112)
		(drill 0.4064)
		(layers "F.Cu" "B.Cu")
		(net "GND")
	)
	(via
		(at 91.544648 -1.524)
		(size 0.7112)
		(drill 0.4064)
		(layers "F.Cu" "B.Cu")
		(net "GND")
	)
	(via
		(at 351.536 -198.628)
		(size 0.5588)
		(drill 0.3048)
		(layers "F.Cu" "B.Cu")
		(net "GND")
	)
	(via
		(at 186.055 -20.655026)
		(size 0.5588)
		(drill 0.3048)
		(layers "F.Cu" "B.Cu")
		(net "GND")
	)
	(via
		(at 489.926122 -280.41219)
		(size 0.7112)
		(drill 0.4064)
		(layers "F.Cu" "B.Cu")
		(net "GND")
	)
	(via
		(at 314.904882 -380.775972)
		(size 0.7112)
		(drill 0.4064)
		(layers "F.Cu" "B.Cu")
		(net "GND")
	)
	(via
		(at 459.613 -47.117)
		(size 0.5588)
		(drill 0.3048)
		(layers "F.Cu" "B.Cu")
		(net "GND")
	)
	(via
		(at 1.524 -49.933352)
		(size 0.7112)
		(drill 0.4064)
		(layers "F.Cu" "B.Cu")
		(net "GND")
	)
	(via
		(at 332.105 -52.07)
		(size 0.5588)
		(drill 0.3048)
		(layers "F.Cu" "B.Cu")
		(net "GND")
	)
	(via
		(at 288.911284 -213.494366)
		(size 0.6604)
		(drill 0.3556)
		(layers "F.Cu" "B.Cu")
		(net "GND")
	)
	(via
		(at 142.223998 -384.47599)
		(size 0.7112)
		(drill 0.4064)
		(layers "F.Cu" "B.Cu")
		(net "GND")
	)
	(via
		(at 1.524 -309.013352)
		(size 0.7112)
		(drill 0.4064)
		(layers "F.Cu" "B.Cu")
		(net "GND")
	)
	(via
		(at 489.926122 -270.25219)
		(size 0.7112)
		(drill 0.4064)
		(layers "F.Cu" "B.Cu")
		(net "GND")
	)
	(via
		(at 243.078 -306.705)
		(size 0.5588)
		(drill 0.3048)
		(layers "F.Cu" "B.Cu")
		(net "GND")
	)
	(via
		(at 469.9 -292.1)
		(size 0.5588)
		(drill 0.3048)
		(layers "F.Cu" "B.Cu")
		(net "GND")
	)
	(via
		(at 288.911284 -220.694504)
		(size 0.6604)
		(drill 0.3556)
		(layers "F.Cu" "B.Cu")
		(net "GND")
	)
	(via
		(at 95.19412 -358.292146)
		(size 0.7112)
		(drill 0.4064)
		(layers "F.Cu" "B.Cu")
		(net "GND")
	)
	(via
		(at 489.926122 -89.91219)
		(size 0.7112)
		(drill 0.4064)
		(layers "F.Cu" "B.Cu")
		(net "GND")
	)
	(via
		(at 489.926122 -215.64219)
		(size 0.7112)
		(drill 0.4064)
		(layers "F.Cu" "B.Cu")
		(net "GND")
	)
	(via
		(at 67.758056 -105.031286)
		(size 0.5588)
		(drill 0.3048)
		(layers "F.Cu" "B.Cu")
		(net "GND")
	)
	(via
		(at 489.926122 -221.99219)
		(size 0.7112)
		(drill 0.4064)
		(layers "F.Cu" "B.Cu")
		(net "GND")
	)
	(via
		(at 99.164648 -1.524)
		(size 0.7112)
		(drill 0.4064)
		(layers "F.Cu" "B.Cu")
		(net "GND")
	)
	(via
		(at 1.524 -253.133352)
		(size 0.7112)
		(drill 0.4064)
		(layers "F.Cu" "B.Cu")
		(net "GND")
	)
	(via
		(at 122.954796 -145.81505)
		(size 0.5588)
		(drill 0.3048)
		(layers "F.Cu" "B.Cu")
		(net "GND")
	)
	(via
		(at 318.356996 -370.6622)
		(size 0.5588)
		(drill 0.3048)
		(layers "F.Cu" "B.Cu")
		(net "GND")
	)
	(via
		(at 388.754874 -155.97505)
		(size 0.5588)
		(drill 0.3048)
		(layers "F.Cu" "B.Cu")
		(net "GND")
	)
	(via
		(at 14.432026 -384.47599)
		(size 0.7112)
		(drill 0.4064)
		(layers "F.Cu" "B.Cu")
		(net "GND")
	)
	(via
		(at 59.854846 -33.355026)
		(size 0.5588)
		(drill 0.3048)
		(layers "F.Cu" "B.Cu")
		(net "GND")
	)
	(via
		(at 460.07147 -37.590476)
		(size 0.5588)
		(drill 0.3048)
		(layers "F.Cu" "B.Cu")
		(net "GND")
	)
	(via
		(at 148.717 -11.43)
		(size 0.5588)
		(drill 0.3048)
		(layers "F.Cu" "B.Cu")
		(net "GND")
	)
	(via
		(at 445.476376 -1.524)
		(size 0.7112)
		(drill 0.4064)
		(layers "F.Cu" "B.Cu")
		(net "GND")
	)
	(via
		(at 154.504898 -263.355074)
		(size 0.5588)
		(drill 0.3048)
		(layers "F.Cu" "B.Cu")
		(net "GND")
	)
	(via
		(at 300.709076 -342.077802)
		(size 0.5588)
		(drill 0.3048)
		(layers "F.Cu" "B.Cu")
		(net "GND")
	)
	(via
		(at 93.182948 -50.785014)
		(size 0.5588)
		(drill 0.3048)
		(layers "F.Cu" "B.Cu")
		(net "GND")
	)
	(via
		(at 288.911284 -177.494692)
		(size 0.6604)
		(drill 0.3556)
		(layers "F.Cu" "B.Cu")
		(net "GND")
	)
	(via
		(at 485.182926 -165.785038)
		(size 0.5588)
		(drill 0.3048)
		(layers "F.Cu" "B.Cu")
		(net "GND")
	)
	(via
		(at 352.552 -96.012)
		(size 0.5588)
		(drill 0.3048)
		(layers "F.Cu" "B.Cu")
		(net "GND")
	)
	(via
		(at 81.5848 -263.779)
		(size 0.5588)
		(drill 0.3048)
		(layers "F.Cu" "B.Cu")
		(net "GND")
	)
	(via
		(at 339.807296 -96.310704)
		(size 0.5588)
		(drill 0.3048)
		(layers "F.Cu" "B.Cu")
		(net "GND")
	)
	(via
		(at 284.821884 -335.197704)
		(size 0.5588)
		(drill 0.3048)
		(layers "F.Cu" "B.Cu")
		(net "GND")
	)
	(via
		(at 121.811796 -136.430004)
		(size 0.5588)
		(drill 0.3048)
		(layers "F.Cu" "B.Cu")
		(net "GND")
	)
	(via
		(at 426.72 -242.316)
		(size 0.5588)
		(drill 0.3048)
		(layers "F.Cu" "B.Cu")
		(net "GND")
	)
	(via
		(at 407.376376 -1.524)
		(size 0.7112)
		(drill 0.4064)
		(layers "F.Cu" "B.Cu")
		(net "GND")
	)
	(via
		(at 206.5274 -304.1142)
		(size 0.7112)
		(drill 0.4064)
		(layers "F.Cu" "B.Cu")
		(net "GND")
	)
	(via
		(at 483.404926 -263.355074)
		(size 0.5588)
		(drill 0.3048)
		(layers "F.Cu" "B.Cu")
		(net "GND")
	)
	(via
		(at 458.216 -225.933)
		(size 0.5588)
		(drill 0.3048)
		(layers "F.Cu" "B.Cu")
		(net "GND")
	)
	(via
		(at 30.082998 -237.035086)
		(size 0.5588)
		(drill 0.3048)
		(layers "F.Cu" "B.Cu")
		(net "GND")
	)
	(via
		(at 456.7174 -136.645142)
		(size 0.5588)
		(drill 0.3048)
		(layers "F.Cu" "B.Cu")
		(net "GND")
	)
	(via
		(at 121.811796 -141.230096)
		(size 0.5588)
		(drill 0.3048)
		(layers "F.Cu" "B.Cu")
		(net "GND")
	)
	(via
		(at 197.47611 -6.082538)
		(size 0.7112)
		(drill 0.4064)
		(layers "F.Cu" "B.Cu")
		(net "GND")
	)
	(via
		(at 331.47 -277.114)
		(size 0.5588)
		(drill 0.3048)
		(layers "F.Cu" "B.Cu")
		(net "GND")
	)
	(via
		(at 1.524 -20.723352)
		(size 0.7112)
		(drill 0.4064)
		(layers "F.Cu" "B.Cu")
		(net "GND")
	)
	(via
		(at 312.523886 -31.13151)
		(size 0.7112)
		(drill 0.4064)
		(layers "F.Cu" "B.Cu")
		(net "GND")
	)
	(via
		(at 342.9 -292.1)
		(size 0.5588)
		(drill 0.3048)
		(layers "F.Cu" "B.Cu")
		(net "GND")
	)
	(via
		(at 311.404 -364.744)
		(size 0.5588)
		(drill 0.3048)
		(layers "F.Cu" "B.Cu")
		(net "GND")
	)
	(via
		(at 58.711846 -138.83005)
		(size 0.5588)
		(drill 0.3048)
		(layers "F.Cu" "B.Cu")
		(net "GND")
	)
	(via
		(at 9.652 -252.984)
		(size 0.5588)
		(drill 0.3048)
		(layers "F.Cu" "B.Cu")
		(net "GND")
	)
	(via
		(at 4.445 -384.048)
		(size 0.7112)
		(drill 0.4064)
		(layers "F.Cu" "B.Cu")
		(net "GND")
	)
	(via
		(at 1.524 -366.163352)
		(size 0.7112)
		(drill 0.4064)
		(layers "F.Cu" "B.Cu")
		(net "GND")
	)
	(via
		(at 153.361898 -141.230096)
		(size 0.5588)
		(drill 0.3048)
		(layers "F.Cu" "B.Cu")
		(net "GND")
	)
	(via
		(at 372.25097 -216.759028)
		(size 0.5588)
		(drill 0.3048)
		(layers "F.Cu" "B.Cu")
		(net "GND")
	)
	(via
		(at 63.5 -88.9)
		(size 0.5588)
		(drill 0.3048)
		(layers "F.Cu" "B.Cu")
		(net "GND")
	)
	(via
		(at 312.523886 -19.70151)
		(size 0.7112)
		(drill 0.4064)
		(layers "F.Cu" "B.Cu")
		(net "GND")
	)
	(via
		(at 4.523994 -376.604022)
		(size 0.7112)
		(drill 0.4064)
		(layers "F.Cu" "B.Cu")
		(net "GND")
	)
	(via
		(at 435.61 -77.597)
		(size 0.5588)
		(drill 0.3048)
		(layers "F.Cu" "B.Cu")
		(net "GND")
	)
	(via
		(at 312.523886 -20.97151)
		(size 0.7112)
		(drill 0.4064)
		(layers "F.Cu" "B.Cu")
		(net "GND")
	)
	(via
		(at 466.007196 -211.310728)
		(size 0.5588)
		(drill 0.3048)
		(layers "F.Cu" "B.Cu")
		(net "GND")
	)
	(via
		(at 300.668436 -49.724056)
		(size 0.7112)
		(drill 0.4064)
		(layers "F.Cu" "B.Cu")
		(net "GND")
	)
	(via
		(at 232.208832 -234.766866)
		(size 0.5588)
		(drill 0.3048)
		(layers "F.Cu" "B.Cu")
		(net "GND")
	)
	(via
		(at 239.8268 -275.1074)
		(size 0.7112)
		(drill 0.4064)
		(layers "F.Cu" "B.Cu")
		(net "GND")
	)
	(via
		(at 58.711846 -253.830074)
		(size 0.5588)
		(drill 0.3048)
		(layers "F.Cu" "B.Cu")
		(net "GND")
	)
	(via
		(at 325.654924 -16.845026)
		(size 0.5588)
		(drill 0.3048)
		(layers "F.Cu" "B.Cu")
		(net "GND")
	)
	(via
		(at 447.04 -354.076)
		(size 0.5588)
		(drill 0.3048)
		(layers "F.Cu" "B.Cu")
		(net "GND")
	)
	(via
		(at 484.846376 -1.524)
		(size 0.7112)
		(drill 0.4064)
		(layers "F.Cu" "B.Cu")
		(net "GND")
	)
	(via
		(at 181.991 -277.241)
		(size 0.5588)
		(drill 0.3048)
		(layers "F.Cu" "B.Cu")
		(net "GND")
	)
	(via
		(at 420.304976 -38.435026)
		(size 0.5588)
		(drill 0.3048)
		(layers "F.Cu" "B.Cu")
		(net "GND")
	)
	(via
		(at 489.926122 -285.49219)
		(size 0.7112)
		(drill 0.4064)
		(layers "F.Cu" "B.Cu")
		(net "GND")
	)
	(via
		(at 455.93 -277.114)
		(size 0.5588)
		(drill 0.3048)
		(layers "F.Cu" "B.Cu")
		(net "GND")
	)
	(via
		(at 13.162026 -384.47599)
		(size 0.7112)
		(drill 0.4064)
		(layers "F.Cu" "B.Cu")
		(net "GND")
	)
	(via
		(at 275.336 -277.368)
		(size 0.5588)
		(drill 0.3048)
		(layers "F.Cu" "B.Cu")
		(net "GND")
	)
	(via
		(at 351.028 -150.368)
		(size 0.5588)
		(drill 0.3048)
		(layers "F.Cu" "B.Cu")
		(net "GND")
	)
	(via
		(at 10.264648 -1.524)
		(size 0.7112)
		(drill 0.4064)
		(layers "F.Cu" "B.Cu")
		(net "GND")
	)
	(via
		(at 427.192186 -114.987578)
		(size 0.5588)
		(drill 0.3048)
		(layers "F.Cu" "B.Cu")
		(net "GND")
	)
	(via
		(at 489.926122 -6.09219)
		(size 0.7112)
		(drill 0.4064)
		(layers "F.Cu" "B.Cu")
		(net "GND")
	)
	(via
		(at 1.524 -273.453352)
		(size 0.7112)
		(drill 0.4064)
		(layers "F.Cu" "B.Cu")
		(net "GND")
	)
	(via
		(at 489.926122 -202.94219)
		(size 0.7112)
		(drill 0.4064)
		(layers "F.Cu" "B.Cu")
		(net "GND")
	)
	(via
		(at 4.523994 -371.524022)
		(size 0.7112)
		(drill 0.4064)
		(layers "F.Cu" "B.Cu")
		(net "GND")
	)
	(via
		(at 1.524 -52.473352)
		(size 0.7112)
		(drill 0.4064)
		(layers "F.Cu" "B.Cu")
		(net "GND")
	)
	(via
		(at 437.896 -58.928)
		(size 0.5588)
		(drill 0.3048)
		(layers "F.Cu" "B.Cu")
		(net "GND")
	)
	(via
		(at 455.93 -47.117)
		(size 0.5588)
		(drill 0.3048)
		(layers "F.Cu" "B.Cu")
		(net "GND")
	)
	(via
		(at 300.430692 -384.47599)
		(size 0.7112)
		(drill 0.4064)
		(layers "F.Cu" "B.Cu")
		(net "GND")
	)
	(via
		(at 305.748436 -49.724056)
		(size 0.7112)
		(drill 0.4064)
		(layers "F.Cu" "B.Cu")
		(net "GND")
	)
	(via
		(at 1.524 -124.863352)
		(size 0.7112)
		(drill 0.4064)
		(layers "F.Cu" "B.Cu")
		(net "GND")
	)
	(via
		(at 329.85837 -15.221204)
		(size 0.5588)
		(drill 0.3048)
		(layers "F.Cu" "B.Cu")
		(net "GND")
	)
	(via
		(at 42.527982 -384.47599)
		(size 0.7112)
		(drill 0.4064)
		(layers "F.Cu" "B.Cu")
		(net "GND")
	)
	(via
		(at 54.229 -156.2608)
		(size 0.5588)
		(drill 0.3048)
		(layers "F.Cu" "B.Cu")
		(net "GND")
	)
	(via
		(at 239.780826 -368.86388)
		(size 0.5588)
		(drill 0.3048)
		(layers "F.Cu" "B.Cu")
		(net "GND")
	)
	(via
		(at 22.606 -226.949)
		(size 0.5588)
		(drill 0.3048)
		(layers "F.Cu" "B.Cu")
		(net "GND")
	)
	(via
		(at 170.307 -265.684)
		(size 0.5588)
		(drill 0.3048)
		(layers "F.Cu" "B.Cu")
		(net "GND")
	)
	(via
		(at 118.745 -29.464)
		(size 0.5588)
		(drill 0.3048)
		(layers "F.Cu" "B.Cu")
		(net "GND")
	)
	(via
		(at 196.476112 -382.438148)
		(size 0.7112)
		(drill 0.4064)
		(layers "F.Cu" "B.Cu")
		(net "GND")
	)
	(via
		(at 358.983026 -7.035038)
		(size 0.5588)
		(drill 0.3048)
		(layers "F.Cu" "B.Cu")
		(net "GND")
	)
	(via
		(at 50.673 -248.6152)
		(size 0.5588)
		(drill 0.3048)
		(layers "F.Cu" "B.Cu")
		(net "GND")
	)
	(via
		(at 1.524 -325.523352)
		(size 0.7112)
		(drill 0.4064)
		(layers "F.Cu" "B.Cu")
		(net "GND")
	)
	(via
		(at 384.737864 -378.476002)
		(size 0.7112)
		(drill 0.4064)
		(layers "F.Cu" "B.Cu")
		(net "GND")
	)
	(via
		(at 148.844 -41.3258)
		(size 0.5588)
		(drill 0.3048)
		(layers "F.Cu" "B.Cu")
		(net "GND")
	)
	(via
		(at 11.801094 -216.759028)
		(size 0.5588)
		(drill 0.3048)
		(layers "F.Cu" "B.Cu")
		(net "GND")
	)
	(via
		(at 115.316 -256.667)
		(size 0.5588)
		(drill 0.3048)
		(layers "F.Cu" "B.Cu")
		(net "GND")
	)
	(via
		(at 308.554882 -380.775972)
		(size 0.7112)
		(drill 0.4064)
		(layers "F.Cu" "B.Cu")
		(net "GND")
	)
	(via
		(at 331.176376 -1.524)
		(size 0.7112)
		(drill 0.4064)
		(layers "F.Cu" "B.Cu")
		(net "GND")
	)
	(via
		(at 419.161976 -253.830074)
		(size 0.5588)
		(drill 0.3048)
		(layers "F.Cu" "B.Cu")
		(net "GND")
	)
	(via
		(at 1.524 -19.453352)
		(size 0.7112)
		(drill 0.4064)
		(layers "F.Cu" "B.Cu")
		(net "GND")
	)
	(via
		(at 1.524 -126.133352)
		(size 0.7112)
		(drill 0.4064)
		(layers "F.Cu" "B.Cu")
		(net "GND")
	)
	(via
		(at 180.4162 -161.3916)
		(size 0.5588)
		(drill 0.3048)
		(layers "F.Cu" "B.Cu")
		(net "GND")
	)
	(via
		(at 448.904868 -135.565134)
		(size 0.5588)
		(drill 0.3048)
		(layers "F.Cu" "B.Cu")
		(net "GND")
	)
	(via
		(at 466.901022 -216.759028)
		(size 0.5588)
		(drill 0.3048)
		(layers "F.Cu" "B.Cu")
		(net "GND")
	)
	(via
		(at 48.199802 -230.51135)
		(size 0.5588)
		(drill 0.3048)
		(layers "F.Cu" "B.Cu")
		(net "GND")
	)
	(via
		(at 117.77599 -378.476002)
		(size 0.7112)
		(drill 0.4064)
		(layers "F.Cu" "B.Cu")
		(net "GND")
	)
	(via
		(at 213.614 -65.666874)
		(size 0.6604)
		(drill 0.3556)
		(layers "F.Cu" "B.Cu")
		(net "GND")
	)
	(via
		(at 84.836 -174.244)
		(size 0.5588)
		(drill 0.3048)
		(layers "F.Cu" "B.Cu")
		(net "GND")
	)
	(via
		(at 428.42942 -20.571714)
		(size 0.5588)
		(drill 0.3048)
		(layers "F.Cu" "B.Cu")
		(net "GND")
	)
	(via
		(at 449.072 -78.74)
		(size 0.5588)
		(drill 0.3048)
		(layers "F.Cu" "B.Cu")
		(net "GND")
	)
	(via
		(at 95.377 -30.3276)
		(size 0.5588)
		(drill 0.3048)
		(layers "F.Cu" "B.Cu")
		(net "GND")
	)
	(via
		(at 197.47611 -27.672538)
		(size 0.7112)
		(drill 0.4064)
		(layers "F.Cu" "B.Cu")
		(net "GND")
	)
	(via
		(at 1.524 -27.073352)
		(size 0.7112)
		(drill 0.4064)
		(layers "F.Cu" "B.Cu")
		(net "GND")
	)
	(via
		(at 325.654924 -155.97505)
		(size 0.5588)
		(drill 0.3048)
		(layers "F.Cu" "B.Cu")
		(net "GND")
	)
	(via
		(at 186.055 -263.355074)
		(size 0.5588)
		(drill 0.3048)
		(layers "F.Cu" "B.Cu")
		(net "GND")
	)
	(via
		(at 290.576 -106.172)
		(size 0.5588)
		(drill 0.3048)
		(layers "F.Cu" "B.Cu")
		(net "GND")
	)
	(via
		(at 130.3655 -261.239)
		(size 0.5588)
		(drill 0.3048)
		(layers "F.Cu" "B.Cu")
		(net "GND")
	)
	(via
		(at 312.523886 -33.67151)
		(size 0.7112)
		(drill 0.4064)
		(layers "F.Cu" "B.Cu")
		(net "GND")
	)
	(via
		(at 28.304998 -40.975026)
		(size 0.5588)
		(drill 0.3048)
		(layers "F.Cu" "B.Cu")
		(net "GND")
	)
	(via
		(at 287.048448 -346.271342)
		(size 0.5588)
		(drill 0.3048)
		(layers "F.Cu" "B.Cu")
		(net "GND")
	)
	(via
		(at 74.06386 -119.326406)
		(size 0.5588)
		(drill 0.3048)
		(layers "F.Cu" "B.Cu")
		(net "GND")
	)
	(via
		(at 364.109 -378.587)
		(size 0.7112)
		(drill 0.4064)
		(layers "F.Cu" "B.Cu")
		(net "GND")
	)
	(via
		(at 77.574648 -1.524)
		(size 0.7112)
		(drill 0.4064)
		(layers "F.Cu" "B.Cu")
		(net "GND")
	)
	(via
		(at 444.5 -304.8)
		(size 0.5588)
		(drill 0.3048)
		(layers "F.Cu" "B.Cu")
		(net "GND")
	)
	(via
		(at 1.524 -209.953352)
		(size 0.7112)
		(drill 0.4064)
		(layers "F.Cu" "B.Cu")
		(net "GND")
	)
	(via
		(at 344.932 -23.114)
		(size 0.5588)
		(drill 0.3048)
		(layers "F.Cu" "B.Cu")
		(net "GND")
	)
	(via
		(at 61.064648 -1.524)
		(size 0.7112)
		(drill 0.4064)
		(layers "F.Cu" "B.Cu")
		(net "GND")
	)
	(via
		(at 151.113998 -384.47599)
		(size 0.7112)
		(drill 0.4064)
		(layers "F.Cu" "B.Cu")
		(net "GND")
	)
	(via
		(at 489.926122 -75.94219)
		(size 0.7112)
		(drill 0.4064)
		(layers "F.Cu" "B.Cu")
		(net "GND")
	)
	(via
		(at 1.524 -189.633352)
		(size 0.7112)
		(drill 0.4064)
		(layers "F.Cu" "B.Cu")
		(net "GND")
	)
	(via
		(at 356.062026 -26.230072)
		(size 0.5588)
		(drill 0.3048)
		(layers "F.Cu" "B.Cu")
		(net "GND")
	)
	(via
		(at 413.726376 -1.524)
		(size 0.7112)
		(drill 0.4064)
		(layers "F.Cu" "B.Cu")
		(net "GND")
	)
	(via
		(at 357.205026 -16.845026)
		(size 0.5588)
		(drill 0.3048)
		(layers "F.Cu" "B.Cu")
		(net "GND")
	)
	(via
		(at 445.516 -59.436)
		(size 0.5588)
		(drill 0.3048)
		(layers "F.Cu" "B.Cu")
		(net "GND")
	)
	(via
		(at 208.798922 -101.471984)
		(size 0.7112)
		(drill 0.4064)
		(layers "F.Cu" "B.Cu")
		(net "GND")
	)
	(via
		(at 351.376996 -361.95)
		(size 0.7112)
		(drill 0.4064)
		(layers "F.Cu" "B.Cu")
		(net "GND")
	)
	(via
		(at 483.404926 -40.975026)
		(size 0.5588)
		(drill 0.3048)
		(layers "F.Cu" "B.Cu")
		(net "GND")
	)
	(via
		(at 203.332588 -49.724056)
		(size 0.7112)
		(drill 0.4064)
		(layers "F.Cu" "B.Cu")
		(net "GND")
	)
	(via
		(at 59.037982 -136.430004)
		(size 0.5588)
		(drill 0.3048)
		(layers "F.Cu" "B.Cu")
		(net "GND")
	)
	(via
		(at 61.632846 -122.035062)
		(size 0.5588)
		(drill 0.3048)
		(layers "F.Cu" "B.Cu")
		(net "GND")
	)
	(via
		(at 387.611874 -26.230072)
		(size 0.5588)
		(drill 0.3048)
		(layers "F.Cu" "B.Cu")
		(net "GND")
	)
	(via
		(at 1.524 -43.583352)
		(size 0.7112)
		(drill 0.4064)
		(layers "F.Cu" "B.Cu")
		(net "GND")
	)
	(via
		(at 240.0808 -355.1682)
		(size 0.7112)
		(drill 0.4064)
		(layers "F.Cu" "B.Cu")
		(net "GND")
	)
	(via
		(at 428.371 -268.224)
		(size 0.5588)
		(drill 0.3048)
		(layers "F.Cu" "B.Cu")
		(net "GND")
	)
	(via
		(at 21.59 -224.917)
		(size 0.5588)
		(drill 0.3048)
		(layers "F.Cu" "B.Cu")
		(net "GND")
	)
	(via
		(at 465.796376 -1.524)
		(size 0.7112)
		(drill 0.4064)
		(layers "F.Cu" "B.Cu")
		(net "GND")
	)
	(via
		(at 333.0448 -244.856)
		(size 0.5588)
		(drill 0.3048)
		(layers "F.Cu" "B.Cu")
		(net "GND")
	)
	(via
		(at 489.926122 -135.63219)
		(size 0.7112)
		(drill 0.4064)
		(layers "F.Cu" "B.Cu")
		(net "GND")
	)
	(via
		(at 94.866968 -342.250014)
		(size 0.5588)
		(drill 0.3048)
		(layers "F.Cu" "B.Cu")
		(net "GND")
	)
	(via
		(at 381.976376 -1.524)
		(size 0.7112)
		(drill 0.4064)
		(layers "F.Cu" "B.Cu")
		(net "GND")
	)
	(via
		(at 77.13599 -378.476002)
		(size 0.7112)
		(drill 0.4064)
		(layers "F.Cu" "B.Cu")
		(net "GND")
	)
	(via
		(at 63.5 -203.2)
		(size 0.5588)
		(drill 0.3048)
		(layers "F.Cu" "B.Cu")
		(net "GND")
	)
	(via
		(at 489.926122 -37.84219)
		(size 0.7112)
		(drill 0.4064)
		(layers "F.Cu" "B.Cu")
		(net "GND")
	)
	(via
		(at 190.5 -275.336)
		(size 0.5588)
		(drill 0.3048)
		(layers "F.Cu" "B.Cu")
		(net "GND")
	)
	(via
		(at 41.62044 -234.835192)
		(size 0.5588)
		(drill 0.3048)
		(layers "F.Cu" "B.Cu")
		(net "GND")
	)
	(via
		(at 32.367982 -384.47599)
		(size 0.7112)
		(drill 0.4064)
		(layers "F.Cu" "B.Cu")
		(net "GND")
	)
	(via
		(at 187.833 -165.785038)
		(size 0.5588)
		(drill 0.3048)
		(layers "F.Cu" "B.Cu")
		(net "GND")
	)
	(via
		(at 103.80599 -378.476002)
		(size 0.7112)
		(drill 0.4064)
		(layers "F.Cu" "B.Cu")
		(net "GND")
	)
	(via
		(at 285.667958 -101.211888)
		(size 0.7112)
		(drill 0.4064)
		(layers "F.Cu" "B.Cu")
		(net "GND")
	)
	(via
		(at 91.404948 -250.655074)
		(size 0.5588)
		(drill 0.3048)
		(layers "F.Cu" "B.Cu")
		(net "GND")
	)
	(via
		(at 178.816 -20.447)
		(size 0.5588)
		(drill 0.3048)
		(layers "F.Cu" "B.Cu")
		(net "GND")
	)
	(via
		(at 1.524 -95.653352)
		(size 0.7112)
		(drill 0.4064)
		(layers "F.Cu" "B.Cu")
		(net "GND")
	)
	(via
		(at 12.192 -40.64)
		(size 0.5588)
		(drill 0.3048)
		(layers "F.Cu" "B.Cu")
		(net "GND")
	)
	(via
		(at 453.645016 -384.429)
		(size 0.7112)
		(drill 0.4064)
		(layers "F.Cu" "B.Cu")
		(net "GND")
	)
	(via
		(at 374.396 -19.812)
		(size 0.5588)
		(drill 0.3048)
		(layers "F.Cu" "B.Cu")
		(net "GND")
	)
	(via
		(at 72.03186 -119.326406)
		(size 0.5588)
		(drill 0.3048)
		(layers "F.Cu" "B.Cu")
		(net "GND")
	)
	(via
		(at 189.952122 -155.47721)
		(size 0.5588)
		(drill 0.3048)
		(layers "F.Cu" "B.Cu")
		(net "GND")
	)
	(via
		(at 300.736 -111.76)
		(size 0.5588)
		(drill 0.3048)
		(layers "F.Cu" "B.Cu")
		(net "GND")
	)
	(via
		(at 489.926122 -242.31219)
		(size 0.7112)
		(drill 0.4064)
		(layers "F.Cu" "B.Cu")
		(net "GND")
	)
	(via
		(at 489.926122 -45.46219)
		(size 0.7112)
		(drill 0.4064)
		(layers "F.Cu" "B.Cu")
		(net "GND")
	)
	(via
		(at 14.64945 -216.308686)
		(size 0.5588)
		(drill 0.3048)
		(layers "F.Cu" "B.Cu")
		(net "GND")
	)
	(via
		(at 437.125872 -384.47599)
		(size 0.7112)
		(drill 0.4064)
		(layers "F.Cu" "B.Cu")
		(net "GND")
	)
	(via
		(at 165.735 -250.063)
		(size 0.5588)
		(drill 0.3048)
		(layers "F.Cu" "B.Cu")
		(net "GND")
	)
	(via
		(at 350.226376 -1.524)
		(size 0.7112)
		(drill 0.4064)
		(layers "F.Cu" "B.Cu")
		(net "GND")
	)
	(via
		(at 468.336376 -1.524)
		(size 0.7112)
		(drill 0.4064)
		(layers "F.Cu" "B.Cu")
		(net "GND")
	)
	(via
		(at 16.3195 -139.954)
		(size 0.5588)
		(drill 0.3048)
		(layers "F.Cu" "B.Cu")
		(net "GND")
	)
	(via
		(at 489.926122 -53.08219)
		(size 0.7112)
		(drill 0.4064)
		(layers "F.Cu" "B.Cu")
		(net "GND")
	)
	(via
		(at 137.684764 -365.820452)
		(size 0.5588)
		(drill 0.3048)
		(layers "F.Cu" "B.Cu")
		(net "GND")
	)
	(via
		(at 87.376 -162.179)
		(size 0.5588)
		(drill 0.3048)
		(layers "F.Cu" "B.Cu")
		(net "GND")
	)
	(via
		(at 12.7 -317.5)
		(size 0.5588)
		(drill 0.3048)
		(layers "F.Cu" "B.Cu")
		(net "GND")
	)
	(via
		(at 115.316 -21.2852)
		(size 0.5588)
		(drill 0.3048)
		(layers "F.Cu" "B.Cu")
		(net "GND")
	)
	(via
		(at 203.922122 -102.665784)
		(size 0.7112)
		(drill 0.4064)
		(layers "F.Cu" "B.Cu")
		(net "GND")
	)
	(via
		(at 244.348 -213.9696)
		(size 0.5588)
		(drill 0.3048)
		(layers "F.Cu" "B.Cu")
		(net "GND")
	)
	(via
		(at 200.4822 -304.1142)
		(size 0.7112)
		(drill 0.4064)
		(layers "F.Cu" "B.Cu")
		(net "GND")
	)
	(via
		(at 381 -304.8)
		(size 0.5588)
		(drill 0.3048)
		(layers "F.Cu" "B.Cu")
		(net "GND")
	)
	(via
		(at 416.3314 -260.3246)
		(size 0.5588)
		(drill 0.3048)
		(layers "F.Cu" "B.Cu")
		(net "GND")
	)
	(via
		(at 25.4 -203.2)
		(size 0.5588)
		(drill 0.3048)
		(layers "F.Cu" "B.Cu")
		(net "GND")
	)
	(via
		(at 279.4 -88.9)
		(size 0.5588)
		(drill 0.3048)
		(layers "F.Cu" "B.Cu")
		(net "GND")
	)
	(via
		(at 489.926122 -93.72219)
		(size 0.7112)
		(drill 0.4064)
		(layers "F.Cu" "B.Cu")
		(net "GND")
	)
	(via
		(at 424.8912 -250.7742)
		(size 0.5588)
		(drill 0.3048)
		(layers "F.Cu" "B.Cu")
		(net "GND")
	)
	(via
		(at 153.774648 -1.524)
		(size 0.7112)
		(drill 0.4064)
		(layers "F.Cu" "B.Cu")
		(net "GND")
	)
	(via
		(at 139.75715 -101.8286)
		(size 0.5588)
		(drill 0.3048)
		(layers "F.Cu" "B.Cu")
		(net "GND")
	)
	(via
		(at 2.644648 -1.524)
		(size 0.7112)
		(drill 0.4064)
		(layers "F.Cu" "B.Cu")
		(net "GND")
	)
	(via
		(at 439.317384 -116.632228)
		(size 0.5588)
		(drill 0.3048)
		(layers "F.Cu" "B.Cu")
		(net "GND")
	)
	(via
		(at 259.383276 -194.788282)
		(size 0.7112)
		(drill 0.4064)
		(layers "F.Cu" "B.Cu")
		(net "GND")
	)
	(via
		(at 1.524 -249.323352)
		(size 0.7112)
		(drill 0.4064)
		(layers "F.Cu" "B.Cu")
		(net "GND")
	)
	(via
		(at 489.926122 -4.82219)
		(size 0.7112)
		(drill 0.4064)
		(layers "F.Cu" "B.Cu")
		(net "GND")
	)
	(via
		(at 317.627 -383.667)
		(size 0.7112)
		(drill 0.4064)
		(layers "F.Cu" "B.Cu")
		(net "GND")
	)
	(via
		(at 223.31807 -221.881192)
		(size 0.5588)
		(drill 0.3048)
		(layers "F.Cu" "B.Cu")
		(net "GND")
	)
	(via
		(at 489.926122 -208.02219)
		(size 0.7112)
		(drill 0.4064)
		(layers "F.Cu" "B.Cu")
		(net "GND")
	)
	(via
		(at 301.938436 -49.724056)
		(size 0.7112)
		(drill 0.4064)
		(layers "F.Cu" "B.Cu")
		(net "GND")
	)
	(via
		(at 369.497864 -378.476002)
		(size 0.7112)
		(drill 0.4064)
		(layers "F.Cu" "B.Cu")
		(net "GND")
	)
	(via
		(at 292.1 -63.5)
		(size 0.5588)
		(drill 0.3048)
		(layers "F.Cu" "B.Cu")
		(net "GND")
	)
	(via
		(at 327.432924 -50.785014)
		(size 0.5588)
		(drill 0.3048)
		(layers "F.Cu" "B.Cu")
		(net "GND")
	)
	(via
		(at 464.82 -107.696)
		(size 0.5588)
		(drill 0.3048)
		(layers "F.Cu" "B.Cu")
		(net "GND")
	)
	(via
		(at 1.524 -289.963352)
		(size 0.7112)
		(drill 0.4064)
		(layers "F.Cu" "B.Cu")
		(net "GND")
	)
	(via
		(at 65.422018 -103.984044)
		(size 0.5588)
		(drill 0.3048)
		(layers "F.Cu" "B.Cu")
		(net "GND")
	)
	(via
		(at 364.998 -47.117)
		(size 0.5588)
		(drill 0.3048)
		(layers "F.Cu" "B.Cu")
		(net "GND")
	)
	(via
		(at 1.524 -367.433352)
		(size 0.7112)
		(drill 0.4064)
		(layers "F.Cu" "B.Cu")
		(net "GND")
	)
	(via
		(at 18.669 -145.542)
		(size 0.5588)
		(drill 0.3048)
		(layers "F.Cu" "B.Cu")
		(net "GND")
	)
	(via
		(at 1.524 -77.873352)
		(size 0.7112)
		(drill 0.4064)
		(layers "F.Cu" "B.Cu")
		(net "GND")
	)
	(via
		(at 70.866 -380.619)
		(size 0.7112)
		(drill 0.4064)
		(layers "F.Cu" "B.Cu")
		(net "GND")
	)
	(via
		(at 229.616 -302.6918)
		(size 0.5588)
		(drill 0.3048)
		(layers "F.Cu" "B.Cu")
		(net "GND")
	)
	(via
		(at 156.282898 -165.785038)
		(size 0.5588)
		(drill 0.3048)
		(layers "F.Cu" "B.Cu")
		(net "GND")
	)
	(via
		(at 489.926122 -120.39219)
		(size 0.7112)
		(drill 0.4064)
		(layers "F.Cu" "B.Cu")
		(net "GND")
	)
	(via
		(at 15.621 -381.508)
		(size 0.7112)
		(drill 0.4064)
		(layers "F.Cu" "B.Cu")
		(net "GND")
	)
	(via
		(at 359.019856 -384.47599)
		(size 0.7112)
		(drill 0.4064)
		(layers "F.Cu" "B.Cu")
		(net "GND")
	)
	(via
		(at 355.6 -215.9)
		(size 0.5588)
		(drill 0.3048)
		(layers "F.Cu" "B.Cu")
		(net "GND")
	)
	(via
		(at 489.926122 -73.40219)
		(size 0.7112)
		(drill 0.4064)
		(layers "F.Cu" "B.Cu")
		(net "GND")
	)
	(via
		(at 439.317384 -114.600228)
		(size 0.5588)
		(drill 0.3048)
		(layers "F.Cu" "B.Cu")
		(net "GND")
	)
	(via
		(at 451.854824 -30.815026)
		(size 0.5588)
		(drill 0.3048)
		(layers "F.Cu" "B.Cu")
		(net "GND")
	)
	(via
		(at 35.664648 -1.524)
		(size 0.7112)
		(drill 0.4064)
		(layers "F.Cu" "B.Cu")
		(net "GND")
	)
	(via
		(at 95.354648 -1.524)
		(size 0.7112)
		(drill 0.4064)
		(layers "F.Cu" "B.Cu")
		(net "GND")
	)
	(via
		(at 489.926122 -336.29219)
		(size 0.7112)
		(drill 0.4064)
		(layers "F.Cu" "B.Cu")
		(net "GND")
	)
	(via
		(at 459.232 -215.392)
		(size 0.5588)
		(drill 0.3048)
		(layers "F.Cu" "B.Cu")
		(net "GND")
	)
	(via
		(at 170.307 -150.622)
		(size 0.5588)
		(drill 0.3048)
		(layers "F.Cu" "B.Cu")
		(net "GND")
	)
	(via
		(at 361.559856 -384.47599)
		(size 0.7112)
		(drill 0.4064)
		(layers "F.Cu" "B.Cu")
		(net "GND")
	)
	(via
		(at 186.794648 -1.524)
		(size 0.7112)
		(drill 0.4064)
		(layers "F.Cu" "B.Cu")
		(net "GND")
	)
	(via
		(at 327.366376 -1.524)
		(size 0.7112)
		(drill 0.4064)
		(layers "F.Cu" "B.Cu")
		(net "GND")
	)
	(via
		(at 470.876376 -1.524)
		(size 0.7112)
		(drill 0.4064)
		(layers "F.Cu" "B.Cu")
		(net "GND")
	)
	(via
		(at 4.523994 -382.954022)
		(size 0.7112)
		(drill 0.4064)
		(layers "F.Cu" "B.Cu")
		(net "GND")
	)
	(via
		(at 312.523886 -10.81151)
		(size 0.7112)
		(drill 0.4064)
		(layers "F.Cu" "B.Cu")
		(net "GND")
	)
	(via
		(at 304.8 -304.8)
		(size 0.5588)
		(drill 0.3048)
		(layers "F.Cu" "B.Cu")
		(net "GND")
	)
	(via
		(at 28.448 -80.264)
		(size 0.5588)
		(drill 0.3048)
		(layers "F.Cu" "B.Cu")
		(net "GND")
	)
	(via
		(at 66.468498 -123.751848)
		(size 0.5588)
		(drill 0.3048)
		(layers "F.Cu" "B.Cu")
		(net "GND")
	)
	(via
		(at 27.161998 -253.830074)
		(size 0.5588)
		(drill 0.3048)
		(layers "F.Cu" "B.Cu")
		(net "GND")
	)
	(via
		(at 90.261948 -251.430028)
		(size 0.5588)
		(drill 0.3048)
		(layers "F.Cu" "B.Cu")
		(net "GND")
	)
	(via
		(at 325.654924 -40.975026)
		(size 0.5588)
		(drill 0.3048)
		(layers "F.Cu" "B.Cu")
		(net "GND")
	)
	(via
		(at 136.516364 -365.820452)
		(size 0.5588)
		(drill 0.3048)
		(layers "F.Cu" "B.Cu")
		(net "GND")
	)
	(via
		(at 425.7802 -132.715)
		(size 0.5588)
		(drill 0.3048)
		(layers "F.Cu" "B.Cu")
		(net "GND")
	)
	(via
		(at 405.56942 -216.8144)
		(size 0.5588)
		(drill 0.3048)
		(layers "F.Cu" "B.Cu")
		(net "GND")
	)
	(via
		(at 479.745802 -230.51135)
		(size 0.5588)
		(drill 0.3048)
		(layers "F.Cu" "B.Cu")
		(net "GND")
	)
	(via
		(at 355.6 -88.9)
		(size 0.5588)
		(drill 0.3048)
		(layers "F.Cu" "B.Cu")
		(net "GND")
	)
	(via
		(at 128.253998 -384.47599)
		(size 0.7112)
		(drill 0.4064)
		(layers "F.Cu" "B.Cu")
		(net "GND")
	)
	(via
		(at 186.055 -16.845026)
		(size 0.5588)
		(drill 0.3048)
		(layers "F.Cu" "B.Cu")
		(net "GND")
	)
	(via
		(at 474.862398 -217.28303)
		(size 0.5588)
		(drill 0.3048)
		(layers "F.Cu" "B.Cu")
		(net "GND")
	)
	(via
		(at 44.196 -174.244)
		(size 0.5588)
		(drill 0.3048)
		(layers "F.Cu" "B.Cu")
		(net "GND")
	)
	(via
		(at 362.839 -379.476)
		(size 0.7112)
		(drill 0.4064)
		(layers "F.Cu" "B.Cu")
		(net "GND")
	)
	(via
		(at 1.524 -358.543352)
		(size 0.7112)
		(drill 0.4064)
		(layers "F.Cu" "B.Cu")
		(net "GND")
	)
	(via
		(at 47.6123 -113.099342)
		(size 0.6604)
		(drill 0.3302)
		(layers "F.Cu" "B.Cu")
		(net "GND")
	)
	(via
		(at 63.5 -76.2)
		(size 0.5588)
		(drill 0.3048)
		(layers "F.Cu" "B.Cu")
		(net "GND")
	)
	(via
		(at 32.4104 -30.3022)
		(size 0.5588)
		(drill 0.3048)
		(layers "F.Cu" "B.Cu")
		(net "GND")
	)
	(via
		(at 140.462 -261.239)
		(size 0.5588)
		(drill 0.3048)
		(layers "F.Cu" "B.Cu")
		(net "GND")
	)
	(via
		(at 1.524 -102.003352)
		(size 0.7112)
		(drill 0.4064)
		(layers "F.Cu" "B.Cu")
		(net "GND")
	)
	(via
		(at 408.432 -15.748)
		(size 0.5588)
		(drill 0.3048)
		(layers "F.Cu" "B.Cu")
		(net "GND")
	)
	(via
		(at 314.666376 -1.524)
		(size 0.7112)
		(drill 0.4064)
		(layers "F.Cu" "B.Cu")
		(net "GND")
	)
	(via
		(at 1.524 -46.123352)
		(size 0.7112)
		(drill 0.4064)
		(layers "F.Cu" "B.Cu")
		(net "GND")
	)
	(via
		(at 333.0448 -129.921)
		(size 0.5588)
		(drill 0.3048)
		(layers "F.Cu" "B.Cu")
		(net "GND")
	)
	(via
		(at 297.890692 -384.47599)
		(size 0.7112)
		(drill 0.4064)
		(layers "F.Cu" "B.Cu")
		(net "GND")
	)
	(via
		(at 245.9228 -138.9888)
		(size 0.5588)
		(drill 0.3048)
		(layers "F.Cu" "B.Cu")
		(net "GND")
	)
	(via
		(at 430.466754 -364.236)
		(size 0.5588)
		(drill 0.3048)
		(layers "F.Cu" "B.Cu")
		(net "GND")
	)
	(via
		(at 113.536222 -134.078472)
		(size 0.5588)
		(drill 0.3048)
		(layers "F.Cu" "B.Cu")
		(net "GND")
	)
	(via
		(at 1.524 -310.283352)
		(size 0.7112)
		(drill 0.4064)
		(layers "F.Cu" "B.Cu")
		(net "GND")
	)
	(via
		(at 1.524 -98.193352)
		(size 0.7112)
		(drill 0.4064)
		(layers "F.Cu" "B.Cu")
		(net "GND")
	)
	(via
		(at 21.59 -225.933)
		(size 0.5588)
		(drill 0.3048)
		(layers "F.Cu" "B.Cu")
		(net "GND")
	)
	(via
		(at 288.911284 -137.494518)
		(size 0.6604)
		(drill 0.3556)
		(layers "F.Cu" "B.Cu")
		(net "GND")
	)
	(via
		(at 489.926122 -155.95219)
		(size 0.7112)
		(drill 0.4064)
		(layers "F.Cu" "B.Cu")
		(net "GND")
	)
	(via
		(at 483.404926 -33.355026)
		(size 0.5588)
		(drill 0.3048)
		(layers "F.Cu" "B.Cu")
		(net "GND")
	)
	(via
		(at 135.636 -14.732)
		(size 0.5588)
		(drill 0.3048)
		(layers "F.Cu" "B.Cu")
		(net "GND")
	)
	(via
		(at 79.676752 -333.434944)
		(size 0.5588)
		(drill 0.3048)
		(layers "F.Cu" "B.Cu")
		(net "GND")
	)
	(via
		(at 474.3704 -26.4922)
		(size 0.5588)
		(drill 0.3048)
		(layers "F.Cu" "B.Cu")
		(net "GND")
	)
	(via
		(at 489.926122 -9.90219)
		(size 0.7112)
		(drill 0.4064)
		(layers "F.Cu" "B.Cu")
		(net "GND")
	)
	(via
		(at 63.5 -215.9)
		(size 0.5588)
		(drill 0.3048)
		(layers "F.Cu" "B.Cu")
		(net "GND")
	)
	(via
		(at 461.265016 -384.429)
		(size 0.7112)
		(drill 0.4064)
		(layers "F.Cu" "B.Cu")
		(net "GND")
	)
	(via
		(at 53.5178 -135.4328)
		(size 0.5588)
		(drill 0.3048)
		(layers "F.Cu" "B.Cu")
		(net "GND")
	)
	(via
		(at 469.606376 -1.524)
		(size 0.7112)
		(drill 0.4064)
		(layers "F.Cu" "B.Cu")
		(net "GND")
	)
	(via
		(at 200.4822 -305.3334)
		(size 0.7112)
		(drill 0.4064)
		(layers "F.Cu" "B.Cu")
		(net "GND")
	)
	(via
		(at 54.229 -41.3258)
		(size 0.5588)
		(drill 0.3048)
		(layers "F.Cu" "B.Cu")
		(net "GND")
	)
	(via
		(at 357.205026 -260.815074)
		(size 0.5588)
		(drill 0.3048)
		(layers "F.Cu" "B.Cu")
		(net "GND")
	)
	(via
		(at 338.796376 -1.524)
		(size 0.7112)
		(drill 0.4064)
		(layers "F.Cu" "B.Cu")
		(net "GND")
	)
	(via
		(at 489.926122 -131.82219)
		(size 0.7112)
		(drill 0.4064)
		(layers "F.Cu" "B.Cu")
		(net "GND")
	)
	(via
		(at 416.487864 -378.476002)
		(size 0.7112)
		(drill 0.4064)
		(layers "F.Cu" "B.Cu")
		(net "GND")
	)
	(via
		(at 489.926122 -173.73219)
		(size 0.7112)
		(drill 0.4064)
		(layers "F.Cu" "B.Cu")
		(net "GND")
	)
	(via
		(at 314.452 -41.656)
		(size 0.5588)
		(drill 0.3048)
		(layers "F.Cu" "B.Cu")
		(net "GND")
	)
	(via
		(at 184.531 -173.101)
		(size 0.5588)
		(drill 0.3048)
		(layers "F.Cu" "B.Cu")
		(net "GND")
	)
	(via
		(at 113.134648 -1.524)
		(size 0.7112)
		(drill 0.4064)
		(layers "F.Cu" "B.Cu")
		(net "GND")
	)
	(via
		(at 304.8 -63.5)
		(size 0.5588)
		(drill 0.3048)
		(layers "F.Cu" "B.Cu")
		(net "GND")
	)
	(via
		(at 127 -373.888)
		(size 0.508)
		(drill 0.254)
		(layers "F.Cu" "B.Cu")
		(net "GND")
	)
	(via
		(at 190.604648 -1.524)
		(size 0.7112)
		(drill 0.4064)
		(layers "F.Cu" "B.Cu")
		(net "GND")
	)
	(via
		(at 396.875 -38.227)
		(size 0.5588)
		(drill 0.3048)
		(layers "F.Cu" "B.Cu")
		(net "GND")
	)
	(via
		(at 53.975 -141.605)
		(size 0.5588)
		(drill 0.3048)
		(layers "F.Cu" "B.Cu")
		(net "GND")
	)
	(via
		(at 415.217864 -378.476002)
		(size 0.7112)
		(drill 0.4064)
		(layers "F.Cu" "B.Cu")
		(net "GND")
	)
	(via
		(at 97.456752 -344.864944)
		(size 0.5588)
		(drill 0.3048)
		(layers "F.Cu" "B.Cu")
		(net "GND")
	)
	(via
		(at 489.926122 -176.27219)
		(size 0.7112)
		(drill 0.4064)
		(layers "F.Cu" "B.Cu")
		(net "GND")
	)
	(via
		(at 478.496376 -1.524)
		(size 0.7112)
		(drill 0.4064)
		(layers "F.Cu" "B.Cu")
		(net "GND")
	)
	(via
		(at 436.372 -16.764)
		(size 0.5588)
		(drill 0.3048)
		(layers "F.Cu" "B.Cu")
		(net "GND")
	)
	(via
		(at 3.914648 -1.524)
		(size 0.7112)
		(drill 0.4064)
		(layers "F.Cu" "B.Cu")
		(net "GND")
	)
	(via
		(at 102.108 -142.24)
		(size 0.5588)
		(drill 0.3048)
		(layers "F.Cu" "B.Cu")
		(net "GND")
	)
	(via
		(at 288.911284 -235.094526)
		(size 0.6604)
		(drill 0.3556)
		(layers "F.Cu" "B.Cu")
		(net "GND")
	)
	(via
		(at 114.3762 -18.2118)
		(size 0.5588)
		(drill 0.3048)
		(layers "F.Cu" "B.Cu")
		(net "GND")
	)
	(via
		(at 314.0964 -342.077802)
		(size 0.5588)
		(drill 0.3048)
		(layers "F.Cu" "B.Cu")
		(net "GND")
	)
	(via
		(at 293.048436 -49.724056)
		(size 0.7112)
		(drill 0.4064)
		(layers "F.Cu" "B.Cu")
		(net "GND")
	)
	(via
		(at 332.349856 -384.47599)
		(size 0.7112)
		(drill 0.4064)
		(layers "F.Cu" "B.Cu")
		(net "GND")
	)
	(via
		(at 168.893998 -384.47599)
		(size 0.7112)
		(drill 0.4064)
		(layers "F.Cu" "B.Cu")
		(net "GND")
	)
	(via
		(at 435.316376 -1.524)
		(size 0.7112)
		(drill 0.4064)
		(layers "F.Cu" "B.Cu")
		(net "GND")
	)
	(via
		(at 61.632846 -50.785014)
		(size 0.5588)
		(drill 0.3048)
		(layers "F.Cu" "B.Cu")
		(net "GND")
	)
	(via
		(at 86.127844 -333.554832)
		(size 0.5588)
		(drill 0.3048)
		(layers "F.Cu" "B.Cu")
		(net "GND")
	)
	(via
		(at 485.182926 -280.785062)
		(size 0.5588)
		(drill 0.3048)
		(layers "F.Cu" "B.Cu")
		(net "GND")
	)
	(via
		(at 428.371 -38.227)
		(size 0.5588)
		(drill 0.3048)
		(layers "F.Cu" "B.Cu")
		(net "GND")
	)
	(via
		(at 93.182948 -280.785062)
		(size 0.5588)
		(drill 0.3048)
		(layers "F.Cu" "B.Cu")
		(net "GND")
	)
	(via
		(at 1.524 -129.943352)
		(size 0.7112)
		(drill 0.4064)
		(layers "F.Cu" "B.Cu")
		(net "GND")
	)
	(via
		(at 55.753 -47.244)
		(size 0.5588)
		(drill 0.3048)
		(layers "F.Cu" "B.Cu")
		(net "GND")
	)
	(via
		(at 165.288468 -96.248728)
		(size 0.5588)
		(drill 0.3048)
		(layers "F.Cu" "B.Cu")
		(net "GND")
	)
	(via
		(at 458.216 -223.901)
		(size 0.5588)
		(drill 0.3048)
		(layers "F.Cu" "B.Cu")
		(net "GND")
	)
	(via
		(at 176.634648 -1.524)
		(size 0.7112)
		(drill 0.4064)
		(layers "F.Cu" "B.Cu")
		(net "GND")
	)
	(via
		(at 185.6486 -242.7732)
		(size 0.5588)
		(drill 0.3048)
		(layers "F.Cu" "B.Cu")
		(net "GND")
	)
	(via
		(at 469.9 -273.812)
		(size 0.5588)
		(drill 0.3048)
		(layers "F.Cu" "B.Cu")
		(net "GND")
	)
	(via
		(at 336.804 -23.368)
		(size 0.5588)
		(drill 0.3048)
		(layers "F.Cu" "B.Cu")
		(net "GND")
	)
	(via
		(at 489.926122 -258.82219)
		(size 0.7112)
		(drill 0.4064)
		(layers "F.Cu" "B.Cu")
		(net "GND")
	)
	(via
		(at 206.197962 -378.476002)
		(size 0.7112)
		(drill 0.4064)
		(layers "F.Cu" "B.Cu")
		(net "GND")
	)
	(via
		(at 112.0902 -32.004)
		(size 0.5588)
		(drill 0.3048)
		(layers "F.Cu" "B.Cu")
		(net "GND")
	)
	(via
		(at 270.926052 -373.991632)
		(size 0.7112)
		(drill 0.4064)
		(layers "F.Cu" "B.Cu")
		(net "GND")
	)
	(via
		(at 1.524 -44.853352)
		(size 0.7112)
		(drill 0.4064)
		(layers "F.Cu" "B.Cu")
		(net "GND")
	)
	(via
		(at 99.187 -352.044)
		(size 0.5588)
		(drill 0.3048)
		(layers "F.Cu" "B.Cu")
		(net "GND")
	)
	(via
		(at 57.254648 -1.524)
		(size 0.7112)
		(drill 0.4064)
		(layers "F.Cu" "B.Cu")
		(net "GND")
	)
	(via
		(at 205.476094 -53.766212)
		(size 0.7112)
		(drill 0.4064)
		(layers "F.Cu" "B.Cu")
		(net "GND")
	)
	(via
		(at 104.14 -138.176)
		(size 0.5588)
		(drill 0.3048)
		(layers "F.Cu" "B.Cu")
		(net "GND")
	)
	(via
		(at 302.393096 -326.593962)
		(size 0.5588)
		(drill 0.3048)
		(layers "F.Cu" "B.Cu")
		(net "GND")
	)
	(via
		(at 363.728 -7.62)
		(size 0.5588)
		(drill 0.3048)
		(layers "F.Cu" "B.Cu")
		(net "GND")
	)
	(via
		(at 312.523886 -3.19151)
		(size 0.7112)
		(drill 0.4064)
		(layers "F.Cu" "B.Cu")
		(net "GND")
	)
	(via
		(at 287.730692 -384.47599)
		(size 0.7112)
		(drill 0.4064)
		(layers "F.Cu" "B.Cu")
		(net "GND")
	)
	(via
		(at 165.608 -54.356)
		(size 0.5588)
		(drill 0.3048)
		(layers "F.Cu" "B.Cu")
		(net "GND")
	)
	(via
		(at 264.192258 -361.315)
		(size 0.5588)
		(drill 0.3048)
		(layers "F.Cu" "B.Cu")
		(net "GND")
	)
	(via
		(at 489.926122 -219.45219)
		(size 0.7112)
		(drill 0.4064)
		(layers "F.Cu" "B.Cu")
		(net "GND")
	)
	(via
		(at 102.974648 -1.524)
		(size 0.7112)
		(drill 0.4064)
		(layers "F.Cu" "B.Cu")
		(net "GND")
	)
	(via
		(at 460.9719 -5.461)
		(size 0.5588)
		(drill 0.3048)
		(layers "F.Cu" "B.Cu")
		(net "GND")
	)
	(via
		(at 118.364 -193.548)
		(size 0.5588)
		(drill 0.3048)
		(layers "F.Cu" "B.Cu")
		(net "GND")
	)
	(via
		(at 296.858436 -49.724056)
		(size 0.7112)
		(drill 0.4064)
		(layers "F.Cu" "B.Cu")
		(net "GND")
	)
	(via
		(at 458.176376 -1.524)
		(size 0.7112)
		(drill 0.4064)
		(layers "F.Cu" "B.Cu")
		(net "GND")
	)
	(via
		(at 323.459856 -384.47599)
		(size 0.7112)
		(drill 0.4064)
		(layers "F.Cu" "B.Cu")
		(net "GND")
	)
	(via
		(at 278.274018 -369.838478)
		(size 0.7112)
		(drill 0.4064)
		(layers "F.Cu" "B.Cu")
		(net "GND")
	)
	(via
		(at 483.404926 -16.845026)
		(size 0.5588)
		(drill 0.3048)
		(layers "F.Cu" "B.Cu")
		(net "GND")
	)
	(via
		(at 406.649428 -101.49713)
		(size 0.5588)
		(drill 0.3048)
		(layers "F.Cu" "B.Cu")
		(net "GND")
	)
	(via
		(at 489.926122 -246.12219)
		(size 0.7112)
		(drill 0.4064)
		(layers "F.Cu" "B.Cu")
		(net "GND")
	)
	(via
		(at 29.827982 -384.47599)
		(size 0.7112)
		(drill 0.4064)
		(layers "F.Cu" "B.Cu")
		(net "GND")
	)
	(via
		(at 456.184 -143.891)
		(size 0.5588)
		(drill 0.3048)
		(layers "F.Cu" "B.Cu")
		(net "GND")
	)
	(via
		(at 185.559954 -384.47599)
		(size 0.7112)
		(drill 0.4064)
		(layers "F.Cu" "B.Cu")
		(net "GND")
	)
	(via
		(at 362.966 -162.179)
		(size 0.5588)
		(drill 0.3048)
		(layers "F.Cu" "B.Cu")
		(net "GND")
	)
	(via
		(at 60.25769 -360.435906)
		(size 0.7112)
		(drill 0.4064)
		(layers "F.Cu" "B.Cu")
		(net "GND")
	)
	(via
		(at 200.792588 -49.724056)
		(size 0.7112)
		(drill 0.4064)
		(layers "F.Cu" "B.Cu")
		(net "GND")
	)
	(via
		(at 88.566752 -344.864944)
		(size 0.5588)
		(drill 0.3048)
		(layers "F.Cu" "B.Cu")
		(net "GND")
	)
	(via
		(at 394.2842 -132.715)
		(size 0.5588)
		(drill 0.3048)
		(layers "F.Cu" "B.Cu")
		(net "GND")
	)
	(via
		(at 147.424648 -1.524)
		(size 0.7112)
		(drill 0.4064)
		(layers "F.Cu" "B.Cu")
		(net "GND")
	)
	(via
		(at 181.714648 -1.524)
		(size 0.7112)
		(drill 0.4064)
		(layers "F.Cu" "B.Cu")
		(net "GND")
	)
	(via
		(at 482.6 -63.5)
		(size 0.5588)
		(drill 0.3048)
		(layers "F.Cu" "B.Cu")
		(net "GND")
	)
	(via
		(at 343.408 -131.064)
		(size 0.5588)
		(drill 0.3048)
		(layers "F.Cu" "B.Cu")
		(net "GND")
	)
	(via
		(at 205.9178 -197.231)
		(size 0.5588)
		(drill 0.3048)
		(layers "F.Cu" "B.Cu")
		(net "GND")
	)
	(via
		(at 463.895186 -120.194578)
		(size 0.5588)
		(drill 0.3048)
		(layers "F.Cu" "B.Cu")
		(net "GND")
	)
	(via
		(at 346.319856 -384.47599)
		(size 0.7112)
		(drill 0.4064)
		(layers "F.Cu" "B.Cu")
		(net "GND")
	)
	(via
		(at 243.967 -288.163)
		(size 0.5588)
		(drill 0.3048)
		(layers "F.Cu" "B.Cu")
		(net "GND")
	)
	(via
		(at 196.954648 -1.524)
		(size 0.7112)
		(drill 0.4064)
		(layers "F.Cu" "B.Cu")
		(net "GND")
	)
	(via
		(at 152.4 -195.58)
		(size 0.5588)
		(drill 0.3048)
		(layers "F.Cu" "B.Cu")
		(net "GND")
	)
	(via
		(at 404.836376 -1.524)
		(size 0.7112)
		(drill 0.4064)
		(layers "F.Cu" "B.Cu")
		(net "GND")
	)
	(via
		(at 187.833 -237.035086)
		(size 0.5588)
		(drill 0.3048)
		(layers "F.Cu" "B.Cu")
		(net "GND")
	)
	(via
		(at 122.954796 -263.355074)
		(size 0.5588)
		(drill 0.3048)
		(layers "F.Cu" "B.Cu")
		(net "GND")
	)
	(via
		(at 171.554648 -1.524)
		(size 0.7112)
		(drill 0.4064)
		(layers "F.Cu" "B.Cu")
		(net "GND")
	)
	(via
		(at 425.45 -38.608)
		(size 0.5588)
		(drill 0.3048)
		(layers "F.Cu" "B.Cu")
		(net "GND")
	)
	(via
		(at 280.924 -252.476)
		(size 0.5588)
		(drill 0.3048)
		(layers "F.Cu" "B.Cu")
		(net "GND")
	)
	(via
		(at 343.876376 -1.524)
		(size 0.7112)
		(drill 0.4064)
		(layers "F.Cu" "B.Cu")
		(net "GND")
	)
	(via
		(at 489.926122 -23.87219)
		(size 0.7112)
		(drill 0.4064)
		(layers "F.Cu" "B.Cu")
		(net "GND")
	)
	(via
		(at 489.926122 -121.66219)
		(size 0.7112)
		(drill 0.4064)
		(layers "F.Cu" "B.Cu")
		(net "GND")
	)
	(via
		(at 209.804 -269.748)
		(size 0.5588)
		(drill 0.3048)
		(layers "F.Cu" "B.Cu")
		(net "GND")
	)
	(via
		(at 184.289954 -384.47599)
		(size 0.7112)
		(drill 0.4064)
		(layers "F.Cu" "B.Cu")
		(net "GND")
	)
	(via
		(at 486.811828 -384.47599)
		(size 0.7112)
		(drill 0.4064)
		(layers "F.Cu" "B.Cu")
		(net "GND")
	)
	(via
		(at 1.524 -344.573352)
		(size 0.7112)
		(drill 0.4064)
		(layers "F.Cu" "B.Cu")
		(net "GND")
	)
	(via
		(at 364.5408 -244.856)
		(size 0.5588)
		(drill 0.3048)
		(layers "F.Cu" "B.Cu")
		(net "GND")
	)
	(via
		(at 186.055 -38.435026)
		(size 0.5588)
		(drill 0.3048)
		(layers "F.Cu" "B.Cu")
		(net "GND")
	)
	(via
		(at 1.524 -199.793352)
		(size 0.7112)
		(drill 0.4064)
		(layers "F.Cu" "B.Cu")
		(net "GND")
	)
	(via
		(at 362.6612 -247.65)
		(size 0.5588)
		(drill 0.3048)
		(layers "F.Cu" "B.Cu")
		(net "GND")
	)
	(via
		(at 320.548 -44.196)
		(size 0.5588)
		(drill 0.3048)
		(layers "F.Cu" "B.Cu")
		(net "GND")
	)
	(via
		(at 323.141594 -146.19605)
		(size 0.5588)
		(drill 0.3048)
		(layers "F.Cu" "B.Cu")
		(net "GND")
	)
	(via
		(at 105.07599 -378.476002)
		(size 0.7112)
		(drill 0.4064)
		(layers "F.Cu" "B.Cu")
		(net "GND")
	)
	(via
		(at 58.674 -20.828)
		(size 0.5588)
		(drill 0.3048)
		(layers "F.Cu" "B.Cu")
		(net "GND")
	)
	(via
		(at 16.3195 -25.019)
		(size 0.5588)
		(drill 0.3048)
		(layers "F.Cu" "B.Cu")
		(net "GND")
	)
	(via
		(at 135.347964 -365.820452)
		(size 0.5588)
		(drill 0.3048)
		(layers "F.Cu" "B.Cu")
		(net "GND")
	)
	(via
		(at 309.091076 -334.970882)
		(size 0.5588)
		(drill 0.3048)
		(layers "F.Cu" "B.Cu")
		(net "GND")
	)
	(via
		(at 1.524 -353.463352)
		(size 0.7112)
		(drill 0.4064)
		(layers "F.Cu" "B.Cu")
		(net "GND")
	)
	(via
		(at 489.926122 -191.51219)
		(size 0.7112)
		(drill 0.4064)
		(layers "F.Cu" "B.Cu")
		(net "GND")
	)
	(via
		(at 399.796 -6.604)
		(size 0.5588)
		(drill 0.3048)
		(layers "F.Cu" "B.Cu")
		(net "GND")
	)
	(via
		(at 1.524 -258.213352)
		(size 0.7112)
		(drill 0.4064)
		(layers "F.Cu" "B.Cu")
		(net "GND")
	)
	(via
		(at 486.925874 -379.510036)
		(size 0.7112)
		(drill 0.4064)
		(layers "F.Cu" "B.Cu")
		(net "GND")
	)
	(via
		(at 479.191828 -384.47599)
		(size 0.7112)
		(drill 0.4064)
		(layers "F.Cu" "B.Cu")
		(net "GND")
	)
	(via
		(at 235.839 -310.0578)
		(size 0.5588)
		(drill 0.3048)
		(layers "F.Cu" "B.Cu")
		(net "GND")
	)
	(via
		(at 230.327962 -378.476002)
		(size 0.7112)
		(drill 0.4064)
		(layers "F.Cu" "B.Cu")
		(net "GND")
	)
	(via
		(at 461.863186 -120.194578)
		(size 0.5588)
		(drill 0.3048)
		(layers "F.Cu" "B.Cu")
		(net "GND")
	)
	(via
		(at 363.728 -122.428)
		(size 0.5588)
		(drill 0.3048)
		(layers "F.Cu" "B.Cu")
		(net "GND")
	)
	(via
		(at 184.254648 -1.524)
		(size 0.7112)
		(drill 0.4064)
		(layers "F.Cu" "B.Cu")
		(net "GND")
	)
	(via
		(at 61.632846 -7.035038)
		(size 0.5588)
		(drill 0.3048)
		(layers "F.Cu" "B.Cu")
		(net "GND")
	)
	(via
		(at 459.867 -153.289)
		(size 0.5588)
		(drill 0.3048)
		(layers "F.Cu" "B.Cu")
		(net "GND")
	)
	(via
		(at 458.752956 -231.086914)
		(size 0.5588)
		(drill 0.3048)
		(layers "F.Cu" "B.Cu")
		(net "GND")
	)
	(via
		(at 398.8054 -148.2852)
		(size 0.5588)
		(drill 0.3048)
		(layers "F.Cu" "B.Cu")
		(net "GND")
	)
	(via
		(at 312.523886 -41.29151)
		(size 0.7112)
		(drill 0.4064)
		(layers "F.Cu" "B.Cu")
		(net "GND")
	)
	(via
		(at 406.4 -304.8)
		(size 0.5588)
		(drill 0.3048)
		(layers "F.Cu" "B.Cu")
		(net "GND")
	)
	(via
		(at 469.749378 -216.497154)
		(size 0.5588)
		(drill 0.3048)
		(layers "F.Cu" "B.Cu")
		(net "GND")
	)
	(via
		(at 154.504898 -246.845074)
		(size 0.5588)
		(drill 0.3048)
		(layers "F.Cu" "B.Cu")
		(net "GND")
	)
	(via
		(at 482.306376 -1.524)
		(size 0.7112)
		(drill 0.4064)
		(layers "F.Cu" "B.Cu")
		(net "GND")
	)
	(via
		(at 489.926122 -288.03219)
		(size 0.7112)
		(drill 0.4064)
		(layers "F.Cu" "B.Cu")
		(net "GND")
	)
	(via
		(at 149.6695 -135.382)
		(size 0.5588)
		(drill 0.3048)
		(layers "F.Cu" "B.Cu")
		(net "GND")
	)
	(via
		(at 135.873998 -384.47599)
		(size 0.7112)
		(drill 0.4064)
		(layers "F.Cu" "B.Cu")
		(net "GND")
	)
	(via
		(at 148.844 -271.3228)
		(size 0.5588)
		(drill 0.3048)
		(layers "F.Cu" "B.Cu")
		(net "GND")
	)
	(via
		(at 51.83505 -101.246686)
		(size 0.5588)
		(drill 0.3048)
		(layers "F.Cu" "B.Cu")
		(net "GND")
	)
	(via
		(at 420.304976 -260.815074)
		(size 0.5588)
		(drill 0.3048)
		(layers "F.Cu" "B.Cu")
		(net "GND")
	)
	(via
		(at 482.6 -355.6)
		(size 0.5588)
		(drill 0.3048)
		(layers "F.Cu" "B.Cu")
		(net "GND")
	)
	(via
		(at 374.577864 -378.476002)
		(size 0.7112)
		(drill 0.4064)
		(layers "F.Cu" "B.Cu")
		(net "GND")
	)
	(via
		(at 473.71 -145.542)
		(size 0.5588)
		(drill 0.3048)
		(layers "F.Cu" "B.Cu")
		(net "GND")
	)
	(via
		(at 279.078436 -49.724056)
		(size 0.7112)
		(drill 0.4064)
		(layers "F.Cu" "B.Cu")
		(net "GND")
	)
	(via
		(at 177.8 -292.1)
		(size 0.5588)
		(drill 0.3048)
		(layers "F.Cu" "B.Cu")
		(net "GND")
	)
	(via
		(at 158.24327 -148.347938)
		(size 0.5588)
		(drill 0.3048)
		(layers "F.Cu" "B.Cu")
		(net "GND")
	)
	(via
		(at 1.524 -239.163352)
		(size 0.7112)
		(drill 0.4064)
		(layers "F.Cu" "B.Cu")
		(net "GND")
	)
	(via
		(at 243.027962 -378.476002)
		(size 0.7112)
		(drill 0.4064)
		(layers "F.Cu" "B.Cu")
		(net "GND")
	)
	(via
		(at 475.956376 -1.524)
		(size 0.7112)
		(drill 0.4064)
		(layers "F.Cu" "B.Cu")
		(net "GND")
	)
	(via
		(at 185.950098 -52.793138)
		(size 0.5588)
		(drill 0.3048)
		(layers "F.Cu" "B.Cu")
		(net "GND")
	)
	(via
		(at 238.4806 -280.3398)
		(size 0.7112)
		(drill 0.4064)
		(layers "F.Cu" "B.Cu")
		(net "GND")
	)
	(via
		(at 176.276 -263.779)
		(size 0.5588)
		(drill 0.3048)
		(layers "F.Cu" "B.Cu")
		(net "GND")
	)
	(via
		(at 121.811796 -256.23012)
		(size 0.5588)
		(drill 0.3048)
		(layers "F.Cu" "B.Cu")
		(net "GND")
	)
	(via
		(at 378.46 -151.892)
		(size 0.5588)
		(drill 0.3048)
		(layers "F.Cu" "B.Cu")
		(net "GND")
	)
	(via
		(at 106.34599 -378.476002)
		(size 0.7112)
		(drill 0.4064)
		(layers "F.Cu" "B.Cu")
		(net "GND")
	)
	(via
		(at 489.926122 -134.36219)
		(size 0.7112)
		(drill 0.4064)
		(layers "F.Cu" "B.Cu")
		(net "GND")
	)
	(via
		(at 1.524 -96.923352)
		(size 0.7112)
		(drill 0.4064)
		(layers "F.Cu" "B.Cu")
		(net "GND")
	)
	(via
		(at 304.903378 -233.18724)
		(size 0.5588)
		(drill 0.3048)
		(layers "F.Cu" "B.Cu")
		(net "GND")
	)
	(via
		(at 189.334648 -1.524)
		(size 0.7112)
		(drill 0.4064)
		(layers "F.Cu" "B.Cu")
		(net "GND")
	)
	(via
		(at 78.40599 -378.476002)
		(size 0.7112)
		(drill 0.4064)
		(layers "F.Cu" "B.Cu")
		(net "GND")
	)
	(via
		(at 27.161998 -256.23012)
		(size 0.5588)
		(drill 0.3048)
		(layers "F.Cu" "B.Cu")
		(net "GND")
	)
	(via
		(at 28.304998 -153.43505)
		(size 0.5588)
		(drill 0.3048)
		(layers "F.Cu" "B.Cu")
		(net "GND")
	)
	(via
		(at 44.81195 -216.8398)
		(size 0.5588)
		(drill 0.3048)
		(layers "F.Cu" "B.Cu")
		(net "GND")
	)
	(via
		(at 189.574424 -153.43505)
		(size 0.5588)
		(drill 0.3048)
		(layers "F.Cu" "B.Cu")
		(net "GND")
	)
	(via
		(at 207.467962 -378.476002)
		(size 0.7112)
		(drill 0.4064)
		(layers "F.Cu" "B.Cu")
		(net "GND")
	)
	(via
		(at 144.7546 -263.779)
		(size 0.5588)
		(drill 0.3048)
		(layers "F.Cu" "B.Cu")
		(net "GND")
	)
	(via
		(at 28.304998 -243.035074)
		(size 0.5588)
		(drill 0.3048)
		(layers "F.Cu" "B.Cu")
		(net "GND")
	)
	(via
		(at 423.155872 -384.47599)
		(size 0.7112)
		(drill 0.4064)
		(layers "F.Cu" "B.Cu")
		(net "GND")
	)
	(via
		(at 79.676752 -335.974944)
		(size 0.5588)
		(drill 0.3048)
		(layers "F.Cu" "B.Cu")
		(net "GND")
	)
	(via
		(at 459.995016 -384.429)
		(size 0.7112)
		(drill 0.4064)
		(layers "F.Cu" "B.Cu")
		(net "GND")
	)
	(via
		(at 43.768772 -214.574628)
		(size 0.5588)
		(drill 0.3048)
		(layers "F.Cu" "B.Cu")
		(net "GND")
	)
	(via
		(at 428.301404 -363.855)
		(size 0.5588)
		(drill 0.3048)
		(layers "F.Cu" "B.Cu")
		(net "GND")
	)
	(via
		(at 351.910396 -363.093)
		(size 0.7112)
		(drill 0.4064)
		(layers "F.Cu" "B.Cu")
		(net "GND")
	)
	(via
		(at 1.524 -67.713352)
		(size 0.7112)
		(drill 0.4064)
		(layers "F.Cu" "B.Cu")
		(net "GND")
	)
	(via
		(at 102.108 -16.256)
		(size 0.5588)
		(drill 0.3048)
		(layers "F.Cu" "B.Cu")
		(net "GND")
	)
	(via
		(at 334.889856 -384.47599)
		(size 0.7112)
		(drill 0.4064)
		(layers "F.Cu" "B.Cu")
		(net "GND")
	)
	(via
		(at 96.624648 -1.524)
		(size 0.7112)
		(drill 0.4064)
		(layers "F.Cu" "B.Cu")
		(net "GND")
	)
	(via
		(at 280.791158 -103.624888)
		(size 0.7112)
		(drill 0.4064)
		(layers "F.Cu" "B.Cu")
		(net "GND")
	)
	(via
		(at 489.926122 -326.13219)
		(size 0.7112)
		(drill 0.4064)
		(layers "F.Cu" "B.Cu")
		(net "GND")
	)
	(via
		(at 1.524 -169.313352)
		(size 0.7112)
		(drill 0.4064)
		(layers "F.Cu" "B.Cu")
		(net "GND")
	)
	(via
		(at 466.155024 -380.775972)
		(size 0.7112)
		(drill 0.4064)
		(layers "F.Cu" "B.Cu")
		(net "GND")
	)
	(via
		(at 82.21599 -378.476002)
		(size 0.7112)
		(drill 0.4064)
		(layers "F.Cu" "B.Cu")
		(net "GND")
	)
	(via
		(at 444.5 -292.1)
		(size 0.5588)
		(drill 0.3048)
		(layers "F.Cu" "B.Cu")
		(net "GND")
	)
	(via
		(at 420.615872 -384.47599)
		(size 0.7112)
		(drill 0.4064)
		(layers "F.Cu" "B.Cu")
		(net "GND")
	)
	(via
		(at 489.926122 -200.40219)
		(size 0.7112)
		(drill 0.4064)
		(layers "F.Cu" "B.Cu")
		(net "GND")
	)
	(via
		(at 337.429856 -384.47599)
		(size 0.7112)
		(drill 0.4064)
		(layers "F.Cu" "B.Cu")
		(net "GND")
	)
	(via
		(at 422.082976 -7.035038)
		(size 0.5588)
		(drill 0.3048)
		(layers "F.Cu" "B.Cu")
		(net "GND")
	)
	(via
		(at 425.156376 -1.524)
		(size 0.7112)
		(drill 0.4064)
		(layers "F.Cu" "B.Cu")
		(net "GND")
	)
	(via
		(at 175.364648 -1.524)
		(size 0.7112)
		(drill 0.4064)
		(layers "F.Cu" "B.Cu")
		(net "GND")
	)
	(via
		(at 388.754874 -13.035026)
		(size 0.5588)
		(drill 0.3048)
		(layers "F.Cu" "B.Cu")
		(net "GND")
	)
	(via
		(at 1.524 -34.693352)
		(size 0.7112)
		(drill 0.4064)
		(layers "F.Cu" "B.Cu")
		(net "GND")
	)
	(via
		(at 270.383 -50.165)
		(size 0.7112)
		(drill 0.4064)
		(layers "F.Cu" "B.Cu")
		(net "GND")
	)
	(via
		(at 427.6598 -129.921)
		(size 0.5588)
		(drill 0.3048)
		(layers "F.Cu" "B.Cu")
		(net "GND")
	)
	(via
		(at 489.926122 -39.11219)
		(size 0.7112)
		(drill 0.4064)
		(layers "F.Cu" "B.Cu")
		(net "GND")
	)
	(via
		(at 179.835048 -380.775972)
		(size 0.7112)
		(drill 0.4064)
		(layers "F.Cu" "B.Cu")
		(net "GND")
	)
	(via
		(at 193.144648 -1.524)
		(size 0.7112)
		(drill 0.4064)
		(layers "F.Cu" "B.Cu")
		(net "GND")
	)
	(via
		(at 489.926122 -275.33219)
		(size 0.7112)
		(drill 0.4064)
		(layers "F.Cu" "B.Cu")
		(net "GND")
	)
	(via
		(at 357.205026 -128.03505)
		(size 0.5588)
		(drill 0.3048)
		(layers "F.Cu" "B.Cu")
		(net "GND")
	)
	(via
		(at 85.1408 -20.4978)
		(size 0.5588)
		(drill 0.3048)
		(layers "F.Cu" "B.Cu")
		(net "GND")
	)
	(via
		(at 420.304976 -246.845074)
		(size 0.5588)
		(drill 0.3048)
		(layers "F.Cu" "B.Cu")
		(net "GND")
	)
	(via
		(at 174.2059 -373.0244)
		(size 0.5588)
		(drill 0.3048)
		(layers "F.Cu" "B.Cu")
		(net "GND")
	)
	(via
		(at 474.686376 -1.524)
		(size 0.7112)
		(drill 0.4064)
		(layers "F.Cu" "B.Cu")
		(net "GND")
	)
	(via
		(at 53.848 -232.664)
		(size 0.5588)
		(drill 0.3048)
		(layers "F.Cu" "B.Cu")
		(net "GND")
	)
	(via
		(at 9.652 -88.392)
		(size 0.5588)
		(drill 0.3048)
		(layers "F.Cu" "B.Cu")
		(net "GND")
	)
	(via
		(at 489.926122 -351.53219)
		(size 0.7112)
		(drill 0.4064)
		(layers "F.Cu" "B.Cu")
		(net "GND")
	)
	(via
		(at 489.926122 -101.34219)
		(size 0.7112)
		(drill 0.4064)
		(layers "F.Cu" "B.Cu")
		(net "GND")
	)
	(via
		(at 344.424 -253.492)
		(size 0.5588)
		(drill 0.3048)
		(layers "F.Cu" "B.Cu")
		(net "GND")
	)
	(via
		(at 162.543998 -384.47599)
		(size 0.7112)
		(drill 0.4064)
		(layers "F.Cu" "B.Cu")
		(net "GND")
	)
	(via
		(at 284.448758 -101.211888)
		(size 0.7112)
		(drill 0.4064)
		(layers "F.Cu" "B.Cu")
		(net "GND")
	)
	(via
		(at 69.99986 -119.326406)
		(size 0.5588)
		(drill 0.3048)
		(layers "F.Cu" "B.Cu")
		(net "GND")
	)
	(via
		(at 181.105048 -380.775972)
		(size 0.7112)
		(drill 0.4064)
		(layers "F.Cu" "B.Cu")
		(net "GND")
	)
	(via
		(at 137.094468 -96.324928)
		(size 0.5588)
		(drill 0.3048)
		(layers "F.Cu" "B.Cu")
		(net "GND")
	)
	(via
		(at 1.524 -29.613352)
		(size 0.7112)
		(drill 0.4064)
		(layers "F.Cu" "B.Cu")
		(net "GND")
	)
	(via
		(at 469.9 -165.1)
		(size 0.5588)
		(drill 0.3048)
		(layers "F.Cu" "B.Cu")
		(net "GND")
	)
	(via
		(at 489.926122 -133.09219)
		(size 0.7112)
		(drill 0.4064)
		(layers "F.Cu" "B.Cu")
		(net "GND")
	)
	(via
		(at 368.7572 -148.2852)
		(size 0.5588)
		(drill 0.3048)
		(layers "F.Cu" "B.Cu")
		(net "GND")
	)
	(via
		(at 149.86 -172.72)
		(size 0.5588)
		(drill 0.3048)
		(layers "F.Cu" "B.Cu")
		(net "GND")
	)
	(via
		(at 191.874648 -1.524)
		(size 0.7112)
		(drill 0.4064)
		(layers "F.Cu" "B.Cu")
		(net "GND")
	)
	(via
		(at 438.199276 -216.497154)
		(size 0.5588)
		(drill 0.3048)
		(layers "F.Cu" "B.Cu")
		(net "GND")
	)
	(via
		(at 138.811 -265.684)
		(size 0.5588)
		(drill 0.3048)
		(layers "F.Cu" "B.Cu")
		(net "GND")
	)
	(via
		(at 75.692 -150.622)
		(size 0.5588)
		(drill 0.3048)
		(layers "F.Cu" "B.Cu")
		(net "GND")
	)
	(via
		(at 1.524 -217.573352)
		(size 0.7112)
		(drill 0.4064)
		(layers "F.Cu" "B.Cu")
		(net "GND")
	)
	(via
		(at 489.926122 -169.92219)
		(size 0.7112)
		(drill 0.4064)
		(layers "F.Cu" "B.Cu")
		(net "GND")
	)
	(via
		(at 1.524 -135.023352)
		(size 0.7112)
		(drill 0.4064)
		(layers "F.Cu" "B.Cu")
		(net "GND")
	)
	(via
		(at 205.476094 -55.036212)
		(size 0.7112)
		(drill 0.4064)
		(layers "F.Cu" "B.Cu")
		(net "GND")
	)
	(via
		(at 14.074648 -1.524)
		(size 0.7112)
		(drill 0.4064)
		(layers "F.Cu" "B.Cu")
		(net "GND")
	)
	(via
		(at 337.526376 -1.524)
		(size 0.7112)
		(drill 0.4064)
		(layers "F.Cu" "B.Cu")
		(net "GND")
	)
	(via
		(at 312.523886 -43.83151)
		(size 0.7112)
		(drill 0.4064)
		(layers "F.Cu" "B.Cu")
		(net "GND")
	)
	(via
		(at 489.926122 -143.25219)
		(size 0.7112)
		(drill 0.4064)
		(layers "F.Cu" "B.Cu")
		(net "GND")
	)
	(via
		(at 489.926122 -328.67219)
		(size 0.7112)
		(drill 0.4064)
		(layers "F.Cu" "B.Cu")
		(net "GND")
	)
	(via
		(at 489.926122 -31.49219)
		(size 0.7112)
		(drill 0.4064)
		(layers "F.Cu" "B.Cu")
		(net "GND")
	)
	(via
		(at 94.866968 -335.900014)
		(size 0.5588)
		(drill 0.3048)
		(layers "F.Cu" "B.Cu")
		(net "GND")
	)
	(via
		(at 439.42 -266.7)
		(size 0.5588)
		(drill 0.3048)
		(layers "F.Cu" "B.Cu")
		(net "GND")
	)
	(via
		(at 1.524 -90.573352)
		(size 0.7112)
		(drill 0.4064)
		(layers "F.Cu" "B.Cu")
		(net "GND")
	)
	(via
		(at 313.8424 -326.593962)
		(size 0.5588)
		(drill 0.3048)
		(layers "F.Cu" "B.Cu")
		(net "GND")
	)
	(via
		(at 456.226164 -226.759516)
		(size 0.5588)
		(drill 0.3048)
		(layers "F.Cu" "B.Cu")
		(net "GND")
	)
	(via
		(at 463.931 -382.651)
		(size 0.7112)
		(drill 0.4064)
		(layers "F.Cu" "B.Cu")
		(net "GND")
	)
	(via
		(at 489.926122 -192.78219)
		(size 0.7112)
		(drill 0.4064)
		(layers "F.Cu" "B.Cu")
		(net "GND")
	)
	(via
		(at 329.692 -162.1282)
		(size 0.5588)
		(drill 0.3048)
		(layers "F.Cu" "B.Cu")
		(net "GND")
	)
	(via
		(at 461.35925 -101.587554)
		(size 0.5588)
		(drill 0.3048)
		(layers "F.Cu" "B.Cu")
		(net "GND")
	)
	(via
		(at 213.93658 -239.372394)
		(size 0.5588)
		(drill 0.3048)
		(layers "F.Cu" "B.Cu")
		(net "GND")
	)
	(via
		(at 1.524 -364.893352)
		(size 0.7112)
		(drill 0.4064)
		(layers "F.Cu" "B.Cu")
		(net "GND")
	)
	(via
		(at 134.239 -366.9284)
		(size 0.5588)
		(drill 0.3048)
		(layers "F.Cu" "B.Cu")
		(net "GND")
	)
	(via
		(at 249.555 -307.086)
		(size 0.5588)
		(drill 0.3048)
		(layers "F.Cu" "B.Cu")
		(net "GND")
	)
	(via
		(at 40.64 -129.032)
		(size 0.5588)
		(drill 0.3048)
		(layers "F.Cu" "B.Cu")
		(net "GND")
	)
	(via
		(at 147.303998 -384.47599)
		(size 0.7112)
		(drill 0.4064)
		(layers "F.Cu" "B.Cu")
		(net "GND")
	)
	(via
		(at 59.854846 -270.975074)
		(size 0.5588)
		(drill 0.3048)
		(layers "F.Cu" "B.Cu")
		(net "GND")
	)
	(via
		(at 252.222 -378.841)
		(size 0.7112)
		(drill 0.4064)
		(layers "F.Cu" "B.Cu")
		(net "GND")
	)
	(via
		(at 356.576376 -1.524)
		(size 0.7112)
		(drill 0.4064)
		(layers "F.Cu" "B.Cu")
		(net "GND")
	)
	(via
		(at 225.922332 -230.592884)
		(size 0.5588)
		(drill 0.3048)
		(layers "F.Cu" "B.Cu")
		(net "GND")
	)
	(via
		(at 87.296752 -342.324944)
		(size 0.5588)
		(drill 0.3048)
		(layers "F.Cu" "B.Cu")
		(net "GND")
	)
	(via
		(at 489.926122 -11.17219)
		(size 0.7112)
		(drill 0.4064)
		(layers "F.Cu" "B.Cu")
		(net "GND")
	)
	(via
		(at 392.136376 -1.524)
		(size 0.7112)
		(drill 0.4064)
		(layers "F.Cu" "B.Cu")
		(net "GND")
	)
	(via
		(at 489.926122 -69.59219)
		(size 0.7112)
		(drill 0.4064)
		(layers "F.Cu" "B.Cu")
		(net "GND")
	)
	(via
		(at 309.372 -87.376)
		(size 0.5588)
		(drill 0.3048)
		(layers "F.Cu" "B.Cu")
		(net "GND")
	)
	(via
		(at 190.0428 -145.3388)
		(size 0.5588)
		(drill 0.3048)
		(layers "F.Cu" "B.Cu")
		(net "GND")
	)
	(via
		(at 1.524 -317.903352)
		(size 0.7112)
		(drill 0.4064)
		(layers "F.Cu" "B.Cu")
		(net "GND")
	)
	(via
		(at 447.122804 -363.093)
		(size 0.7112)
		(drill 0.4064)
		(layers "F.Cu" "B.Cu")
		(net "GND")
	)
	(via
		(at 290.508436 -49.724056)
		(size 0.7112)
		(drill 0.4064)
		(layers "F.Cu" "B.Cu")
		(net "GND")
	)
	(via
		(at 216.8906 -213.1568)
		(size 0.5588)
		(drill 0.3048)
		(layers "F.Cu" "B.Cu")
		(net "GND")
	)
	(via
		(at 477.012 -7.4422)
		(size 0.5588)
		(drill 0.3048)
		(layers "F.Cu" "B.Cu")
		(net "GND")
	)
	(via
		(at 197.47611 -32.752538)
		(size 0.7112)
		(drill 0.4064)
		(layers "F.Cu" "B.Cu")
		(net "GND")
	)
	(via
		(at 205.613 -50.165)
		(size 0.7112)
		(drill 0.4064)
		(layers "F.Cu" "B.Cu")
		(net "GND")
	)
	(via
		(at 395.946376 -1.524)
		(size 0.7112)
		(drill 0.4064)
		(layers "F.Cu" "B.Cu")
		(net "GND")
	)
	(via
		(at 29.177996 -375.0818)
		(size 0.5588)
		(drill 0.3048)
		(layers "F.Cu" "B.Cu")
		(net "GND")
	)
	(via
		(at 260.931152 -372.730014)
		(size 0.5588)
		(drill 0.3048)
		(layers "F.Cu" "B.Cu")
		(net "GND")
	)
	(via
		(at 51.435 -20.955)
		(size 0.5588)
		(drill 0.3048)
		(layers "F.Cu" "B.Cu")
		(net "GND")
	)
	(via
		(at 73.924668 -96.324928)
		(size 0.5588)
		(drill 0.3048)
		(layers "F.Cu" "B.Cu")
		(net "GND")
	)
	(via
		(at 399.756376 -1.524)
		(size 0.7112)
		(drill 0.4064)
		(layers "F.Cu" "B.Cu")
		(net "GND")
	)
	(via
		(at 279.571958 -102.405688)
		(size 0.7112)
		(drill 0.4064)
		(layers "F.Cu" "B.Cu")
		(net "GND")
	)
	(via
		(at 489.926122 -166.11219)
		(size 0.7112)
		(drill 0.4064)
		(layers "F.Cu" "B.Cu")
		(net "GND")
	)
	(via
		(at 451.854824 -145.81505)
		(size 0.5588)
		(drill 0.3048)
		(layers "F.Cu" "B.Cu")
		(net "GND")
	)
	(via
		(at 1.524 -203.603352)
		(size 0.7112)
		(drill 0.4064)
		(layers "F.Cu" "B.Cu")
		(net "GND")
	)
	(via
		(at 1.524 -328.063352)
		(size 0.7112)
		(drill 0.4064)
		(layers "F.Cu" "B.Cu")
		(net "GND")
	)
	(via
		(at 87.296752 -335.974944)
		(size 0.5588)
		(drill 0.3048)
		(layers "F.Cu" "B.Cu")
		(net "GND")
	)
	(via
		(at 287.968436 -49.724056)
		(size 0.7112)
		(drill 0.4064)
		(layers "F.Cu" "B.Cu")
		(net "GND")
	)
	(via
		(at 30.082998 -50.785014)
		(size 0.5588)
		(drill 0.3048)
		(layers "F.Cu" "B.Cu")
		(net "GND")
	)
	(via
		(at 59.854846 -40.975026)
		(size 0.5588)
		(drill 0.3048)
		(layers "F.Cu" "B.Cu")
		(net "GND")
	)
	(via
		(at 482.793802 -230.51135)
		(size 0.5588)
		(drill 0.3048)
		(layers "F.Cu" "B.Cu")
		(net "GND")
	)
	(via
		(at 393.406376 -1.524)
		(size 0.7112)
		(drill 0.4064)
		(layers "F.Cu" "B.Cu")
		(net "GND")
	)
	(via
		(at 41.656 -271.272)
		(size 0.5588)
		(drill 0.3048)
		(layers "F.Cu" "B.Cu")
		(net "GND")
	)
	(via
		(at 489.926122 -252.47219)
		(size 0.7112)
		(drill 0.4064)
		(layers "F.Cu" "B.Cu")
		(net "GND")
	)
	(via
		(at 135.128 -22.86)
		(size 0.5588)
		(drill 0.3048)
		(layers "F.Cu" "B.Cu")
		(net "GND")
	)
	(via
		(at 115.23599 -378.476002)
		(size 0.7112)
		(drill 0.4064)
		(layers "F.Cu" "B.Cu")
		(net "GND")
	)
	(via
		(at 12.804648 -1.524)
		(size 0.7112)
		(drill 0.4064)
		(layers "F.Cu" "B.Cu")
		(net "GND")
	)
	(via
		(at 356.062026 -141.230096)
		(size 0.5588)
		(drill 0.3048)
		(layers "F.Cu" "B.Cu")
		(net "GND")
	)
	(via
		(at 419.161976 -251.430028)
		(size 0.5588)
		(drill 0.3048)
		(layers "F.Cu" "B.Cu")
		(net "GND")
	)
	(via
		(at 149.6695 -20.447)
		(size 0.5588)
		(drill 0.3048)
		(layers "F.Cu" "B.Cu")
		(net "GND")
	)
	(via
		(at 327.432924 -280.785062)
		(size 0.5588)
		(drill 0.3048)
		(layers "F.Cu" "B.Cu")
		(net "GND")
	)
	(via
		(at 176.784 -248.6152)
		(size 0.5588)
		(drill 0.3048)
		(layers "F.Cu" "B.Cu")
		(net "GND")
	)
	(via
		(at 482.261926 -23.830026)
		(size 0.5588)
		(drill 0.3048)
		(layers "F.Cu" "B.Cu")
		(net "GND")
	)
	(via
		(at 11.892026 -384.47599)
		(size 0.7112)
		(drill 0.4064)
		(layers "F.Cu" "B.Cu")
		(net "GND")
	)
	(via
		(at 1.524 -301.393352)
		(size 0.7112)
		(drill 0.4064)
		(layers "F.Cu" "B.Cu")
		(net "GND")
	)
	(via
		(at 59.854846 -131.84505)
		(size 0.5588)
		(drill 0.3048)
		(layers "F.Cu" "B.Cu")
		(net "GND")
	)
	(via
		(at 189.81166 -30.18028)
		(size 0.5588)
		(drill 0.3048)
		(layers "F.Cu" "B.Cu")
		(net "GND")
	)
	(via
		(at 22.0218 -20.4978)
		(size 0.5588)
		(drill 0.3048)
		(layers "F.Cu" "B.Cu")
		(net "GND")
	)
	(via
		(at 117.348 -240.538)
		(size 0.5588)
		(drill 0.3048)
		(layers "F.Cu" "B.Cu")
		(net "GND")
	)
	(via
		(at 374.904 -131.572)
		(size 0.5588)
		(drill 0.3048)
		(layers "F.Cu" "B.Cu")
		(net "GND")
	)
	(via
		(at 1.524 -170.583352)
		(size 0.7112)
		(drill 0.4064)
		(layers "F.Cu" "B.Cu")
		(net "GND")
	)
	(via
		(at 91.207844 -333.554832)
		(size 0.5588)
		(drill 0.3048)
		(layers "F.Cu" "B.Cu")
		(net "GND")
	)
	(via
		(at 403.801072 -216.759028)
		(size 0.5588)
		(drill 0.3048)
		(layers "F.Cu" "B.Cu")
		(net "GND")
	)
	(via
		(at 306.832 -381.635)
		(size 0.7112)
		(drill 0.4064)
		(layers "F.Cu" "B.Cu")
		(net "GND")
	)
	(via
		(at 82.169 -248.6152)
		(size 0.5588)
		(drill 0.3048)
		(layers "F.Cu" "B.Cu")
		(net "GND")
	)
	(via
		(at 280.791158 -102.405688)
		(size 0.7112)
		(drill 0.4064)
		(layers "F.Cu" "B.Cu")
		(net "GND")
	)
	(via
		(at 393.7 -215.9)
		(size 0.5588)
		(drill 0.3048)
		(layers "F.Cu" "B.Cu")
		(net "GND")
	)
	(via
		(at 446.746376 -1.524)
		(size 0.7112)
		(drill 0.4064)
		(layers "F.Cu" "B.Cu")
		(net "GND")
	)
	(via
		(at 1.524 -232.813352)
		(size 0.7112)
		(drill 0.4064)
		(layers "F.Cu" "B.Cu")
		(net "GND")
	)
	(via
		(at 446.532 -189.992)
		(size 0.5588)
		(drill 0.3048)
		(layers "F.Cu" "B.Cu")
		(net "GND")
	)
	(via
		(at 168.783 -24.638)
		(size 0.5588)
		(drill 0.3048)
		(layers "F.Cu" "B.Cu")
		(net "GND")
	)
	(via
		(at 28.304998 -268.435074)
		(size 0.5588)
		(drill 0.3048)
		(layers "F.Cu" "B.Cu")
		(net "GND")
	)
	(via
		(at 21.59 -226.949)
		(size 0.5588)
		(drill 0.3048)
		(layers "F.Cu" "B.Cu")
		(net "GND")
	)
	(via
		(at 43.284648 -1.524)
		(size 0.7112)
		(drill 0.4064)
		(layers "F.Cu" "B.Cu")
		(net "GND")
	)
	(via
		(at 238.9505 -225.044)
		(size 0.5588)
		(drill 0.3048)
		(layers "F.Cu" "B.Cu")
		(net "GND")
	)
	(via
		(at 4.523994 -375.334022)
		(size 0.7112)
		(drill 0.4064)
		(layers "F.Cu" "B.Cu")
		(net "GND")
	)
	(via
		(at 303.784 -346.964)
		(size 0.5588)
		(drill 0.3048)
		(layers "F.Cu" "B.Cu")
		(net "GND")
	)
	(via
		(at 257.07975 -235.17225)
		(size 0.5588)
		(drill 0.3048)
		(layers "F.Cu" "B.Cu")
		(net "GND")
	)
	(via
		(at 489.926122 -352.80219)
		(size 0.7112)
		(drill 0.4064)
		(layers "F.Cu" "B.Cu")
		(net "GND")
	)
	(via
		(at 489.926122 -49.27219)
		(size 0.7112)
		(drill 0.4064)
		(layers "F.Cu" "B.Cu")
		(net "GND")
	)
	(via
		(at 95.19412 -364.388146)
		(size 0.7112)
		(drill 0.4064)
		(layers "F.Cu" "B.Cu")
		(net "GND")
	)
	(via
		(at 406.106376 -1.524)
		(size 0.7112)
		(drill 0.4064)
		(layers "F.Cu" "B.Cu")
		(net "GND")
	)
	(via
		(at 181.864 -144.399)
		(size 0.5588)
		(drill 0.3048)
		(layers "F.Cu" "B.Cu")
		(net "GND")
	)
	(via
		(at 42.909998 -217.13063)
		(size 0.5588)
		(drill 0.3048)
		(layers "F.Cu" "B.Cu")
		(net "GND")
	)
	(via
		(at 300.709076 -335.224882)
		(size 0.5588)
		(drill 0.3048)
		(layers "F.Cu" "B.Cu")
		(net "GND")
	)
	(via
		(at 288.911284 -141.09446)
		(size 0.6604)
		(drill 0.3556)
		(layers "F.Cu" "B.Cu")
		(net "GND")
	)
	(via
		(at 321.016376 -1.524)
		(size 0.7112)
		(drill 0.4064)
		(layers "F.Cu" "B.Cu")
		(net "GND")
	)
	(via
		(at 256.5273 -212.852)
		(size 0.5588)
		(drill 0.3048)
		(layers "F.Cu" "B.Cu")
		(net "GND")
	)
	(via
		(at 1.524 -187.093352)
		(size 0.7112)
		(drill 0.4064)
		(layers "F.Cu" "B.Cu")
		(net "GND")
	)
	(via
		(at 333.619856 -384.47599)
		(size 0.7112)
		(drill 0.4064)
		(layers "F.Cu" "B.Cu")
		(net "GND")
	)
	(via
		(at 169.03065 -101.442012)
		(size 0.5588)
		(drill 0.3048)
		(layers "F.Cu" "B.Cu")
		(net "GND")
	)
	(via
		(at 1.524 -11.833352)
		(size 0.7112)
		(drill 0.4064)
		(layers "F.Cu" "B.Cu")
		(net "GND")
	)
	(via
		(at 278.274018 -362.218478)
		(size 0.7112)
		(drill 0.4064)
		(layers "F.Cu" "B.Cu")
		(net "GND")
	)
	(via
		(at 119.04599 -378.476002)
		(size 0.7112)
		(drill 0.4064)
		(layers "F.Cu" "B.Cu")
		(net "GND")
	)
	(via
		(at 433.324 -164.084)
		(size 0.5588)
		(drill 0.3048)
		(layers "F.Cu" "B.Cu")
		(net "GND")
	)
	(via
		(at 244.297962 -378.476002)
		(size 0.7112)
		(drill 0.4064)
		(layers "F.Cu" "B.Cu")
		(net "GND")
	)
	(via
		(at 406.527 -247.65)
		(size 0.5588)
		(drill 0.3048)
		(layers "F.Cu" "B.Cu")
		(net "GND")
	)
	(via
		(at 86.464648 -1.524)
		(size 0.7112)
		(drill 0.4064)
		(layers "F.Cu" "B.Cu")
		(net "GND")
	)
	(via
		(at 340.701122 -101.759004)
		(size 0.5588)
		(drill 0.3048)
		(layers "F.Cu" "B.Cu")
		(net "GND")
	)
	(via
		(at 415.036 -156.972)
		(size 0.5588)
		(drill 0.3048)
		(layers "F.Cu" "B.Cu")
		(net "GND")
	)
	(via
		(at 341.336376 -1.524)
		(size 0.7112)
		(drill 0.4064)
		(layers "F.Cu" "B.Cu")
		(net "GND")
	)
	(via
		(at 482.6 -330.2)
		(size 0.5588)
		(drill 0.3048)
		(layers "F.Cu" "B.Cu")
		(net "GND")
	)
	(via
		(at 189.484 -309.372)
		(size 0.5588)
		(drill 0.3048)
		(layers "F.Cu" "B.Cu")
		(net "GND")
	)
	(via
		(at 22.352 -126.492)
		(size 0.5588)
		(drill 0.3048)
		(layers "F.Cu" "B.Cu")
		(net "GND")
	)
	(via
		(at 1.524 -298.853352)
		(size 0.7112)
		(drill 0.4064)
		(layers "F.Cu" "B.Cu")
		(net "GND")
	)
	(via
		(at 105.664 -49.784)
		(size 0.5588)
		(drill 0.3048)
		(layers "F.Cu" "B.Cu")
		(net "GND")
	)
	(via
		(at 197.47611 -28.942538)
		(size 0.7112)
		(drill 0.4064)
		(layers "F.Cu" "B.Cu")
		(net "GND")
	)
	(via
		(at 453.632824 -165.785038)
		(size 0.5588)
		(drill 0.3048)
		(layers "F.Cu" "B.Cu")
		(net "GND")
	)
	(via
		(at 38.2778 -8.4074)
		(size 0.5588)
		(drill 0.3048)
		(layers "F.Cu" "B.Cu")
		(net "GND")
	)
	(via
		(at 327.437496 -363.3978)
		(size 0.5588)
		(drill 0.3048)
		(layers "F.Cu" "B.Cu")
		(net "GND")
	)
	(via
		(at 249.485658 -292.1889)
		(size 0.6096)
		(drill 0.3048)
		(layers "F.Cu" "B.Cu")
		(net "GND")
	)
	(via
		(at 489.926122 -168.65219)
		(size 0.7112)
		(drill 0.4064)
		(layers "F.Cu" "B.Cu")
		(net "GND")
	)
	(via
		(at 270.52397 -53.82133)
		(size 0.7112)
		(drill 0.4064)
		(layers "F.Cu" "B.Cu")
		(net "GND")
	)
	(via
		(at 381 -292.1)
		(size 0.5588)
		(drill 0.3048)
		(layers "F.Cu" "B.Cu")
		(net "GND")
	)
	(via
		(at 370.84 -164.084)
		(size 0.5588)
		(drill 0.3048)
		(layers "F.Cu" "B.Cu")
		(net "GND")
	)
	(via
		(at 77.66685 -101.322886)
		(size 0.5588)
		(drill 0.3048)
		(layers "F.Cu" "B.Cu")
		(net "GND")
	)
	(via
		(at 454.366376 -1.524)
		(size 0.7112)
		(drill 0.4064)
		(layers "F.Cu" "B.Cu")
		(net "GND")
	)
	(via
		(at 40.132 -38.608)
		(size 0.5588)
		(drill 0.3048)
		(layers "F.Cu" "B.Cu")
		(net "GND")
	)
	(via
		(at 26.162 -383.794)
		(size 0.7112)
		(drill 0.4064)
		(layers "F.Cu" "B.Cu")
		(net "GND")
	)
	(via
		(at 337.058 -123.698)
		(size 0.5588)
		(drill 0.3048)
		(layers "F.Cu" "B.Cu")
		(net "GND")
	)
	(via
		(at 489.926122 -343.91219)
		(size 0.7112)
		(drill 0.4064)
		(layers "F.Cu" "B.Cu")
		(net "GND")
	)
	(via
		(at 96.18599 -378.476002)
		(size 0.7112)
		(drill 0.4064)
		(layers "F.Cu" "B.Cu")
		(net "GND")
	)
	(via
		(at 140.83665 -101.511354)
		(size 0.5588)
		(drill 0.3048)
		(layers "F.Cu" "B.Cu")
		(net "GND")
	)
	(via
		(at 88.9 -215.9)
		(size 0.5588)
		(drill 0.3048)
		(layers "F.Cu" "B.Cu")
		(net "GND")
	)
	(via
		(at 489.926122 -345.18219)
		(size 0.7112)
		(drill 0.4064)
		(layers "F.Cu" "B.Cu")
		(net "GND")
	)
	(via
		(at 449.825872 -384.47599)
		(size 0.7112)
		(drill 0.4064)
		(layers "F.Cu" "B.Cu")
		(net "GND")
	)
	(via
		(at 208.5086 -225.679)
		(size 0.5588)
		(drill 0.3048)
		(layers "F.Cu" "B.Cu")
		(net "GND")
	)
	(via
		(at 325.654924 -13.035026)
		(size 0.5588)
		(drill 0.3048)
		(layers "F.Cu" "B.Cu")
		(net "GND")
	)
	(via
		(at 478.3328 -135.7884)
		(size 0.5588)
		(drill 0.3048)
		(layers "F.Cu" "B.Cu")
		(net "GND")
	)
	(via
		(at 205.907386 -194.945)
		(size 0.5588)
		(drill 0.3048)
		(layers "F.Cu" "B.Cu")
		(net "GND")
	)
	(via
		(at 394.589 -109.601)
		(size 0.5588)
		(drill 0.3048)
		(layers "F.Cu" "B.Cu")
		(net "GND")
	)
	(via
		(at 384.9116 -260.35)
		(size 0.5588)
		(drill 0.3048)
		(layers "F.Cu" "B.Cu")
		(net "GND")
	)
	(via
		(at 58.711846 -23.830026)
		(size 0.5588)
		(drill 0.3048)
		(layers "F.Cu" "B.Cu")
		(net "GND")
	)
	(via
		(at 352.151696 -359.529126)
		(size 0.6604)
		(drill 0.3302)
		(layers "F.Cu" "B.Cu")
		(net "GND")
	)
	(via
		(at 458.216 -127.381)
		(size 0.5588)
		(drill 0.3048)
		(layers "F.Cu" "B.Cu")
		(net "GND")
	)
	(via
		(at 304.8 -292.1)
		(size 0.5588)
		(drill 0.3048)
		(layers "F.Cu" "B.Cu")
		(net "GND")
	)
	(via
		(at 388.754874 -145.81505)
		(size 0.5588)
		(drill 0.3048)
		(layers "F.Cu" "B.Cu")
		(net "GND")
	)
	(via
		(at 475.3356 -20.828)
		(size 0.5588)
		(drill 0.3048)
		(layers "F.Cu" "B.Cu")
		(net "GND")
	)
	(via
		(at 35.56 -238.252)
		(size 0.5588)
		(drill 0.3048)
		(layers "F.Cu" "B.Cu")
		(net "GND")
	)
	(via
		(at 441.666376 -1.524)
		(size 0.7112)
		(drill 0.4064)
		(layers "F.Cu" "B.Cu")
		(net "GND")
	)
	(via
		(at 362.6612 -132.715)
		(size 0.5588)
		(drill 0.3048)
		(layers "F.Cu" "B.Cu")
		(net "GND")
	)
	(via
		(at 148.573998 -384.47599)
		(size 0.7112)
		(drill 0.4064)
		(layers "F.Cu" "B.Cu")
		(net "GND")
	)
	(via
		(at 91.404948 -153.43505)
		(size 0.5588)
		(drill 0.3048)
		(layers "F.Cu" "B.Cu")
		(net "GND")
	)
	(via
		(at 342.9 -304.8)
		(size 0.5588)
		(drill 0.3048)
		(layers "F.Cu" "B.Cu")
		(net "GND")
	)
	(via
		(at 489.926122 -195.32219)
		(size 0.7112)
		(drill 0.4064)
		(layers "F.Cu" "B.Cu")
		(net "GND")
	)
	(via
		(at 77.343 -261.239)
		(size 0.5588)
		(drill 0.3048)
		(layers "F.Cu" "B.Cu")
		(net "GND")
	)
	(via
		(at 169.32275 -216.7636)
		(size 0.5588)
		(drill 0.3048)
		(layers "F.Cu" "B.Cu")
		(net "GND")
	)
	(via
		(at 75.866752 -344.864944)
		(size 0.5588)
		(drill 0.3048)
		(layers "F.Cu" "B.Cu")
		(net "GND")
	)
	(via
		(at 63.5 -342.9)
		(size 0.5588)
		(drill 0.3048)
		(layers "F.Cu" "B.Cu")
		(net "GND")
	)
	(via
		(at 489.926122 -162.30219)
		(size 0.7112)
		(drill 0.4064)
		(layers "F.Cu" "B.Cu")
		(net "GND")
	)
	(via
		(at 457.617068 -96.401128)
		(size 0.5588)
		(drill 0.3048)
		(layers "F.Cu" "B.Cu")
		(net "GND")
	)
	(via
		(at 372.037864 -378.476002)
		(size 0.7112)
		(drill 0.4064)
		(layers "F.Cu" "B.Cu")
		(net "GND")
	)
	(via
		(at 189.992 -297.18)
		(size 0.5588)
		(drill 0.3048)
		(layers "F.Cu" "B.Cu")
		(net "GND")
	)
	(via
		(at 163.934648 -1.524)
		(size 0.7112)
		(drill 0.4064)
		(layers "F.Cu" "B.Cu")
		(net "GND")
	)
	(via
		(at 260.736334 -98.49358)
		(size 0.6604)
		(drill 0.3302)
		(layers "F.Cu" "B.Cu")
		(net "GND")
	)
	(via
		(at 65.452498 -123.751848)
		(size 0.5588)
		(drill 0.3048)
		(layers "F.Cu" "B.Cu")
		(net "GND")
	)
	(via
		(at 315.468 -358.648)
		(size 0.5588)
		(drill 0.3048)
		(layers "F.Cu" "B.Cu")
		(net "GND")
	)
	(via
		(at 182.499 -381)
		(size 0.7112)
		(drill 0.4064)
		(layers "F.Cu" "B.Cu")
		(net "GND")
	)
	(via
		(at 333.756 -153.289)
		(size 0.5588)
		(drill 0.3048)
		(layers "F.Cu" "B.Cu")
		(net "GND")
	)
	(via
		(at 50.8 -279.4)
		(size 0.5588)
		(drill 0.3048)
		(layers "F.Cu" "B.Cu")
		(net "GND")
	)
	(via
		(at 187.96 -305.308)
		(size 0.5588)
		(drill 0.3048)
		(layers "F.Cu" "B.Cu")
		(net "GND")
	)
	(via
		(at 485.182926 -7.035038)
		(size 0.5588)
		(drill 0.3048)
		(layers "F.Cu" "B.Cu")
		(net "GND")
	)
	(via
		(at 170.688 -291.084)
		(size 0.5588)
		(drill 0.3048)
		(layers "F.Cu" "B.Cu")
		(net "GND")
	)
	(via
		(at 405.638 -217.805)
		(size 0.5588)
		(drill 0.3048)
		(layers "F.Cu" "B.Cu")
		(net "GND")
	)
	(via
		(at 1.524 -235.353352)
		(size 0.7112)
		(drill 0.4064)
		(layers "F.Cu" "B.Cu")
		(net "GND")
	)
	(via
		(at 457.2 -330.2)
		(size 0.5588)
		(drill 0.3048)
		(layers "F.Cu" "B.Cu")
		(net "GND")
	)
	(via
		(at 396.167864 -378.476002)
		(size 0.7112)
		(drill 0.4064)
		(layers "F.Cu" "B.Cu")
		(net "GND")
	)
	(via
		(at 356.062026 -138.83005)
		(size 0.5588)
		(drill 0.3048)
		(layers "F.Cu" "B.Cu")
		(net "GND")
	)
	(via
		(at 484.825802 -230.51135)
		(size 0.5588)
		(drill 0.3048)
		(layers "F.Cu" "B.Cu")
		(net "GND")
	)
	(via
		(at 58.711846 -256.23012)
		(size 0.5588)
		(drill 0.3048)
		(layers "F.Cu" "B.Cu")
		(net "GND")
	)
	(via
		(at 180.34 -193.167)
		(size 0.5588)
		(drill 0.3048)
		(layers "F.Cu" "B.Cu")
		(net "GND")
	)
	(via
		(at 1.524 -178.203352)
		(size 0.7112)
		(drill 0.4064)
		(layers "F.Cu" "B.Cu")
		(net "GND")
	)
	(via
		(at 54.229 -241.681)
		(size 0.5588)
		(drill 0.3048)
		(layers "F.Cu" "B.Cu")
		(net "GND")
	)
	(via
		(at 480.461828 -384.47599)
		(size 0.7112)
		(drill 0.4064)
		(layers "F.Cu" "B.Cu")
		(net "GND")
	)
	(via
		(at 63.7286 -30.353)
		(size 0.5588)
		(drill 0.3048)
		(layers "F.Cu" "B.Cu")
		(net "GND")
	)
	(via
		(at 275.082 -157.48)
		(size 0.5588)
		(drill 0.3048)
		(layers "F.Cu" "B.Cu")
		(net "GND")
	)
	(via
		(at 47.183802 -230.51135)
		(size 0.5588)
		(drill 0.3048)
		(layers "F.Cu" "B.Cu")
		(net "GND")
	)
	(via
		(at 489.926122 -140.71219)
		(size 0.7112)
		(drill 0.4064)
		(layers "F.Cu" "B.Cu")
		(net "GND")
	)
	(via
		(at 240.0808 -353.949)
		(size 0.7112)
		(drill 0.4064)
		(layers "F.Cu" "B.Cu")
		(net "GND")
	)
	(via
		(at 451.854824 -243.035074)
		(size 0.5588)
		(drill 0.3048)
		(layers "F.Cu" "B.Cu")
		(net "GND")
	)
	(via
		(at 419.1 -177.8)
		(size 0.5588)
		(drill 0.3048)
		(layers "F.Cu" "B.Cu")
		(net "GND")
	)
	(via
		(at 405.892 -52.324)
		(size 0.5588)
		(drill 0.3048)
		(layers "F.Cu" "B.Cu")
		(net "GND")
	)
	(via
		(at 212.547962 -378.476002)
		(size 0.7112)
		(drill 0.4064)
		(layers "F.Cu" "B.Cu")
		(net "GND")
	)
	(via
		(at 489.926122 -152.14219)
		(size 0.7112)
		(drill 0.4064)
		(layers "F.Cu" "B.Cu")
		(net "GND")
	)
	(via
		(at 157.584648 -1.524)
		(size 0.7112)
		(drill 0.4064)
		(layers "F.Cu" "B.Cu")
		(net "GND")
	)
	(via
		(at 393.954 -153.67)
		(size 0.5588)
		(drill 0.3048)
		(layers "F.Cu" "B.Cu")
		(net "GND")
	)
	(via
		(at 59.854846 -153.43505)
		(size 0.5588)
		(drill 0.3048)
		(layers "F.Cu" "B.Cu")
		(net "GND")
	)
	(via
		(at 320.261996 -376.2756)
		(size 0.5588)
		(drill 0.3048)
		(layers "F.Cu" "B.Cu")
		(net "GND")
	)
	(via
		(at 1.524 -48.663352)
		(size 0.7112)
		(drill 0.4064)
		(layers "F.Cu" "B.Cu")
		(net "GND")
	)
	(via
		(at 482.6 -203.2)
		(size 0.5588)
		(drill 0.3048)
		(layers "F.Cu" "B.Cu")
		(net "GND")
	)
	(via
		(at 1.524 -283.613352)
		(size 0.7112)
		(drill 0.4064)
		(layers "F.Cu" "B.Cu")
		(net "GND")
	)
	(via
		(at 41.58996 -215.067388)
		(size 0.5588)
		(drill 0.3048)
		(layers "F.Cu" "B.Cu")
		(net "GND")
	)
	(via
		(at 387.611874 -136.430004)
		(size 0.5588)
		(drill 0.3048)
		(layers "F.Cu" "B.Cu")
		(net "GND")
	)
	(via
		(at 154.504898 -33.355026)
		(size 0.5588)
		(drill 0.3048)
		(layers "F.Cu" "B.Cu")
		(net "GND")
	)
	(via
		(at 14.023086 -96.336612)
		(size 0.5588)
		(drill 0.3048)
		(layers "F.Cu" "B.Cu")
		(net "GND")
	)
	(via
		(at 27.161998 -21.42998)
		(size 0.5588)
		(drill 0.3048)
		(layers "F.Cu" "B.Cu")
		(net "GND")
	)
	(via
		(at 1.524 -183.283352)
		(size 0.7112)
		(drill 0.4064)
		(layers "F.Cu" "B.Cu")
		(net "GND")
	)
	(via
		(at 387.277864 -378.476002)
		(size 0.7112)
		(drill 0.4064)
		(layers "F.Cu" "B.Cu")
		(net "GND")
	)
	(via
		(at 477.17964 -234.987592)
		(size 0.5588)
		(drill 0.3048)
		(layers "F.Cu" "B.Cu")
		(net "GND")
	)
	(via
		(at 348.742 -59.563)
		(size 0.5588)
		(drill 0.3048)
		(layers "F.Cu" "B.Cu")
		(net "GND")
	)
	(via
		(at 371.357144 -211.310728)
		(size 0.5588)
		(drill 0.3048)
		(layers "F.Cu" "B.Cu")
		(net "GND")
	)
	(via
		(at 106.365294 -216.682828)
		(size 0.5588)
		(drill 0.3048)
		(layers "F.Cu" "B.Cu")
		(net "GND")
	)
	(via
		(at 63.5 -190.5)
		(size 0.5588)
		(drill 0.3048)
		(layers "F.Cu" "B.Cu")
		(net "GND")
	)
	(via
		(at 489.926122 -102.61219)
		(size 0.7112)
		(drill 0.4064)
		(layers "F.Cu" "B.Cu")
		(net "GND")
	)
	(via
		(at 458.216 -226.949)
		(size 0.5588)
		(drill 0.3048)
		(layers "F.Cu" "B.Cu")
		(net "GND")
	)
	(via
		(at 64.874648 -1.524)
		(size 0.7112)
		(drill 0.4064)
		(layers "F.Cu" "B.Cu")
		(net "GND")
	)
	(via
		(at 412.677864 -378.476002)
		(size 0.7112)
		(drill 0.4064)
		(layers "F.Cu" "B.Cu")
		(net "GND")
	)
	(via
		(at 426.085 -162.179)
		(size 0.5588)
		(drill 0.3048)
		(layers "F.Cu" "B.Cu")
		(net "GND")
	)
	(via
		(at 422.082976 -165.785038)
		(size 0.5588)
		(drill 0.3048)
		(layers "F.Cu" "B.Cu")
		(net "GND")
	)
	(via
		(at 402.296376 -1.524)
		(size 0.7112)
		(drill 0.4064)
		(layers "F.Cu" "B.Cu")
		(net "GND")
	)
	(via
		(at 363.601 -242.316)
		(size 0.5588)
		(drill 0.3048)
		(layers "F.Cu" "B.Cu")
		(net "GND")
	)
	(via
		(at 38.204648 -1.524)
		(size 0.7112)
		(drill 0.4064)
		(layers "F.Cu" "B.Cu")
		(net "GND")
	)
	(via
		(at 132.184648 -1.524)
		(size 0.7112)
		(drill 0.4064)
		(layers "F.Cu" "B.Cu")
		(net "GND")
	)
	(via
		(at 258.164076 -194.788282)
		(size 0.7112)
		(drill 0.4064)
		(layers "F.Cu" "B.Cu")
		(net "GND")
	)
	(via
		(at 484.271828 -384.47599)
		(size 0.7112)
		(drill 0.4064)
		(layers "F.Cu" "B.Cu")
		(net "GND")
	)
	(via
		(at 215.011 -267.97)
		(size 0.5588)
		(drill 0.3048)
		(layers "F.Cu" "B.Cu")
		(net "GND")
	)
	(via
		(at 50.147982 -384.47599)
		(size 0.7112)
		(drill 0.4064)
		(layers "F.Cu" "B.Cu")
		(net "GND")
	)
	(via
		(at 64.13246 -122.704606)
		(size 0.5588)
		(drill 0.3048)
		(layers "F.Cu" "B.Cu")
		(net "GND")
	)
	(via
		(at 14.916912 -99.874324)
		(size 0.5588)
		(drill 0.3048)
		(layers "F.Cu" "B.Cu")
		(net "GND")
	)
	(via
		(at 172.847 -381.889)
		(size 0.7112)
		(drill 0.4064)
		(layers "F.Cu" "B.Cu")
		(net "GND")
	)
	(via
		(at 427.228 -122.936)
		(size 0.5588)
		(drill 0.3048)
		(layers "F.Cu" "B.Cu")
		(net "GND")
	)
	(via
		(at 1.524 -57.553352)
		(size 0.7112)
		(drill 0.4064)
		(layers "F.Cu" "B.Cu")
		(net "GND")
	)
	(via
		(at 213.2076 -189.20968)
		(size 0.5588)
		(drill 0.3048)
		(layers "F.Cu" "B.Cu")
		(net "GND")
	)
	(via
		(at 299.72 -211.328)
		(size 0.5588)
		(drill 0.3048)
		(layers "F.Cu" "B.Cu")
		(net "GND")
	)
	(via
		(at 350.538796 -363.093)
		(size 0.7112)
		(drill 0.4064)
		(layers "F.Cu" "B.Cu")
		(net "GND")
	)
	(via
		(at 451.826376 -1.524)
		(size 0.7112)
		(drill 0.4064)
		(layers "F.Cu" "B.Cu")
		(net "GND")
	)
	(via
		(at 364.196376 -1.524)
		(size 0.7112)
		(drill 0.4064)
		(layers "F.Cu" "B.Cu")
		(net "GND")
	)
	(via
		(at 489.926122 -307.08219)
		(size 0.7112)
		(drill 0.4064)
		(layers "F.Cu" "B.Cu")
		(net "GND")
	)
	(via
		(at 244.729 -313.182)
		(size 0.5588)
		(drill 0.3048)
		(layers "F.Cu" "B.Cu")
		(net "GND")
	)
	(via
		(at 489.926122 -237.23219)
		(size 0.7112)
		(drill 0.4064)
		(layers "F.Cu" "B.Cu")
		(net "GND")
	)
	(via
		(at 61.632846 -237.035086)
		(size 0.5588)
		(drill 0.3048)
		(layers "F.Cu" "B.Cu")
		(net "GND")
	)
	(via
		(at 439.85434 -120.770142)
		(size 0.5588)
		(drill 0.3048)
		(layers "F.Cu" "B.Cu")
		(net "GND")
	)
	(via
		(at 205.476094 -52.496212)
		(size 0.7112)
		(drill 0.4064)
		(layers "F.Cu" "B.Cu")
		(net "GND")
	)
	(via
		(at 85.852 -7.62)
		(size 0.5588)
		(drill 0.3048)
		(layers "F.Cu" "B.Cu")
		(net "GND")
	)
	(via
		(at 486.925874 -378.240036)
		(size 0.7112)
		(drill 0.4064)
		(layers "F.Cu" "B.Cu")
		(net "GND")
	)
	(via
		(at 489.926122 -25.14219)
		(size 0.7112)
		(drill 0.4064)
		(layers "F.Cu" "B.Cu")
		(net "GND")
	)
	(via
		(at 23.504906 -380.775972)
		(size 0.7112)
		(drill 0.4064)
		(layers "F.Cu" "B.Cu")
		(net "GND")
	)
	(via
		(at 17.884648 -1.524)
		(size 0.7112)
		(drill 0.4064)
		(layers "F.Cu" "B.Cu")
		(net "GND")
	)
	(via
		(at 481.731828 -384.47599)
		(size 0.7112)
		(drill 0.4064)
		(layers "F.Cu" "B.Cu")
		(net "GND")
	)
	(via
		(at 388.754874 -30.815026)
		(size 0.5588)
		(drill 0.3048)
		(layers "F.Cu" "B.Cu")
		(net "GND")
	)
	(via
		(at 111.42599 -378.476002)
		(size 0.7112)
		(drill 0.4064)
		(layers "F.Cu" "B.Cu")
		(net "GND")
	)
	(via
		(at 439.126376 -1.524)
		(size 0.7112)
		(drill 0.4064)
		(layers "F.Cu" "B.Cu")
		(net "GND")
	)
	(via
		(at 1.524 -303.933352)
		(size 0.7112)
		(drill 0.4064)
		(layers "F.Cu" "B.Cu")
		(net "GND")
	)
	(via
		(at 270.926052 -370.181632)
		(size 0.7112)
		(drill 0.4064)
		(layers "F.Cu" "B.Cu")
		(net "GND")
	)
	(via
		(at 489.926122 -341.37219)
		(size 0.7112)
		(drill 0.4064)
		(layers "F.Cu" "B.Cu")
		(net "GND")
	)
	(via
		(at 58.524648 -1.524)
		(size 0.7112)
		(drill 0.4064)
		(layers "F.Cu" "B.Cu")
		(net "GND")
	)
	(via
		(at 83.587844 -333.554832)
		(size 0.5588)
		(drill 0.3048)
		(layers "F.Cu" "B.Cu")
		(net "GND")
	)
	(via
		(at 41.148 -78.74)
		(size 0.5588)
		(drill 0.3048)
		(layers "F.Cu" "B.Cu")
		(net "GND")
	)
	(via
		(at 94.916752 -344.864944)
		(size 0.5588)
		(drill 0.3048)
		(layers "F.Cu" "B.Cu")
		(net "GND")
	)
	(via
		(at 113.792 -280.924)
		(size 0.5588)
		(drill 0.3048)
		(layers "F.Cu" "B.Cu")
		(net "GND")
	)
	(via
		(at 190.639954 -384.47599)
		(size 0.7112)
		(drill 0.4064)
		(layers "F.Cu" "B.Cu")
		(net "GND")
	)
	(via
		(at 426.72 -127.381)
		(size 0.5588)
		(drill 0.3048)
		(layers "F.Cu" "B.Cu")
		(net "GND")
	)
	(via
		(at 203.657962 -378.476002)
		(size 0.7112)
		(drill 0.4064)
		(layers "F.Cu" "B.Cu")
		(net "GND")
	)
	(via
		(at 420.304976 -13.035026)
		(size 0.5588)
		(drill 0.3048)
		(layers "F.Cu" "B.Cu")
		(net "GND")
	)
	(via
		(at 154.504898 -128.03505)
		(size 0.5588)
		(drill 0.3048)
		(layers "F.Cu" "B.Cu")
		(net "GND")
	)
	(via
		(at 94.866968 -337.170014)
		(size 0.5588)
		(drill 0.3048)
		(layers "F.Cu" "B.Cu")
		(net "GND")
	)
	(via
		(at 124.12599 -378.476002)
		(size 0.7112)
		(drill 0.4064)
		(layers "F.Cu" "B.Cu")
		(net "GND")
	)
	(via
		(at 482.261926 -136.430004)
		(size 0.5588)
		(drill 0.3048)
		(layers "F.Cu" "B.Cu")
		(net "GND")
	)
	(via
		(at 206.5274 -305.3334)
		(size 0.7112)
		(drill 0.4064)
		(layers "F.Cu" "B.Cu")
		(net "GND")
	)
	(via
		(at 128.326896 -361.735624)
		(size 0.5588)
		(drill 0.3048)
		(layers "F.Cu" "B.Cu")
		(net "GND")
	)
	(via
		(at 439.42 -144.272)
		(size 0.5588)
		(drill 0.3048)
		(layers "F.Cu" "B.Cu")
		(net "GND")
	)
	(via
		(at 28.304998 -155.97505)
		(size 0.5588)
		(drill 0.3048)
		(layers "F.Cu" "B.Cu")
		(net "GND")
	)
	(via
		(at 124.732796 -50.785014)
		(size 0.5588)
		(drill 0.3048)
		(layers "F.Cu" "B.Cu")
		(net "GND")
	)
	(via
		(at 457.341224 -124.62002)
		(size 0.5588)
		(drill 0.3048)
		(layers "F.Cu" "B.Cu")
		(net "GND")
	)
	(via
		(at 194.449954 -384.47599)
		(size 0.7112)
		(drill 0.4064)
		(layers "F.Cu" "B.Cu")
		(net "GND")
	)
	(via
		(at 59.200796 -363.093)
		(size 0.7112)
		(drill 0.4064)
		(layers "F.Cu" "B.Cu")
		(net "GND")
	)
	(via
		(at 84.75599 -378.476002)
		(size 0.7112)
		(drill 0.4064)
		(layers "F.Cu" "B.Cu")
		(net "GND")
	)
	(via
		(at 380.706376 -1.524)
		(size 0.7112)
		(drill 0.4064)
		(layers "F.Cu" "B.Cu")
		(net "GND")
	)
	(via
		(at 447.9544 -30.3276)
		(size 0.5588)
		(drill 0.3048)
		(layers "F.Cu" "B.Cu")
		(net "GND")
	)
	(via
		(at 394.589 -48.133)
		(size 0.5588)
		(drill 0.3048)
		(layers "F.Cu" "B.Cu")
		(net "GND")
	)
	(via
		(at 460.6798 -139.2682)
		(size 0.5588)
		(drill 0.3048)
		(layers "F.Cu" "B.Cu")
		(net "GND")
	)
	(via
		(at 450.711824 -138.83005)
		(size 0.5588)
		(drill 0.3048)
		(layers "F.Cu" "B.Cu")
		(net "GND")
	)
	(via
		(at 458.216 -224.917)
		(size 0.5588)
		(drill 0.3048)
		(layers "F.Cu" "B.Cu")
		(net "GND")
	)
	(via
		(at 128.374648 -1.524)
		(size 0.7112)
		(drill 0.4064)
		(layers "F.Cu" "B.Cu")
		(net "GND")
	)
	(via
		(at 309.558436 -49.724056)
		(size 0.7112)
		(drill 0.4064)
		(layers "F.Cu" "B.Cu")
		(net "GND")
	)
	(via
		(at 421.885872 -384.47599)
		(size 0.7112)
		(drill 0.4064)
		(layers "F.Cu" "B.Cu")
		(net "GND")
	)
	(via
		(at 209.804 -277.876)
		(size 0.5588)
		(drill 0.3048)
		(layers "F.Cu" "B.Cu")
		(net "GND")
	)
	(via
		(at 362.926376 -1.524)
		(size 0.7112)
		(drill 0.4064)
		(layers "F.Cu" "B.Cu")
		(net "GND")
	)
	(via
		(at 208.8896 -144.0434)
		(size 0.7112)
		(drill 0.4064)
		(layers "F.Cu" "B.Cu")
		(net "GND")
	)
	(via
		(at 489.926122 -115.31219)
		(size 0.7112)
		(drill 0.4064)
		(layers "F.Cu" "B.Cu")
		(net "GND")
	)
	(via
		(at 87.397844 -333.554832)
		(size 0.5588)
		(drill 0.3048)
		(layers "F.Cu" "B.Cu")
		(net "GND")
	)
	(via
		(at 130.914648 -1.524)
		(size 0.7112)
		(drill 0.4064)
		(layers "F.Cu" "B.Cu")
		(net "GND")
	)
	(via
		(at 479.766376 -1.524)
		(size 0.7112)
		(drill 0.4064)
		(layers "F.Cu" "B.Cu")
		(net "GND")
	)
	(via
		(at 489.331 -369.57)
		(size 0.7112)
		(drill 0.4064)
		(layers "F.Cu" "B.Cu")
		(net "GND")
	)
	(via
		(at 351.536 -140.716)
		(size 0.5588)
		(drill 0.3048)
		(layers "F.Cu" "B.Cu")
		(net "GND")
	)
	(via
		(at 388.754874 -153.43505)
		(size 0.5588)
		(drill 0.3048)
		(layers "F.Cu" "B.Cu")
		(net "GND")
	)
	(via
		(at 489.926122 -159.76219)
		(size 0.7112)
		(drill 0.4064)
		(layers "F.Cu" "B.Cu")
		(net "GND")
	)
	(via
		(at 278.274018 -368.568478)
		(size 0.7112)
		(drill 0.4064)
		(layers "F.Cu" "B.Cu")
		(net "GND")
	)
	(via
		(at 121.58599 -378.476002)
		(size 0.7112)
		(drill 0.4064)
		(layers "F.Cu" "B.Cu")
		(net "GND")
	)
	(via
		(at 67.056 -23.876)
		(size 0.5588)
		(drill 0.3048)
		(layers "F.Cu" "B.Cu")
		(net "GND")
	)
	(via
		(at 390.525 -166.624)
		(size 0.5588)
		(drill 0.3048)
		(layers "F.Cu" "B.Cu")
		(net "GND")
	)
	(via
		(at 479.5266 -10.4902)
		(size 0.5588)
		(drill 0.3048)
		(layers "F.Cu" "B.Cu")
		(net "GND")
	)
	(via
		(at 38.608 -124.968)
		(size 0.5588)
		(drill 0.3048)
		(layers "F.Cu" "B.Cu")
		(net "GND")
	)
	(via
		(at 27.161998 -138.83005)
		(size 0.5588)
		(drill 0.3048)
		(layers "F.Cu" "B.Cu")
		(net "GND")
	)
	(via
		(at 122.954796 -260.815074)
		(size 0.5588)
		(drill 0.3048)
		(layers "F.Cu" "B.Cu")
		(net "GND")
	)
	(via
		(at 1.524 -76.603352)
		(size 0.7112)
		(drill 0.4064)
		(layers "F.Cu" "B.Cu")
		(net "GND")
	)
	(via
		(at 90.806524 -31.367222)
		(size 0.5588)
		(drill 0.3048)
		(layers "F.Cu" "B.Cu")
		(net "GND")
	)
	(via
		(at 217.627962 -378.476002)
		(size 0.7112)
		(drill 0.4064)
		(layers "F.Cu" "B.Cu")
		(net "GND")
	)
	(via
		(at 273.794982 -358.476042)
		(size 0.7112)
		(drill 0.4064)
		(layers "F.Cu" "B.Cu")
		(net "GND")
	)
	(via
		(at 489.926122 -303.27219)
		(size 0.7112)
		(drill 0.4064)
		(layers "F.Cu" "B.Cu")
		(net "GND")
	)
	(via
		(at 20.964906 -380.775972)
		(size 0.7112)
		(drill 0.4064)
		(layers "F.Cu" "B.Cu")
		(net "GND")
	)
	(via
		(at 127.823976 -383.382012)
		(size 0.7112)
		(drill 0.4064)
		(layers "F.Cu" "B.Cu")
		(net "GND")
	)
	(via
		(at 324.511924 -138.83005)
		(size 0.5588)
		(drill 0.3048)
		(layers "F.Cu" "B.Cu")
		(net "GND")
	)
	(via
		(at 430.784 -280.924)
		(size 0.5588)
		(drill 0.3048)
		(layers "F.Cu" "B.Cu")
		(net "GND")
	)
	(via
		(at 211.6582 -217.65768)
		(size 0.5588)
		(drill 0.3048)
		(layers "F.Cu" "B.Cu")
		(net "GND")
	)
	(via
		(at 489.926122 -96.26219)
		(size 0.7112)
		(drill 0.4064)
		(layers "F.Cu" "B.Cu")
		(net "GND")
	)
	(via
		(at 82.654648 -1.524)
		(size 0.7112)
		(drill 0.4064)
		(layers "F.Cu" "B.Cu")
		(net "GND")
	)
	(via
		(at 85.725 -271.3228)
		(size 0.5588)
		(drill 0.3048)
		(layers "F.Cu" "B.Cu")
		(net "GND")
	)
	(via
		(at 489.926122 -72.13219)
		(size 0.7112)
		(drill 0.4064)
		(layers "F.Cu" "B.Cu")
		(net "GND")
	)
	(via
		(at 308.288436 -49.724056)
		(size 0.7112)
		(drill 0.4064)
		(layers "F.Cu" "B.Cu")
		(net "GND")
	)
	(via
		(at 310.918352 -214.6046)
		(size 0.5588)
		(drill 0.3048)
		(layers "F.Cu" "B.Cu")
		(net "GND")
	)
	(via
		(at 324.511924 -141.230096)
		(size 0.5588)
		(drill 0.3048)
		(layers "F.Cu" "B.Cu")
		(net "GND")
	)
	(via
		(at 457.2 -225.933)
		(size 0.5588)
		(drill 0.3048)
		(layers "F.Cu" "B.Cu")
		(net "GND")
	)
	(via
		(at 186.055 -13.035026)
		(size 0.5588)
		(drill 0.3048)
		(layers "F.Cu" "B.Cu")
		(net "GND")
	)
	(via
		(at 336.256376 -1.524)
		(size 0.7112)
		(drill 0.4064)
		(layers "F.Cu" "B.Cu")
		(net "GND")
	)
	(via
		(at 191.909954 -384.47599)
		(size 0.7112)
		(drill 0.4064)
		(layers "F.Cu" "B.Cu")
		(net "GND")
	)
	(via
		(at 39.01186 -114.119406)
		(size 0.5588)
		(drill 0.3048)
		(layers "F.Cu" "B.Cu")
		(net "GND")
	)
	(via
		(at 305.408076 -326.593962)
		(size 0.5588)
		(drill 0.3048)
		(layers "F.Cu" "B.Cu")
		(net "GND")
	)
	(via
		(at 207.6704 -141.605)
		(size 0.7112)
		(drill 0.4064)
		(layers "F.Cu" "B.Cu")
		(net "GND")
	)
	(via
		(at 279.174448 -350.335342)
		(size 0.5588)
		(drill 0.3048)
		(layers "F.Cu" "B.Cu")
		(net "GND")
	)
	(via
		(at 53.957982 -384.47599)
		(size 0.7112)
		(drill 0.4064)
		(layers "F.Cu" "B.Cu")
		(net "GND")
	)
	(via
		(at 44.069 -150.622)
		(size 0.5588)
		(drill 0.3048)
		(layers "F.Cu" "B.Cu")
		(net "GND")
	)
	(via
		(at 299.212 -308.356)
		(size 0.5588)
		(drill 0.3048)
		(layers "F.Cu" "B.Cu")
		(net "GND")
	)
	(via
		(at 153.361898 -26.230072)
		(size 0.5588)
		(drill 0.3048)
		(layers "F.Cu" "B.Cu")
		(net "GND")
	)
	(via
		(at 83.924648 -1.524)
		(size 0.7112)
		(drill 0.4064)
		(layers "F.Cu" "B.Cu")
		(net "GND")
	)
	(via
		(at 386.007864 -378.476002)
		(size 0.7112)
		(drill 0.4064)
		(layers "F.Cu" "B.Cu")
		(net "GND")
	)
	(via
		(at 489.926122 -247.39219)
		(size 0.7112)
		(drill 0.4064)
		(layers "F.Cu" "B.Cu")
		(net "GND")
	)
	(via
		(at 139.7 -292.1)
		(size 0.5588)
		(drill 0.3048)
		(layers "F.Cu" "B.Cu")
		(net "GND")
	)
	(via
		(at 1.524 -28.343352)
		(size 0.7112)
		(drill 0.4064)
		(layers "F.Cu" "B.Cu")
		(net "GND")
	)
	(via
		(at 37.6047 -5.326634)
		(size 0.5588)
		(drill 0.3048)
		(layers "F.Cu" "B.Cu")
		(net "GND")
	)
	(via
		(at 451.854824 -155.97505)
		(size 0.5588)
		(drill 0.3048)
		(layers "F.Cu" "B.Cu")
		(net "GND")
	)
	(via
		(at 457.581 -47.117)
		(size 0.5588)
		(drill 0.3048)
		(layers "F.Cu" "B.Cu")
		(net "GND")
	)
	(via
		(at 472.146376 -1.524)
		(size 0.7112)
		(drill 0.4064)
		(layers "F.Cu" "B.Cu")
		(net "GND")
	)
	(via
		(at 451.854824 -33.355026)
		(size 0.5588)
		(drill 0.3048)
		(layers "F.Cu" "B.Cu")
		(net "GND")
	)
	(via
		(at 174.827692 -140.11275)
		(size 0.5588)
		(drill 0.3048)
		(layers "F.Cu" "B.Cu")
		(net "GND")
	)
	(via
		(at 1.524 -160.423352)
		(size 0.7112)
		(drill 0.4064)
		(layers "F.Cu" "B.Cu")
		(net "GND")
	)
	(via
		(at 469.9 -50.8)
		(size 0.5588)
		(drill 0.3048)
		(layers "F.Cu" "B.Cu")
		(net "GND")
	)
	(via
		(at 122.954796 -246.845074)
		(size 0.5588)
		(drill 0.3048)
		(layers "F.Cu" "B.Cu")
		(net "GND")
	)
	(via
		(at 278.274018 -367.298478)
		(size 0.7112)
		(drill 0.4064)
		(layers "F.Cu" "B.Cu")
		(net "GND")
	)
	(via
		(at 204.0128 -144.018)
		(size 0.7112)
		(drill 0.4064)
		(layers "F.Cu" "B.Cu")
		(net "GND")
	)
	(via
		(at 30.082998 -280.785062)
		(size 0.5588)
		(drill 0.3048)
		(layers "F.Cu" "B.Cu")
		(net "GND")
	)
	(via
		(at 115.674648 -1.524)
		(size 0.7112)
		(drill 0.4064)
		(layers "F.Cu" "B.Cu")
		(net "GND")
	)
	(via
		(at 478.536 -123.952)
		(size 0.5588)
		(drill 0.3048)
		(layers "F.Cu" "B.Cu")
		(net "GND")
	)
	(via
		(at 122.954796 -38.435026)
		(size 0.5588)
		(drill 0.3048)
		(layers "F.Cu" "B.Cu")
		(net "GND")
	)
	(via
		(at 1.524 -84.223352)
		(size 0.7112)
		(drill 0.4064)
		(layers "F.Cu" "B.Cu")
		(net "GND")
	)
	(via
		(at 435.356 -99.314)
		(size 0.5588)
		(drill 0.3048)
		(layers "F.Cu" "B.Cu")
		(net "GND")
	)
	(via
		(at 288.911284 -191.89446)
		(size 0.6604)
		(drill 0.3556)
		(layers "F.Cu" "B.Cu")
		(net "GND")
	)
	(via
		(at 366.736376 -1.524)
		(size 0.7112)
		(drill 0.4064)
		(layers "F.Cu" "B.Cu")
		(net "GND")
	)
	(via
		(at 281.8384 -306.5018)
		(size 0.7112)
		(drill 0.4064)
		(layers "F.Cu" "B.Cu")
		(net "GND")
	)
	(via
		(at 1.524 -295.043352)
		(size 0.7112)
		(drill 0.4064)
		(layers "F.Cu" "B.Cu")
		(net "GND")
	)
	(via
		(at 394.589 -162.179)
		(size 0.5588)
		(drill 0.3048)
		(layers "F.Cu" "B.Cu")
		(net "GND")
	)
	(via
		(at 255.934972 -375.25071)
		(size 0.5588)
		(drill 0.3048)
		(layers "F.Cu" "B.Cu")
		(net "GND")
	)
	(via
		(at 169.014648 -1.524)
		(size 0.7112)
		(drill 0.4064)
		(layers "F.Cu" "B.Cu")
		(net "GND")
	)
	(via
		(at 1.524 -220.113352)
		(size 0.7112)
		(drill 0.4064)
		(layers "F.Cu" "B.Cu")
		(net "GND")
	)
	(via
		(at 489.926122 -234.69219)
		(size 0.7112)
		(drill 0.4064)
		(layers "F.Cu" "B.Cu")
		(net "GND")
	)
	(via
		(at 118.214648 -1.524)
		(size 0.7112)
		(drill 0.4064)
		(layers "F.Cu" "B.Cu")
		(net "GND")
	)
	(via
		(at 270.56334 -382.731518)
		(size 0.7112)
		(drill 0.4064)
		(layers "F.Cu" "B.Cu")
		(net "GND")
	)
	(via
		(at 49.634648 -1.524)
		(size 0.7112)
		(drill 0.4064)
		(layers "F.Cu" "B.Cu")
		(net "GND")
	)
	(via
		(at 19.812 -11.176)
		(size 0.5588)
		(drill 0.3048)
		(layers "F.Cu" "B.Cu")
		(net "GND")
	)
	(via
		(at 394.2842 -247.65)
		(size 0.5588)
		(drill 0.3048)
		(layers "F.Cu" "B.Cu")
		(net "GND")
	)
	(via
		(at 383.246376 -1.524)
		(size 0.7112)
		(drill 0.4064)
		(layers "F.Cu" "B.Cu")
		(net "GND")
	)
	(via
		(at 448.555872 -384.47599)
		(size 0.7112)
		(drill 0.4064)
		(layers "F.Cu" "B.Cu")
		(net "GND")
	)
	(via
		(at 245.582694 -196.219572)
		(size 0.5588)
		(drill 0.3048)
		(layers "F.Cu" "B.Cu")
		(net "GND")
	)
	(via
		(at 72.644 -107.188)
		(size 0.5588)
		(drill 0.3048)
		(layers "F.Cu" "B.Cu")
		(net "GND")
	)
	(via
		(at 28.304998 -145.81505)
		(size 0.5588)
		(drill 0.3048)
		(layers "F.Cu" "B.Cu")
		(net "GND")
	)
	(via
		(at 482.261926 -256.23012)
		(size 0.5588)
		(drill 0.3048)
		(layers "F.Cu" "B.Cu")
		(net "GND")
	)
	(via
		(at 127.823976 -382.112012)
		(size 0.7112)
		(drill 0.4064)
		(layers "F.Cu" "B.Cu")
		(net "GND")
	)
	(via
		(at 428.235872 -384.47599)
		(size 0.7112)
		(drill 0.4064)
		(layers "F.Cu" "B.Cu")
		(net "GND")
	)
	(via
		(at 1.524 -41.043352)
		(size 0.7112)
		(drill 0.4064)
		(layers "F.Cu" "B.Cu")
		(net "GND")
	)
	(via
		(at 1.524 -74.063352)
		(size 0.7112)
		(drill 0.4064)
		(layers "F.Cu" "B.Cu")
		(net "GND")
	)
	(via
		(at 357.205026 -243.035074)
		(size 0.5588)
		(drill 0.3048)
		(layers "F.Cu" "B.Cu")
		(net "GND")
	)
	(via
		(at 1.524 -175.663352)
		(size 0.7112)
		(drill 0.4064)
		(layers "F.Cu" "B.Cu")
		(net "GND")
	)
	(via
		(at 97.557844 -333.554832)
		(size 0.5588)
		(drill 0.3048)
		(layers "F.Cu" "B.Cu")
		(net "GND")
	)
	(via
		(at 145.796 -123.952)
		(size 0.5588)
		(drill 0.3048)
		(layers "F.Cu" "B.Cu")
		(net "GND")
	)
	(via
		(at 88.9 -355.6)
		(size 0.5588)
		(drill 0.3048)
		(layers "F.Cu" "B.Cu")
		(net "GND")
	)
	(via
		(at 239.776 -213.9696)
		(size 0.5588)
		(drill 0.3048)
		(layers "F.Cu" "B.Cu")
		(net "GND")
	)
	(via
		(at 388.754874 -148.35505)
		(size 0.5588)
		(drill 0.3048)
		(layers "F.Cu" "B.Cu")
		(net "GND")
	)
	(via
		(at 156.193998 -384.47599)
		(size 0.7112)
		(drill 0.4064)
		(layers "F.Cu" "B.Cu")
		(net "GND")
	)
	(via
		(at 277.808436 -49.724056)
		(size 0.7112)
		(drill 0.4064)
		(layers "F.Cu" "B.Cu")
		(net "GND")
	)
	(via
		(at 387.056376 -1.524)
		(size 0.7112)
		(drill 0.4064)
		(layers "F.Cu" "B.Cu")
		(net "GND")
	)
	(via
		(at 1.524 -35.963352)
		(size 0.7112)
		(drill 0.4064)
		(layers "F.Cu" "B.Cu")
		(net "GND")
	)
	(via
		(at 288.911284 -199.094344)
		(size 0.6604)
		(drill 0.3556)
		(layers "F.Cu" "B.Cu")
		(net "GND")
	)
	(via
		(at 451.854824 -38.435026)
		(size 0.5588)
		(drill 0.3048)
		(layers "F.Cu" "B.Cu")
		(net "GND")
	)
	(via
		(at 279.4 -76.2)
		(size 0.5588)
		(drill 0.3048)
		(layers "F.Cu" "B.Cu")
		(net "GND")
	)
	(via
		(at 1.524 -85.493352)
		(size 0.7112)
		(drill 0.4064)
		(layers "F.Cu" "B.Cu")
		(net "GND")
	)
	(via
		(at 446.024 -6.477)
		(size 0.5588)
		(drill 0.3048)
		(layers "F.Cu" "B.Cu")
		(net "GND")
	)
	(via
		(at 262.454898 -358.267)
		(size 0.5588)
		(drill 0.3048)
		(layers "F.Cu" "B.Cu")
		(net "GND")
	)
	(via
		(at 6.812026 -384.47599)
		(size 0.7112)
		(drill 0.4064)
		(layers "F.Cu" "B.Cu")
		(net "GND")
	)
	(via
		(at 312.523886 -8.27151)
		(size 0.7112)
		(drill 0.4064)
		(layers "F.Cu" "B.Cu")
		(net "GND")
	)
	(via
		(at 489.926122 -60.70219)
		(size 0.7112)
		(drill 0.4064)
		(layers "F.Cu" "B.Cu")
		(net "GND")
	)
	(via
		(at 489.926122 -355.34219)
		(size 0.7112)
		(drill 0.4064)
		(layers "F.Cu" "B.Cu")
		(net "GND")
	)
	(via
		(at 1.524 -9.293352)
		(size 0.7112)
		(drill 0.4064)
		(layers "F.Cu" "B.Cu")
		(net "GND")
	)
	(via
		(at 11.534648 -1.524)
		(size 0.7112)
		(drill 0.4064)
		(layers "F.Cu" "B.Cu")
		(net "GND")
	)
	(via
		(at 126.9746 -30.3276)
		(size 0.5588)
		(drill 0.3048)
		(layers "F.Cu" "B.Cu")
		(net "GND")
	)
	(via
		(at 218.897962 -378.476002)
		(size 0.7112)
		(drill 0.4064)
		(layers "F.Cu" "B.Cu")
		(net "GND")
	)
	(via
		(at 459.613 -162.179)
		(size 0.5588)
		(drill 0.3048)
		(layers "F.Cu" "B.Cu")
		(net "GND")
	)
	(via
		(at 36.068 -256.032)
		(size 0.5588)
		(drill 0.3048)
		(layers "F.Cu" "B.Cu")
		(net "GND")
	)
	(via
		(at 339.852 -57.15)
		(size 0.5588)
		(drill 0.3048)
		(layers "F.Cu" "B.Cu")
		(net "GND")
	)
	(via
		(at 195.453 -109.601)
		(size 0.5588)
		(drill 0.3048)
		(layers "F.Cu" "B.Cu")
		(net "GND")
	)
	(via
		(at 252.461268 -224.2566)
		(size 0.5588)
		(drill 0.3048)
		(layers "F.Cu" "B.Cu")
		(net "GND")
	)
	(via
		(at 89.004648 -1.524)
		(size 0.7112)
		(drill 0.4064)
		(layers "F.Cu" "B.Cu")
		(net "GND")
	)
	(via
		(at 250.628912 -226.3394)
		(size 0.5588)
		(drill 0.3048)
		(layers "F.Cu" "B.Cu")
		(net "GND")
	)
	(via
		(at 442.936376 -1.524)
		(size 0.7112)
		(drill 0.4064)
		(layers "F.Cu" "B.Cu")
		(net "GND")
	)
	(via
		(at 397.437864 -378.476002)
		(size 0.7112)
		(drill 0.4064)
		(layers "F.Cu" "B.Cu")
		(net "GND")
	)
	(via
		(at 396.621 -277.114)
		(size 0.5588)
		(drill 0.3048)
		(layers "F.Cu" "B.Cu")
		(net "GND")
	)
	(via
		(at 452.365872 -384.47599)
		(size 0.7112)
		(drill 0.4064)
		(layers "F.Cu" "B.Cu")
		(net "GND")
	)
	(via
		(at 215.011 -253.365)
		(size 0.5588)
		(drill 0.3048)
		(layers "F.Cu" "B.Cu")
		(net "GND")
	)
	(via
		(at 170.815 -156.337)
		(size 0.5588)
		(drill 0.3048)
		(layers "F.Cu" "B.Cu")
		(net "GND")
	)
	(via
		(at 1.524 -230.273352)
		(size 0.7112)
		(drill 0.4064)
		(layers "F.Cu" "B.Cu")
		(net "GND")
	)
	(via
		(at 108.88599 -378.476002)
		(size 0.7112)
		(drill 0.4064)
		(layers "F.Cu" "B.Cu")
		(net "GND")
	)
	(via
		(at 40.1066 -4.5466)
		(size 0.5588)
		(drill 0.3048)
		(layers "F.Cu" "B.Cu")
		(net "GND")
	)
	(via
		(at 96.186752 -344.864944)
		(size 0.5588)
		(drill 0.3048)
		(layers "F.Cu" "B.Cu")
		(net "GND")
	)
	(via
		(at 59.854846 -13.035026)
		(size 0.5588)
		(drill 0.3048)
		(layers "F.Cu" "B.Cu")
		(net "GND")
	)
	(via
		(at 1.524 -208.683352)
		(size 0.7112)
		(drill 0.4064)
		(layers "F.Cu" "B.Cu")
		(net "GND")
	)
	(via
		(at 187.790328 -371.407436)
		(size 0.5588)
		(drill 0.3048)
		(layers "F.Cu" "B.Cu")
		(net "GND")
	)
	(via
		(at 489.926122 -122.93219)
		(size 0.7112)
		(drill 0.4064)
		(layers "F.Cu" "B.Cu")
		(net "GND")
	)
	(via
		(at 87.376 -277.241)
		(size 0.5588)
		(drill 0.3048)
		(layers "F.Cu" "B.Cu")
		(net "GND")
	)
	(via
		(at 407.597864 -378.476002)
		(size 0.7112)
		(drill 0.4064)
		(layers "F.Cu" "B.Cu")
		(net "GND")
	)
	(via
		(at 489.926122 -129.28219)
		(size 0.7112)
		(drill 0.4064)
		(layers "F.Cu" "B.Cu")
		(net "GND")
	)
	(via
		(at 200.4822 -306.5526)
		(size 0.7112)
		(drill 0.4064)
		(layers "F.Cu" "B.Cu")
		(net "GND")
	)
	(via
		(at 22.606 -271.3228)
		(size 0.5588)
		(drill 0.3048)
		(layers "F.Cu" "B.Cu")
		(net "GND")
	)
	(via
		(at 1.524 -259.483352)
		(size 0.7112)
		(drill 0.4064)
		(layers "F.Cu" "B.Cu")
		(net "GND")
	)
	(via
		(at 425.7802 -17.653)
		(size 0.5588)
		(drill 0.3048)
		(layers "F.Cu" "B.Cu")
		(net "GND")
	)
	(via
		(at 116.50599 -378.476002)
		(size 0.7112)
		(drill 0.4064)
		(layers "F.Cu" "B.Cu")
		(net "GND")
	)
	(via
		(at 299.392848 -348.633542)
		(size 0.5588)
		(drill 0.3048)
		(layers "F.Cu" "B.Cu")
		(net "GND")
	)
	(via
		(at 489.926122 -261.36219)
		(size 0.7112)
		(drill 0.4064)
		(layers "F.Cu" "B.Cu")
		(net "GND")
	)
	(via
		(at 94.866968 -334.630014)
		(size 0.5588)
		(drill 0.3048)
		(layers "F.Cu" "B.Cu")
		(net "GND")
	)
	(via
		(at 489.926122 -20.06219)
		(size 0.7112)
		(drill 0.4064)
		(layers "F.Cu" "B.Cu")
		(net "GND")
	)
	(via
		(at 79.4385 -139.954)
		(size 0.5588)
		(drill 0.3048)
		(layers "F.Cu" "B.Cu")
		(net "GND")
	)
	(via
		(at 469.9 -317.5)
		(size 0.5588)
		(drill 0.3048)
		(layers "F.Cu" "B.Cu")
		(net "GND")
	)
	(via
		(at 489.926122 -299.46219)
		(size 0.7112)
		(drill 0.4064)
		(layers "F.Cu" "B.Cu")
		(net "GND")
	)
	(via
		(at 1.524 -306.473352)
		(size 0.7112)
		(drill 0.4064)
		(layers "F.Cu" "B.Cu")
		(net "GND")
	)
	(via
		(at 151.234648 -1.524)
		(size 0.7112)
		(drill 0.4064)
		(layers "F.Cu" "B.Cu")
		(net "GND")
	)
	(via
		(at 189.369954 -384.47599)
		(size 0.7112)
		(drill 0.4064)
		(layers "F.Cu" "B.Cu")
		(net "GND")
	)
	(via
		(at 312.523886 -36.21151)
		(size 0.7112)
		(drill 0.4064)
		(layers "F.Cu" "B.Cu")
		(net "GND")
	)
	(via
		(at 383.467864 -378.476002)
		(size 0.7112)
		(drill 0.4064)
		(layers "F.Cu" "B.Cu")
		(net "GND")
	)
	(via
		(at 245.2878 -131.982718)
		(size 0.5588)
		(drill 0.3048)
		(layers "F.Cu" "B.Cu")
		(net "GND")
	)
	(via
		(at 1.524 -179.473352)
		(size 0.7112)
		(drill 0.4064)
		(layers "F.Cu" "B.Cu")
		(net "GND")
	)
	(via
		(at 489.926122 -183.89219)
		(size 0.7112)
		(drill 0.4064)
		(layers "F.Cu" "B.Cu")
		(net "GND")
	)
	(via
		(at 281.178 -336.169)
		(size 0.5588)
		(drill 0.3048)
		(layers "F.Cu" "B.Cu")
		(net "GND")
	)
	(via
		(at 489.926122 -304.54219)
		(size 0.7112)
		(drill 0.4064)
		(layers "F.Cu" "B.Cu")
		(net "GND")
	)
	(via
		(at 214.376 -286.512)
		(size 0.5588)
		(drill 0.3048)
		(layers "F.Cu" "B.Cu")
		(net "GND")
	)
	(via
		(at 239.903 -288.163)
		(size 0.5588)
		(drill 0.3048)
		(layers "F.Cu" "B.Cu")
		(net "GND")
	)
	(via
		(at 1.524 -204.873352)
		(size 0.7112)
		(drill 0.4064)
		(layers "F.Cu" "B.Cu")
		(net "GND")
	)
	(via
		(at 343.779856 -384.47599)
		(size 0.7112)
		(drill 0.4064)
		(layers "F.Cu" "B.Cu")
		(net "GND")
	)
	(via
		(at 489.926122 -145.79219)
		(size 0.7112)
		(drill 0.4064)
		(layers "F.Cu" "B.Cu")
		(net "GND")
	)
	(via
		(at 462.879186 -120.194578)
		(size 0.5588)
		(drill 0.3048)
		(layers "F.Cu" "B.Cu")
		(net "GND")
	)
	(via
		(at 1.524 -162.963352)
		(size 0.7112)
		(drill 0.4064)
		(layers "F.Cu" "B.Cu")
		(net "GND")
	)
	(via
		(at 232.13949 -356.157784)
		(size 0.5588)
		(drill 0.3048)
		(layers "F.Cu" "B.Cu")
		(net "GND")
	)
	(via
		(at 397.891 -250.317)
		(size 0.5588)
		(drill 0.3048)
		(layers "F.Cu" "B.Cu")
		(net "GND")
	)
	(via
		(at 1.524 -213.763352)
		(size 0.7112)
		(drill 0.4064)
		(layers "F.Cu" "B.Cu")
		(net "GND")
	)
	(via
		(at 390.532874 -280.785062)
		(size 0.5588)
		(drill 0.3048)
		(layers "F.Cu" "B.Cu")
		(net "GND")
	)
	(via
		(at 1.524 -215.033352)
		(size 0.7112)
		(drill 0.4064)
		(layers "F.Cu" "B.Cu")
		(net "GND")
	)
	(via
		(at 74.818494 -101.773228)
		(size 0.5588)
		(drill 0.3048)
		(layers "F.Cu" "B.Cu")
		(net "GND")
	)
	(via
		(at 407.416 -109.855)
		(size 0.5588)
		(drill 0.3048)
		(layers "F.Cu" "B.Cu")
		(net "GND")
	)
	(via
		(at 330.2 -352.552)
		(size 0.5588)
		(drill 0.3048)
		(layers "F.Cu" "B.Cu")
		(net "GND")
	)
	(via
		(at 331.1652 -132.715)
		(size 0.5588)
		(drill 0.3048)
		(layers "F.Cu" "B.Cu")
		(net "GND")
	)
	(via
		(at 184.912 -26.230072)
		(size 0.5588)
		(drill 0.3048)
		(layers "F.Cu" "B.Cu")
		(net "GND")
	)
	(via
		(at 489.926122 -229.61219)
		(size 0.7112)
		(drill 0.4064)
		(layers "F.Cu" "B.Cu")
		(net "GND")
	)
	(via
		(at 368.227864 -378.476002)
		(size 0.7112)
		(drill 0.4064)
		(layers "F.Cu" "B.Cu")
		(net "GND")
	)
	(via
		(at 22.964648 -1.524)
		(size 0.7112)
		(drill 0.4064)
		(layers "F.Cu" "B.Cu")
		(net "GND")
	)
	(via
		(at 246.837962 -378.476002)
		(size 0.7112)
		(drill 0.4064)
		(layers "F.Cu" "B.Cu")
		(net "GND")
	)
	(via
		(at 122.954796 -148.35505)
		(size 0.5588)
		(drill 0.3048)
		(layers "F.Cu" "B.Cu")
		(net "GND")
	)
	(via
		(at 22.234906 -380.775972)
		(size 0.7112)
		(drill 0.4064)
		(layers "F.Cu" "B.Cu")
		(net "GND")
	)
	(via
		(at 456.226164 -225.743516)
		(size 0.5588)
		(drill 0.3048)
		(layers "F.Cu" "B.Cu")
		(net "GND")
	)
	(via
		(at 357.205026 -246.845074)
		(size 0.5588)
		(drill 0.3048)
		(layers "F.Cu" "B.Cu")
		(net "GND")
	)
	(via
		(at 79.4385 -255.016)
		(size 0.5588)
		(drill 0.3048)
		(layers "F.Cu" "B.Cu")
		(net "GND")
	)
	(via
		(at 1.524 -6.753352)
		(size 0.7112)
		(drill 0.4064)
		(layers "F.Cu" "B.Cu")
		(net "GND")
	)
	(via
		(at 301.700692 -384.47599)
		(size 0.7112)
		(drill 0.4064)
		(layers "F.Cu" "B.Cu")
		(net "GND")
	)
	(via
		(at 272.728436 -49.724056)
		(size 0.7112)
		(drill 0.4064)
		(layers "F.Cu" "B.Cu")
		(net "GND")
	)
	(via
		(at 1.524 -297.583352)
		(size 0.7112)
		(drill 0.4064)
		(layers "F.Cu" "B.Cu")
		(net "GND")
	)
	(via
		(at 156.282898 -50.785014)
		(size 0.5588)
		(drill 0.3048)
		(layers "F.Cu" "B.Cu")
		(net "GND")
	)
	(via
		(at 482.6 -342.9)
		(size 0.5588)
		(drill 0.3048)
		(layers "F.Cu" "B.Cu")
		(net "GND")
	)
	(via
		(at 127.254 -379.476)
		(size 0.7112)
		(drill 0.4064)
		(layers "F.Cu" "B.Cu")
		(net "GND")
	)
	(via
		(at 20.616164 -225.743516)
		(size 0.5588)
		(drill 0.3048)
		(layers "F.Cu" "B.Cu")
		(net "GND")
	)
	(via
		(at 87.296752 -334.704944)
		(size 0.5588)
		(drill 0.3048)
		(layers "F.Cu" "B.Cu")
		(net "GND")
	)
	(via
		(at 197.47611 -31.482538)
		(size 0.7112)
		(drill 0.4064)
		(layers "F.Cu" "B.Cu")
		(net "GND")
	)
	(via
		(at 1.524 -80.413352)
		(size 0.7112)
		(drill 0.4064)
		(layers "F.Cu" "B.Cu")
		(net "GND")
	)
	(via
		(at 1.524 -123.593352)
		(size 0.7112)
		(drill 0.4064)
		(layers "F.Cu" "B.Cu")
		(net "GND")
	)
	(via
		(at 91.1352 -242.7986)
		(size 0.5588)
		(drill 0.3048)
		(layers "F.Cu" "B.Cu")
		(net "GND")
	)
	(via
		(at 154.504898 -30.815026)
		(size 0.5588)
		(drill 0.3048)
		(layers "F.Cu" "B.Cu")
		(net "GND")
	)
	(via
		(at 21.59 -222.885)
		(size 0.5588)
		(drill 0.3048)
		(layers "F.Cu" "B.Cu")
		(net "GND")
	)
	(via
		(at 99.99599 -378.476002)
		(size 0.7112)
		(drill 0.4064)
		(layers "F.Cu" "B.Cu")
		(net "GND")
	)
	(via
		(at 74.697844 -333.554832)
		(size 0.5588)
		(drill 0.3048)
		(layers "F.Cu" "B.Cu")
		(net "GND")
	)
	(via
		(at 18.669 -30.607)
		(size 0.5588)
		(drill 0.3048)
		(layers "F.Cu" "B.Cu")
		(net "GND")
	)
	(via
		(at 270.926052 -366.371632)
		(size 0.7112)
		(drill 0.4064)
		(layers "F.Cu" "B.Cu")
		(net "GND")
	)
	(via
		(at 447.548 -274.32)
		(size 0.5588)
		(drill 0.3048)
		(layers "F.Cu" "B.Cu")
		(net "GND")
	)
	(via
		(at 207.882236 -233.67619)
		(size 0.5588)
		(drill 0.3048)
		(layers "F.Cu" "B.Cu")
		(net "GND")
	)
	(via
		(at 324.511924 -136.430004)
		(size 0.5588)
		(drill 0.3048)
		(layers "F.Cu" "B.Cu")
		(net "GND")
	)
	(via
		(at 184.912 -256.23012)
		(size 0.5588)
		(drill 0.3048)
		(layers "F.Cu" "B.Cu")
		(net "GND")
	)
	(via
		(at 28.304998 -16.845026)
		(size 0.5588)
		(drill 0.3048)
		(layers "F.Cu" "B.Cu")
		(net "GND")
	)
	(via
		(at 449.773802 -225.30435)
		(size 0.5588)
		(drill 0.3048)
		(layers "F.Cu" "B.Cu")
		(net "GND")
	)
	(via
		(at 317.246 -382.143)
		(size 0.7112)
		(drill 0.4064)
		(layers "F.Cu" "B.Cu")
		(net "GND")
	)
	(via
		(at 1.524 -82.953352)
		(size 0.7112)
		(drill 0.4064)
		(layers "F.Cu" "B.Cu")
		(net "GND")
	)
	(via
		(at 427.717204 -369.2525)
		(size 0.5588)
		(drill 0.3048)
		(layers "F.Cu" "B.Cu")
		(net "GND")
	)
	(via
		(at 392.938 -47.117)
		(size 0.5588)
		(drill 0.3048)
		(layers "F.Cu" "B.Cu")
		(net "GND")
	)
	(via
		(at 343.549478 -101.49713)
		(size 0.5588)
		(drill 0.3048)
		(layers "F.Cu" "B.Cu")
		(net "GND")
	)
	(via
		(at 276.606 -55.245)
		(size 0.5588)
		(drill 0.3048)
		(layers "F.Cu" "B.Cu")
		(net "GND")
	)
	(via
		(at 451.739 -233.045)
		(size 0.5588)
		(drill 0.3048)
		(layers "F.Cu" "B.Cu")
		(net "GND")
	)
	(via
		(at 282.650692 -384.47599)
		(size 0.7112)
		(drill 0.4064)
		(layers "F.Cu" "B.Cu")
		(net "GND")
	)
	(via
		(at 489.926122 -91.18219)
		(size 0.7112)
		(drill 0.4064)
		(layers "F.Cu" "B.Cu")
		(net "GND")
	)
	(via
		(at 95.19412 -361.340146)
		(size 0.7112)
		(drill 0.4064)
		(layers "F.Cu" "B.Cu")
		(net "GND")
	)
	(via
		(at 489.926122 -327.40219)
		(size 0.7112)
		(drill 0.4064)
		(layers "F.Cu" "B.Cu")
		(net "GND")
	)
	(via
		(at 474.853 -381.889)
		(size 0.7112)
		(drill 0.4064)
		(layers "F.Cu" "B.Cu")
		(net "GND")
	)
	(via
		(at 222.123 -196.723)
		(size 0.5588)
		(drill 0.3048)
		(layers "F.Cu" "B.Cu")
		(net "GND")
	)
	(via
		(at 489.926122 -294.38219)
		(size 0.7112)
		(drill 0.4064)
		(layers "F.Cu" "B.Cu")
		(net "GND")
	)
	(via
		(at 388.754874 -16.845026)
		(size 0.5588)
		(drill 0.3048)
		(layers "F.Cu" "B.Cu")
		(net "GND")
	)
	(via
		(at 63.5 -292.1)
		(size 0.5588)
		(drill 0.3048)
		(layers "F.Cu" "B.Cu")
		(net "GND")
	)
	(via
		(at 1.524 -345.843352)
		(size 0.7112)
		(drill 0.4064)
		(layers "F.Cu" "B.Cu")
		(net "GND")
	)
	(via
		(at 1.524 -42.313352)
		(size 0.7112)
		(drill 0.4064)
		(layers "F.Cu" "B.Cu")
		(net "GND")
	)
	(via
		(at 107.188 -35.687)
		(size 0.5588)
		(drill 0.3048)
		(layers "F.Cu" "B.Cu")
		(net "GND")
	)
	(via
		(at 451.854824 -246.845074)
		(size 0.5588)
		(drill 0.3048)
		(layers "F.Cu" "B.Cu")
		(net "GND")
	)
	(via
		(at 174.094648 -1.524)
		(size 0.7112)
		(drill 0.4064)
		(layers "F.Cu" "B.Cu")
		(net "GND")
	)
	(via
		(at 154.504898 -268.435074)
		(size 0.5588)
		(drill 0.3048)
		(layers "F.Cu" "B.Cu")
		(net "GND")
	)
	(via
		(at 81.788 -30.607)
		(size 0.5588)
		(drill 0.3048)
		(layers "F.Cu" "B.Cu")
		(net "GND")
	)
	(via
		(at 96.71812 -359.816146)
		(size 0.7112)
		(drill 0.4064)
		(layers "F.Cu" "B.Cu")
		(net "GND")
	)
	(via
		(at 309.824882 -380.775972)
		(size 0.7112)
		(drill 0.4064)
		(layers "F.Cu" "B.Cu")
		(net "GND")
	)
	(via
		(at 489.926122 -177.54219)
		(size 0.7112)
		(drill 0.4064)
		(layers "F.Cu" "B.Cu")
		(net "GND")
	)
	(via
		(at 325.654924 -268.435074)
		(size 0.5588)
		(drill 0.3048)
		(layers "F.Cu" "B.Cu")
		(net "GND")
	)
	(via
		(at 1.524 -24.533352)
		(size 0.7112)
		(drill 0.4064)
		(layers "F.Cu" "B.Cu")
		(net "GND")
	)
	(via
		(at 40.0304 -6.223)
		(size 0.5588)
		(drill 0.3048)
		(layers "F.Cu" "B.Cu")
		(net "GND")
	)
	(via
		(at 420.304976 -153.43505)
		(size 0.5588)
		(drill 0.3048)
		(layers "F.Cu" "B.Cu")
		(net "GND")
	)
	(via
		(at 472.3384 -243.9035)
		(size 0.5588)
		(drill 0.3048)
		(layers "F.Cu" "B.Cu")
		(net "GND")
	)
	(via
		(at 365.687864 -378.476002)
		(size 0.7112)
		(drill 0.4064)
		(layers "F.Cu" "B.Cu")
		(net "GND")
	)
	(via
		(at 324.739 -79.502)
		(size 0.5588)
		(drill 0.3048)
		(layers "F.Cu" "B.Cu")
		(net "GND")
	)
	(via
		(at 284.448758 -102.431088)
		(size 0.7112)
		(drill 0.4064)
		(layers "F.Cu" "B.Cu")
		(net "GND")
	)
	(via
		(at 278.274018 -366.028478)
		(size 0.7112)
		(drill 0.4064)
		(layers "F.Cu" "B.Cu")
		(net "GND")
	)
	(via
		(at 75.86599 -378.476002)
		(size 0.7112)
		(drill 0.4064)
		(layers "F.Cu" "B.Cu")
		(net "GND")
	)
	(via
		(at 71.882 -378.968)
		(size 0.7112)
		(drill 0.4064)
		(layers "F.Cu" "B.Cu")
		(net "GND")
	)
	(via
		(at 287.909 -306.451)
		(size 0.7112)
		(drill 0.4064)
		(layers "F.Cu" "B.Cu")
		(net "GND")
	)
	(via
		(at 1.524 -241.703352)
		(size 0.7112)
		(drill 0.4064)
		(layers "F.Cu" "B.Cu")
		(net "GND")
	)
	(via
		(at 207.813148 -208.02727)
		(size 0.5588)
		(drill 0.3048)
		(layers "F.Cu" "B.Cu")
		(net "GND")
	)
	(via
		(at 1.524 -75.333352)
		(size 0.7112)
		(drill 0.4064)
		(layers "F.Cu" "B.Cu")
		(net "GND")
	)
	(via
		(at 242.062 -305.7144)
		(size 0.5588)
		(drill 0.3048)
		(layers "F.Cu" "B.Cu")
		(net "GND")
	)
	(via
		(at 91.404948 -263.355074)
		(size 0.5588)
		(drill 0.3048)
		(layers "F.Cu" "B.Cu")
		(net "GND")
	)
	(via
		(at 489.926122 -161.03219)
		(size 0.7112)
		(drill 0.4064)
		(layers "F.Cu" "B.Cu")
		(net "GND")
	)
	(via
		(at 429.3108 -238.1758)
		(size 0.5588)
		(drill 0.3048)
		(layers "F.Cu" "B.Cu")
		(net "GND")
	)
	(via
		(at 12.021566 -227.406708)
		(size 0.6096)
		(drill 0.3048)
		(layers "F.Cu" "B.Cu")
		(net "GND")
	)
	(via
		(at 477.647 -156.2608)
		(size 0.5588)
		(drill 0.3048)
		(layers "F.Cu" "B.Cu")
		(net "GND")
	)
	(via
		(at 483.404926 -270.975074)
		(size 0.5588)
		(drill 0.3048)
		(layers "F.Cu" "B.Cu")
		(net "GND")
	)
	(via
		(at 1.524 -250.593352)
		(size 0.7112)
		(drill 0.4064)
		(layers "F.Cu" "B.Cu")
		(net "GND")
	)
	(via
		(at 447.04 -214.884)
		(size 0.5588)
		(drill 0.3048)
		(layers "F.Cu" "B.Cu")
		(net "GND")
	)
	(via
		(at 24.257 -162.179)
		(size 0.5588)
		(drill 0.3048)
		(layers "F.Cu" "B.Cu")
		(net "GND")
	)
	(via
		(at 393.7 -330.2)
		(size 0.5588)
		(drill 0.3048)
		(layers "F.Cu" "B.Cu")
		(net "GND")
	)
	(via
		(at 91.10599 -378.476002)
		(size 0.7112)
		(drill 0.4064)
		(layers "F.Cu" "B.Cu")
		(net "GND")
	)
	(via
		(at 222.8596 -302.6918)
		(size 0.5588)
		(drill 0.3048)
		(layers "F.Cu" "B.Cu")
		(net "GND")
	)
	(via
		(at 138.413998 -384.47599)
		(size 0.7112)
		(drill 0.4064)
		(layers "F.Cu" "B.Cu")
		(net "GND")
	)
	(via
		(at 66.144648 -1.524)
		(size 0.7112)
		(drill 0.4064)
		(layers "F.Cu" "B.Cu")
		(net "GND")
	)
	(via
		(at 79.676752 -337.244944)
		(size 0.5588)
		(drill 0.3048)
		(layers "F.Cu" "B.Cu")
		(net "GND")
	)
	(via
		(at 162.052 -123.952)
		(size 0.5588)
		(drill 0.3048)
		(layers "F.Cu" "B.Cu")
		(net "GND")
	)
	(via
		(at 76.58735 -101.8286)
		(size 0.5588)
		(drill 0.3048)
		(layers "F.Cu" "B.Cu")
		(net "GND")
	)
	(via
		(at 489.926122 -172.46219)
		(size 0.7112)
		(drill 0.4064)
		(layers "F.Cu" "B.Cu")
		(net "GND")
	)
	(via
		(at 299.398436 -49.724056)
		(size 0.7112)
		(drill 0.4064)
		(layers "F.Cu" "B.Cu")
		(net "GND")
	)
	(via
		(at 451.095872 -384.47599)
		(size 0.7112)
		(drill 0.4064)
		(layers "F.Cu" "B.Cu")
		(net "GND")
	)
	(via
		(at 478.469198 -217.28303)
		(size 0.5588)
		(drill 0.3048)
		(layers "F.Cu" "B.Cu")
		(net "GND")
	)
	(via
		(at 79.67599 -378.476002)
		(size 0.7112)
		(drill 0.4064)
		(layers "F.Cu" "B.Cu")
		(net "GND")
	)
	(via
		(at 1.524 -195.983352)
		(size 0.7112)
		(drill 0.4064)
		(layers "F.Cu" "B.Cu")
		(net "GND")
	)
	(via
		(at 184.912 -136.430004)
		(size 0.5588)
		(drill 0.3048)
		(layers "F.Cu" "B.Cu")
		(net "GND")
	)
	(via
		(at 34.671 -282.321)
		(size 0.5588)
		(drill 0.3048)
		(layers "F.Cu" "B.Cu")
		(net "GND")
	)
	(via
		(at 39.795196 -364.51159)
		(size 0.5588)
		(drill 0.3048)
		(layers "F.Cu" "B.Cu")
		(net "GND")
	)
	(via
		(at 489.926122 -42.92219)
		(size 0.7112)
		(drill 0.4064)
		(layers "F.Cu" "B.Cu")
		(net "GND")
	)
	(via
		(at 387.611874 -141.230096)
		(size 0.5588)
		(drill 0.3048)
		(layers "F.Cu" "B.Cu")
		(net "GND")
	)
	(via
		(at 471.3605 -255.016)
		(size 0.5588)
		(drill 0.3048)
		(layers "F.Cu" "B.Cu")
		(net "GND")
	)
	(via
		(at 333.502 -277.114)
		(size 0.5588)
		(drill 0.3048)
		(layers "F.Cu" "B.Cu")
		(net "GND")
	)
	(via
		(at 36.177982 -384.47599)
		(size 0.7112)
		(drill 0.4064)
		(layers "F.Cu" "B.Cu")
		(net "GND")
	)
	(via
		(at 197.871588 -48.454056)
		(size 0.7112)
		(drill 0.4064)
		(layers "F.Cu" "B.Cu")
		(net "GND")
	)
	(via
		(at 22.0218 -135.4328)
		(size 0.5588)
		(drill 0.3048)
		(layers "F.Cu" "B.Cu")
		(net "GND")
	)
	(via
		(at 489.926122 -286.76219)
		(size 0.7112)
		(drill 0.4064)
		(layers "F.Cu" "B.Cu")
		(net "GND")
	)
	(via
		(at 1.524 -335.683352)
		(size 0.7112)
		(drill 0.4064)
		(layers "F.Cu" "B.Cu")
		(net "GND")
	)
	(via
		(at 353.314 -260.2992)
		(size 0.5588)
		(drill 0.3048)
		(layers "F.Cu" "B.Cu")
		(net "GND")
	)
	(via
		(at 18.4912 -148.717)
		(size 0.5588)
		(drill 0.3048)
		(layers "F.Cu" "B.Cu")
		(net "GND")
	)
	(via
		(at 1.524 -185.823352)
		(size 0.7112)
		(drill 0.4064)
		(layers "F.Cu" "B.Cu")
		(net "GND")
	)
	(via
		(at 195.961 -63.754)
		(size 0.5588)
		(drill 0.3048)
		(layers "F.Cu" "B.Cu")
		(net "GND")
	)
	(via
		(at 467.487 -60.325)
		(size 0.5588)
		(drill 0.3048)
		(layers "F.Cu" "B.Cu")
		(net "GND")
	)
	(via
		(at 312.523886 -14.62151)
		(size 0.7112)
		(drill 0.4064)
		(layers "F.Cu" "B.Cu")
		(net "GND")
	)
	(via
		(at 489.926122 -147.06219)
		(size 0.7112)
		(drill 0.4064)
		(layers "F.Cu" "B.Cu")
		(net "GND")
	)
	(via
		(at 278.274018 -363.488478)
		(size 0.7112)
		(drill 0.4064)
		(layers "F.Cu" "B.Cu")
		(net "GND")
	)
	(via
		(at 409.916376 -1.524)
		(size 0.7112)
		(drill 0.4064)
		(layers "F.Cu" "B.Cu")
		(net "GND")
	)
	(via
		(at 444.745872 -384.47599)
		(size 0.7112)
		(drill 0.4064)
		(layers "F.Cu" "B.Cu")
		(net "GND")
	)
	(via
		(at 91.404948 -40.975026)
		(size 0.5588)
		(drill 0.3048)
		(layers "F.Cu" "B.Cu")
		(net "GND")
	)
	(via
		(at 215.087962 -378.476002)
		(size 0.7112)
		(drill 0.4064)
		(layers "F.Cu" "B.Cu")
		(net "GND")
	)
	(via
		(at 58.711846 -141.230096)
		(size 0.5588)
		(drill 0.3048)
		(layers "F.Cu" "B.Cu")
		(net "GND")
	)
	(via
		(at 1.524 -108.353352)
		(size 0.7112)
		(drill 0.4064)
		(layers "F.Cu" "B.Cu")
		(net "GND")
	)
	(via
		(at 387.611874 -251.430028)
		(size 0.5588)
		(drill 0.3048)
		(layers "F.Cu" "B.Cu")
		(net "GND")
	)
	(via
		(at 44.196 -265.684)
		(size 0.5588)
		(drill 0.3048)
		(layers "F.Cu" "B.Cu")
		(net "GND")
	)
	(via
		(at 90.261948 -26.230072)
		(size 0.5588)
		(drill 0.3048)
		(layers "F.Cu" "B.Cu")
		(net "GND")
	)
	(via
		(at 379.657864 -378.476002)
		(size 0.7112)
		(drill 0.4064)
		(layers "F.Cu" "B.Cu")
		(net "GND")
	)
	(via
		(at 311.094882 -380.775972)
		(size 0.7112)
		(drill 0.4064)
		(layers "F.Cu" "B.Cu")
		(net "GND")
	)
	(via
		(at 489.926122 -342.64219)
		(size 0.7112)
		(drill 0.4064)
		(layers "F.Cu" "B.Cu")
		(net "GND")
	)
	(via
		(at 95.017844 -333.554832)
		(size 0.5588)
		(drill 0.3048)
		(layers "F.Cu" "B.Cu")
		(net "GND")
	)
	(via
		(at 362.966 -47.117)
		(size 0.5588)
		(drill 0.3048)
		(layers "F.Cu" "B.Cu")
		(net "GND")
	)
	(via
		(at 486.925874 -383.320036)
		(size 0.7112)
		(drill 0.4064)
		(layers "F.Cu" "B.Cu")
		(net "GND")
	)
	(via
		(at 374.019318 -101.814376)
		(size 0.5588)
		(drill 0.3048)
		(layers "F.Cu" "B.Cu")
		(net "GND")
	)
	(via
		(at 122.954796 -33.355026)
		(size 0.5588)
		(drill 0.3048)
		(layers "F.Cu" "B.Cu")
		(net "GND")
	)
	(via
		(at 489.926122 -111.50219)
		(size 0.7112)
		(drill 0.4064)
		(layers "F.Cu" "B.Cu")
		(net "GND")
	)
	(via
		(at 430.236376 -1.524)
		(size 0.7112)
		(drill 0.4064)
		(layers "F.Cu" "B.Cu")
		(net "GND")
	)
	(via
		(at 390.866376 -1.524)
		(size 0.7112)
		(drill 0.4064)
		(layers "F.Cu" "B.Cu")
		(net "GND")
	)
	(via
		(at 489.926122 -300.73219)
		(size 0.7112)
		(drill 0.4064)
		(layers "F.Cu" "B.Cu")
		(net "GND")
	)
	(via
		(at 405.56942 -101.814376)
		(size 0.5588)
		(drill 0.3048)
		(layers "F.Cu" "B.Cu")
		(net "GND")
	)
	(via
		(at 451.854824 -13.035026)
		(size 0.5588)
		(drill 0.3048)
		(layers "F.Cu" "B.Cu")
		(net "GND")
	)
	(via
		(at 67.758056 -106.047286)
		(size 0.5588)
		(drill 0.3048)
		(layers "F.Cu" "B.Cu")
		(net "GND")
	)
	(via
		(at 186.055 -250.655074)
		(size 0.5588)
		(drill 0.3048)
		(layers "F.Cu" "B.Cu")
		(net "GND")
	)
	(via
		(at 153.361898 -138.83005)
		(size 0.5588)
		(drill 0.3048)
		(layers "F.Cu" "B.Cu")
		(net "GND")
	)
	(via
		(at 356.062026 -253.830074)
		(size 0.5588)
		(drill 0.3048)
		(layers "F.Cu" "B.Cu")
		(net "GND")
	)
	(via
		(at 34.907982 -384.47599)
		(size 0.7112)
		(drill 0.4064)
		(layers "F.Cu" "B.Cu")
		(net "GND")
	)
	(via
		(at 416.179 -79.121)
		(size 0.5588)
		(drill 0.3048)
		(layers "F.Cu" "B.Cu")
		(net "GND")
	)
	(via
		(at 89.937844 -333.554832)
		(size 0.5588)
		(drill 0.3048)
		(layers "F.Cu" "B.Cu")
		(net "GND")
	)
	(via
		(at 55.984648 -1.524)
		(size 0.7112)
		(drill 0.4064)
		(layers "F.Cu" "B.Cu")
		(net "GND")
	)
	(via
		(at 176.3268 -148.717)
		(size 0.5588)
		(drill 0.3048)
		(layers "F.Cu" "B.Cu")
		(net "GND")
	)
	(via
		(at 197.47611 -40.372538)
		(size 0.7112)
		(drill 0.4064)
		(layers "F.Cu" "B.Cu")
		(net "GND")
	)
	(via
		(at 489.926122 -266.44219)
		(size 0.7112)
		(drill 0.4064)
		(layers "F.Cu" "B.Cu")
		(net "GND")
	)
	(via
		(at 39.284402 -233.78795)
		(size 0.5588)
		(drill 0.3048)
		(layers "F.Cu" "B.Cu")
		(net "GND")
	)
	(via
		(at 334.90916 -361.780074)
		(size 0.5588)
		(drill 0.3048)
		(layers "F.Cu" "B.Cu")
		(net "GND")
	)
	(via
		(at 133.333998 -384.47599)
		(size 0.7112)
		(drill 0.4064)
		(layers "F.Cu" "B.Cu")
		(net "GND")
	)
	(via
		(at 312.166 -48.133)
		(size 0.7112)
		(drill 0.4064)
		(layers "F.Cu" "B.Cu")
		(net "GND")
	)
	(via
		(at 419.1 -342.9)
		(size 0.5588)
		(drill 0.3048)
		(layers "F.Cu" "B.Cu")
		(net "GND")
	)
	(via
		(at 483.404926 -20.655026)
		(size 0.5588)
		(drill 0.3048)
		(layers "F.Cu" "B.Cu")
		(net "GND")
	)
	(via
		(at 105.547668 -96.248728)
		(size 0.5588)
		(drill 0.3048)
		(layers "F.Cu" "B.Cu")
		(net "GND")
	)
	(via
		(at 186.055 -128.03505)
		(size 0.5588)
		(drill 0.3048)
		(layers "F.Cu" "B.Cu")
		(net "GND")
	)
	(via
		(at 143.614648 -1.524)
		(size 0.7112)
		(drill 0.4064)
		(layers "F.Cu" "B.Cu")
		(net "GND")
	)
	(via
		(at 368.3 -368.3)
		(size 0.5588)
		(drill 0.3048)
		(layers "F.Cu" "B.Cu")
		(net "GND")
	)
	(via
		(at 374.356376 -1.524)
		(size 0.7112)
		(drill 0.4064)
		(layers "F.Cu" "B.Cu")
		(net "GND")
	)
	(via
		(at 12.7 -355.6)
		(size 0.5588)
		(drill 0.3048)
		(layers "F.Cu" "B.Cu")
		(net "GND")
	)
	(via
		(at 22.606 -223.901)
		(size 0.5588)
		(drill 0.3048)
		(layers "F.Cu" "B.Cu")
		(net "GND")
	)
	(via
		(at 461.772 -166.624)
		(size 0.5588)
		(drill 0.3048)
		(layers "F.Cu" "B.Cu")
		(net "GND")
	)
	(via
		(at 362.331 -38.608)
		(size 0.5588)
		(drill 0.3048)
		(layers "F.Cu" "B.Cu")
		(net "GND")
	)
	(via
		(at 23.4315 -20.447)
		(size 0.5588)
		(drill 0.3048)
		(layers "F.Cu" "B.Cu")
		(net "GND")
	)
	(via
		(at 489.926122 -206.75219)
		(size 0.7112)
		(drill 0.4064)
		(layers "F.Cu" "B.Cu")
		(net "GND")
	)
	(via
		(at 351.536 -164.084)
		(size 0.5588)
		(drill 0.3048)
		(layers "F.Cu" "B.Cu")
		(net "GND")
	)
	(via
		(at 65.024 -36.068)
		(size 0.5588)
		(drill 0.3048)
		(layers "F.Cu" "B.Cu")
		(net "GND")
	)
	(via
		(at 48.092868 -96.248728)
		(size 0.5588)
		(drill 0.3048)
		(layers "F.Cu" "B.Cu")
		(net "GND")
	)
	(via
		(at 60.775596 -363.1184)
		(size 0.7112)
		(drill 0.4064)
		(layers "F.Cu" "B.Cu")
		(net "GND")
	)
	(via
		(at 83.48599 -378.476002)
		(size 0.7112)
		(drill 0.4064)
		(layers "F.Cu" "B.Cu")
		(net "GND")
	)
	(via
		(at 117.348 -41.3258)
		(size 0.5588)
		(drill 0.3048)
		(layers "F.Cu" "B.Cu")
		(net "GND")
	)
	(via
		(at 138.811 -35.687)
		(size 0.5588)
		(drill 0.3048)
		(layers "F.Cu" "B.Cu")
		(net "GND")
	)
	(via
		(at 322.58 -220.472)
		(size 0.5588)
		(drill 0.3048)
		(layers "F.Cu" "B.Cu")
		(net "GND")
	)
	(via
		(at 455.93 -162.179)
		(size 0.5588)
		(drill 0.3048)
		(layers "F.Cu" "B.Cu")
		(net "GND")
	)
	(via
		(at 1.524 -71.523352)
		(size 0.7112)
		(drill 0.4064)
		(layers "F.Cu" "B.Cu")
		(net "GND")
	)
	(via
		(at 122.954796 -131.84505)
		(size 0.5588)
		(drill 0.3048)
		(layers "F.Cu" "B.Cu")
		(net "GND")
	)
	(via
		(at 354.076 -63.246)
		(size 0.5588)
		(drill 0.3048)
		(layers "F.Cu" "B.Cu")
		(net "GND")
	)
	(via
		(at 1.524 -182.013352)
		(size 0.7112)
		(drill 0.4064)
		(layers "F.Cu" "B.Cu")
		(net "GND")
	)
	(via
		(at 341.884 -45.466)
		(size 0.5588)
		(drill 0.3048)
		(layers "F.Cu" "B.Cu")
		(net "GND")
	)
	(via
		(at 220.167962 -378.476002)
		(size 0.7112)
		(drill 0.4064)
		(layers "F.Cu" "B.Cu")
		(net "GND")
	)
	(via
		(at 329.906376 -1.524)
		(size 0.7112)
		(drill 0.4064)
		(layers "F.Cu" "B.Cu")
		(net "GND")
	)
	(via
		(at 487.68 -370.332)
		(size 0.7112)
		(drill 0.4064)
		(layers "F.Cu" "B.Cu")
		(net "GND")
	)
	(via
		(at 55.88 -277.241)
		(size 0.5588)
		(drill 0.3048)
		(layers "F.Cu" "B.Cu")
		(net "GND")
	)
	(via
		(at 483.404926 -155.97505)
		(size 0.5588)
		(drill 0.3048)
		(layers "F.Cu" "B.Cu")
		(net "GND")
	)
	(via
		(at 483.404926 -250.655074)
		(size 0.5588)
		(drill 0.3048)
		(layers "F.Cu" "B.Cu")
		(net "GND")
	)
	(via
		(at 19.304 -163.068)
		(size 0.5588)
		(drill 0.3048)
		(layers "F.Cu" "B.Cu")
		(net "GND")
	)
	(via
		(at 1.524 -292.503352)
		(size 0.7112)
		(drill 0.4064)
		(layers "F.Cu" "B.Cu")
		(net "GND")
	)
	(via
		(at 135.636 -271.272)
		(size 0.5588)
		(drill 0.3048)
		(layers "F.Cu" "B.Cu")
		(net "GND")
	)
	(via
		(at 288.911284 -217.094562)
		(size 0.6604)
		(drill 0.3556)
		(layers "F.Cu" "B.Cu")
		(net "GND")
	)
	(via
		(at 28.304998 -38.435026)
		(size 0.5588)
		(drill 0.3048)
		(layers "F.Cu" "B.Cu")
		(net "GND")
	)
	(via
		(at 304.8 -76.2)
		(size 0.5588)
		(drill 0.3048)
		(layers "F.Cu" "B.Cu")
		(net "GND")
	)
	(via
		(at 286.032448 -346.271342)
		(size 0.5588)
		(drill 0.3048)
		(layers "F.Cu" "B.Cu")
		(net "GND")
	)
	(via
		(at 90.261948 -23.830026)
		(size 0.5588)
		(drill 0.3048)
		(layers "F.Cu" "B.Cu")
		(net "GND")
	)
	(via
		(at 256.4384 -216.167716)
		(size 0.5588)
		(drill 0.3048)
		(layers "F.Cu" "B.Cu")
		(net "GND")
	)
	(via
		(at 288.911284 -231.494584)
		(size 0.6604)
		(drill 0.3556)
		(layers "F.Cu" "B.Cu")
		(net "GND")
	)
	(via
		(at 91.404948 -33.355026)
		(size 0.5588)
		(drill 0.3048)
		(layers "F.Cu" "B.Cu")
		(net "GND")
	)
	(via
		(at 325.654924 -250.655074)
		(size 0.5588)
		(drill 0.3048)
		(layers "F.Cu" "B.Cu")
		(net "GND")
	)
	(via
		(at 476.16364 -234.987592)
		(size 0.5588)
		(drill 0.3048)
		(layers "F.Cu" "B.Cu")
		(net "GND")
	)
	(via
		(at 87.296752 -343.594944)
		(size 0.5588)
		(drill 0.3048)
		(layers "F.Cu" "B.Cu")
		(net "GND")
	)
	(via
		(at 436.372 -238.252)
		(size 0.5588)
		(drill 0.3048)
		(layers "F.Cu" "B.Cu")
		(net "GND")
	)
	(via
		(at 178.435 -256.667)
		(size 0.5588)
		(drill 0.3048)
		(layers "F.Cu" "B.Cu")
		(net "GND")
	)
	(via
		(at 270.52397 -52.55133)
		(size 0.7112)
		(drill 0.4064)
		(layers "F.Cu" "B.Cu")
		(net "GND")
	)
	(via
		(at 1.524 -104.543352)
		(size 0.7112)
		(drill 0.4064)
		(layers "F.Cu" "B.Cu")
		(net "GND")
	)
	(via
		(at 95.062294 -145.532602)
		(size 0.5588)
		(drill 0.3048)
		(layers "F.Cu" "B.Cu")
		(net "GND")
	)
	(via
		(at 376.936 -40.132)
		(size 0.5588)
		(drill 0.3048)
		(layers "F.Cu" "B.Cu")
		(net "GND")
	)
	(via
		(at 290.270692 -384.47599)
		(size 0.7112)
		(drill 0.4064)
		(layers "F.Cu" "B.Cu")
		(net "GND")
	)
	(via
		(at 1.524 -321.713352)
		(size 0.7112)
		(drill 0.4064)
		(layers "F.Cu" "B.Cu")
		(net "GND")
	)
	(via
		(at 147.066 -26.67)
		(size 0.5588)
		(drill 0.3048)
		(layers "F.Cu" "B.Cu")
		(net "GND")
	)
	(via
		(at 50.165 -30.607)
		(size 0.5588)
		(drill 0.3048)
		(layers "F.Cu" "B.Cu")
		(net "GND")
	)
	(via
		(at 270.52397 -57.63133)
		(size 0.7112)
		(drill 0.4064)
		(layers "F.Cu" "B.Cu")
		(net "GND")
	)
	(via
		(at 75.967844 -333.554832)
		(size 0.5588)
		(drill 0.3048)
		(layers "F.Cu" "B.Cu")
		(net "GND")
	)
	(via
		(at 127 -203.2)
		(size 0.5588)
		(drill 0.3048)
		(layers "F.Cu" "B.Cu")
		(net "GND")
	)
	(via
		(at 325.654924 -145.81505)
		(size 0.5588)
		(drill 0.3048)
		(layers "F.Cu" "B.Cu")
		(net "GND")
	)
	(via
		(at 368.006376 -1.524)
		(size 0.7112)
		(drill 0.4064)
		(layers "F.Cu" "B.Cu")
		(net "GND")
	)
	(via
		(at 47.991014 -119.90197)
		(size 0.5588)
		(drill 0.3048)
		(layers "F.Cu" "B.Cu")
		(net "GND")
	)
	(via
		(at 388.754874 -131.84505)
		(size 0.5588)
		(drill 0.3048)
		(layers "F.Cu" "B.Cu")
		(net "GND")
	)
	(via
		(at 345.146376 -1.524)
		(size 0.7112)
		(drill 0.4064)
		(layers "F.Cu" "B.Cu")
		(net "GND")
	)
	(via
		(at 1.524 -86.763352)
		(size 0.7112)
		(drill 0.4064)
		(layers "F.Cu" "B.Cu")
		(net "GND")
	)
	(via
		(at 456.039982 -106.915458)
		(size 0.5588)
		(drill 0.3048)
		(layers "F.Cu" "B.Cu")
		(net "GND")
	)
	(via
		(at 477.647 -271.3228)
		(size 0.5588)
		(drill 0.3048)
		(layers "F.Cu" "B.Cu")
		(net "GND")
	)
	(via
		(at 288.911284 -206.294482)
		(size 0.6604)
		(drill 0.3556)
		(layers "F.Cu" "B.Cu")
		(net "GND")
	)
	(via
		(at 96.71812 -362.864146)
		(size 0.7112)
		(drill 0.4064)
		(layers "F.Cu" "B.Cu")
		(net "GND")
	)
	(via
		(at 148.2598 -20.4978)
		(size 0.5588)
		(drill 0.3048)
		(layers "F.Cu" "B.Cu")
		(net "GND")
	)
	(via
		(at 489.926122 -302.00219)
		(size 0.7112)
		(drill 0.4064)
		(layers "F.Cu" "B.Cu")
		(net "GND")
	)
	(via
		(at 165.083998 -384.47599)
		(size 0.7112)
		(drill 0.4064)
		(layers "F.Cu" "B.Cu")
		(net "GND")
	)
	(via
		(at 40.023796 -369.189)
		(size 0.5588)
		(drill 0.3048)
		(layers "F.Cu" "B.Cu")
		(net "GND")
	)
	(via
		(at 138.176 -40.64)
		(size 0.5588)
		(drill 0.3048)
		(layers "F.Cu" "B.Cu")
		(net "GND")
	)
	(via
		(at 334.645 -110.617)
		(size 0.5588)
		(drill 0.3048)
		(layers "F.Cu" "B.Cu")
		(net "GND")
	)
	(via
		(at 144.7546 -33.782)
		(size 0.5588)
		(drill 0.3048)
		(layers "F.Cu" "B.Cu")
		(net "GND")
	)
	(via
		(at 1.524 -221.383352)
		(size 0.7112)
		(drill 0.4064)
		(layers "F.Cu" "B.Cu")
		(net "GND")
	)
	(via
		(at 186.055 -135.65505)
		(size 0.5588)
		(drill 0.3048)
		(layers "F.Cu" "B.Cu")
		(net "GND")
	)
	(via
		(at 218.214702 -326.131682)
		(size 0.5588)
		(drill 0.3048)
		(layers "F.Cu" "B.Cu")
		(net "GND")
	)
	(via
		(at 37.447982 -384.47599)
		(size 0.7112)
		(drill 0.4064)
		(layers "F.Cu" "B.Cu")
		(net "GND")
	)
	(via
		(at 1.524 -362.353352)
		(size 0.7112)
		(drill 0.4064)
		(layers "F.Cu" "B.Cu")
		(net "GND")
	)
	(via
		(at 474.843602 -232.92435)
		(size 0.5588)
		(drill 0.3048)
		(layers "F.Cu" "B.Cu")
		(net "GND")
	)
	(via
		(at 439.665872 -384.47599)
		(size 0.7112)
		(drill 0.4064)
		(layers "F.Cu" "B.Cu")
		(net "GND")
	)
	(via
		(at 388.754874 -260.815074)
		(size 0.5588)
		(drill 0.3048)
		(layers "F.Cu" "B.Cu")
		(net "GND")
	)
	(via
		(at 489.926122 -139.44219)
		(size 0.7112)
		(drill 0.4064)
		(layers "F.Cu" "B.Cu")
		(net "GND")
	)
	(via
		(at 486.925874 -382.050036)
		(size 0.7112)
		(drill 0.4064)
		(layers "F.Cu" "B.Cu")
		(net "GND")
	)
	(via
		(at 1.524 -4.213352)
		(size 0.7112)
		(drill 0.4064)
		(layers "F.Cu" "B.Cu")
		(net "GND")
	)
	(via
		(at 1.524 -279.803352)
		(size 0.7112)
		(drill 0.4064)
		(layers "F.Cu" "B.Cu")
		(net "GND")
	)
	(via
		(at 325.999856 -384.47599)
		(size 0.7112)
		(drill 0.4064)
		(layers "F.Cu" "B.Cu")
		(net "GND")
	)
	(via
		(at 431.8 -292.1)
		(size 0.5588)
		(drill 0.3048)
		(layers "F.Cu" "B.Cu")
		(net "GND")
	)
	(via
		(at 276.538436 -49.724056)
		(size 0.7112)
		(drill 0.4064)
		(layers "F.Cu" "B.Cu")
		(net "GND")
	)
	(via
		(at 361.315 -277.114)
		(size 0.5588)
		(drill 0.3048)
		(layers "F.Cu" "B.Cu")
		(net "GND")
	)
	(via
		(at 483.404926 -246.845074)
		(size 0.5588)
		(drill 0.3048)
		(layers "F.Cu" "B.Cu")
		(net "GND")
	)
	(via
		(at 353.695 -43.942)
		(size 0.5588)
		(drill 0.3048)
		(layers "F.Cu" "B.Cu")
		(net "GND")
	)
	(via
		(at 186.748928 -365.590836)
		(size 0.5588)
		(drill 0.3048)
		(layers "F.Cu" "B.Cu")
		(net "GND")
	)
	(via
		(at 460.1718 -15.1257)
		(size 0.5588)
		(drill 0.3048)
		(layers "F.Cu" "B.Cu")
		(net "GND")
	)
	(via
		(at 483.404926 -145.81505)
		(size 0.5588)
		(drill 0.3048)
		(layers "F.Cu" "B.Cu")
		(net "GND")
	)
	(via
		(at 47.9425 -255.016)
		(size 0.5588)
		(drill 0.3048)
		(layers "F.Cu" "B.Cu")
		(net "GND")
	)
	(via
		(at 427.228 -52.324)
		(size 0.5588)
		(drill 0.3048)
		(layers "F.Cu" "B.Cu")
		(net "GND")
	)
	(via
		(at 101.704648 -1.524)
		(size 0.7112)
		(drill 0.4064)
		(layers "F.Cu" "B.Cu")
		(net "GND")
	)
	(via
		(at 489.926122 -41.65219)
		(size 0.7112)
		(drill 0.4064)
		(layers "F.Cu" "B.Cu")
		(net "GND")
	)
	(via
		(at 464.911186 -120.194578)
		(size 0.5588)
		(drill 0.3048)
		(layers "F.Cu" "B.Cu")
		(net "GND")
	)
	(via
		(at 165.989 -253.365)
		(size 0.5588)
		(drill 0.3048)
		(layers "F.Cu" "B.Cu")
		(net "GND")
	)
	(via
		(at 436.88 -128.524)
		(size 0.5588)
		(drill 0.3048)
		(layers "F.Cu" "B.Cu")
		(net "GND")
	)
	(via
		(at 137.668 -194.056)
		(size 0.5588)
		(drill 0.3048)
		(layers "F.Cu" "B.Cu")
		(net "GND")
	)
	(via
		(at 489.926122 -279.14219)
		(size 0.7112)
		(drill 0.4064)
		(layers "F.Cu" "B.Cu")
		(net "GND")
	)
	(via
		(at 68.119498 -147.065492)
		(size 0.5588)
		(drill 0.3048)
		(layers "F.Cu" "B.Cu")
		(net "GND")
	)
	(via
		(at 463.3468 -4.826)
		(size 0.5588)
		(drill 0.3048)
		(layers "F.Cu" "B.Cu")
		(net "GND")
	)
	(via
		(at 451.854824 -20.655026)
		(size 0.5588)
		(drill 0.3048)
		(layers "F.Cu" "B.Cu")
		(net "GND")
	)
	(via
		(at 166.116 -41.275)
		(size 0.5588)
		(drill 0.3048)
		(layers "F.Cu" "B.Cu")
		(net "GND")
	)
	(via
		(at 1.524 -342.033352)
		(size 0.7112)
		(drill 0.4064)
		(layers "F.Cu" "B.Cu")
		(net "GND")
	)
	(via
		(at 170.40225 -216.257886)
		(size 0.5588)
		(drill 0.3048)
		(layers "F.Cu" "B.Cu")
		(net "GND")
	)
	(via
		(at 94.684596 -365.416592)
		(size 0.6604)
		(drill 0.3302)
		(layers "F.Cu" "B.Cu")
		(net "GND")
	)
	(via
		(at 167.744648 -1.524)
		(size 0.7112)
		(drill 0.4064)
		(layers "F.Cu" "B.Cu")
		(net "GND")
	)
	(via
		(at 364.871 -109.22)
		(size 0.5588)
		(drill 0.3048)
		(layers "F.Cu" "B.Cu")
		(net "GND")
	)
	(via
		(at 447.548 -159.512)
		(size 0.5588)
		(drill 0.3048)
		(layers "F.Cu" "B.Cu")
		(net "GND")
	)
	(via
		(at 388.754874 -20.655026)
		(size 0.5588)
		(drill 0.3048)
		(layers "F.Cu" "B.Cu")
		(net "GND")
	)
	(via
		(at 91.313 -235.0516)
		(size 0.5588)
		(drill 0.3048)
		(layers "F.Cu" "B.Cu")
		(net "GND")
	)
	(via
		(at 372.25097 -101.759004)
		(size 0.5588)
		(drill 0.3048)
		(layers "F.Cu" "B.Cu")
		(net "GND")
	)
	(via
		(at 19.05 -18.6182)
		(size 0.5588)
		(drill 0.3048)
		(layers "F.Cu" "B.Cu")
		(net "GND")
	)
	(via
		(at 12.7 -292.1)
		(size 0.5588)
		(drill 0.3048)
		(layers "F.Cu" "B.Cu")
		(net "GND")
	)
	(via
		(at 154.504898 -270.975074)
		(size 0.5588)
		(drill 0.3048)
		(layers "F.Cu" "B.Cu")
		(net "GND")
	)
	(via
		(at 91.106752 -344.864944)
		(size 0.5588)
		(drill 0.3048)
		(layers "F.Cu" "B.Cu")
		(net "GND")
	)
	(via
		(at 165.862 -378.079)
		(size 0.5588)
		(drill 0.3048)
		(layers "F.Cu" "B.Cu")
		(net "GND")
	)
	(via
		(at 197.47611 -11.162538)
		(size 0.7112)
		(drill 0.4064)
		(layers "F.Cu" "B.Cu")
		(net "GND")
	)
	(via
		(at 406.4 -368.3)
		(size 0.5588)
		(drill 0.3048)
		(layers "F.Cu" "B.Cu")
		(net "GND")
	)
	(via
		(at 46.337982 -384.47599)
		(size 0.7112)
		(drill 0.4064)
		(layers "F.Cu" "B.Cu")
		(net "GND")
	)
	(via
		(at 122.954796 -268.435074)
		(size 0.5588)
		(drill 0.3048)
		(layers "F.Cu" "B.Cu")
		(net "GND")
	)
	(via
		(at 263.129522 -361.860846)
		(size 0.5588)
		(drill 0.3048)
		(layers "F.Cu" "B.Cu")
		(net "GND")
	)
	(via
		(at 450.556376 -1.524)
		(size 0.7112)
		(drill 0.4064)
		(layers "F.Cu" "B.Cu")
		(net "GND")
	)
	(via
		(at 467.066376 -1.524)
		(size 0.7112)
		(drill 0.4064)
		(layers "F.Cu" "B.Cu")
		(net "GND")
	)
	(via
		(at 158.733998 -384.47599)
		(size 0.7112)
		(drill 0.4064)
		(layers "F.Cu" "B.Cu")
		(net "GND")
	)
	(via
		(at 131.064 -123.952)
		(size 0.5588)
		(drill 0.3048)
		(layers "F.Cu" "B.Cu")
		(net "GND")
	)
	(via
		(at 25.4 -355.6)
		(size 0.5588)
		(drill 0.3048)
		(layers "F.Cu" "B.Cu")
		(net "GND")
	)
	(via
		(at 489.926122 -50.54219)
		(size 0.7112)
		(drill 0.4064)
		(layers "F.Cu" "B.Cu")
		(net "GND")
	)
	(via
		(at 166.353998 -384.47599)
		(size 0.7112)
		(drill 0.4064)
		(layers "F.Cu" "B.Cu")
		(net "GND")
	)
	(via
		(at 489.926122 -175.00219)
		(size 0.7112)
		(drill 0.4064)
		(layers "F.Cu" "B.Cu")
		(net "GND")
	)
	(via
		(at 1.524 -2.943352)
		(size 0.7112)
		(drill 0.4064)
		(layers "F.Cu" "B.Cu")
		(net "GND")
	)
	(via
		(at 107.14228 -150.784814)
		(size 0.5588)
		(drill 0.3048)
		(layers "F.Cu" "B.Cu")
		(net "GND")
	)
	(via
		(at 489.926122 -67.05219)
		(size 0.7112)
		(drill 0.4064)
		(layers "F.Cu" "B.Cu")
		(net "GND")
	)
	(via
		(at 372.872 -10.668)
		(size 0.5588)
		(drill 0.3048)
		(layers "F.Cu" "B.Cu")
		(net "GND")
	)
	(via
		(at 338.699856 -384.47599)
		(size 0.7112)
		(drill 0.4064)
		(layers "F.Cu" "B.Cu")
		(net "GND")
	)
	(via
		(at 489.926122 -318.51219)
		(size 0.7112)
		(drill 0.4064)
		(layers "F.Cu" "B.Cu")
		(net "GND")
	)
	(via
		(at 323.590666 -165.78326)
		(size 0.5588)
		(drill 0.3048)
		(layers "F.Cu" "B.Cu")
		(net "GND")
	)
	(via
		(at 293.624 -379.476)
		(size 0.5588)
		(drill 0.3048)
		(layers "F.Cu" "B.Cu")
		(net "GND")
	)
	(via
		(at 157.463998 -384.47599)
		(size 0.7112)
		(drill 0.4064)
		(layers "F.Cu" "B.Cu")
		(net "GND")
	)
	(via
		(at 1.524 -157.883352)
		(size 0.7112)
		(drill 0.4064)
		(layers "F.Cu" "B.Cu")
		(net "GND")
	)
	(via
		(at 60.307982 -384.47599)
		(size 0.7112)
		(drill 0.4064)
		(layers "F.Cu" "B.Cu")
		(net "GND")
	)
	(via
		(at 431.8 -304.8)
		(size 0.5588)
		(drill 0.3048)
		(layers "F.Cu" "B.Cu")
		(net "GND")
	)
	(via
		(at 98.726752 -344.864944)
		(size 0.5588)
		(drill 0.3048)
		(layers "F.Cu" "B.Cu")
		(net "GND")
	)
	(via
		(at 171.433998 -384.47599)
		(size 0.7112)
		(drill 0.4064)
		(layers "F.Cu" "B.Cu")
		(net "GND")
	)
	(via
		(at 489.926122 -362.96219)
		(size 0.7112)
		(drill 0.4064)
		(layers "F.Cu" "B.Cu")
		(net "GND")
	)
	(via
		(at 489.926122 -354.07219)
		(size 0.7112)
		(drill 0.4064)
		(layers "F.Cu" "B.Cu")
		(net "GND")
	)
	(via
		(at 78.844648 -1.524)
		(size 0.7112)
		(drill 0.4064)
		(layers "F.Cu" "B.Cu")
		(net "GND")
	)
	(via
		(at 489.926122 -171.19219)
		(size 0.7112)
		(drill 0.4064)
		(layers "F.Cu" "B.Cu")
		(net "GND")
	)
	(via
		(at 53.6448 -250.4948)
		(size 0.5588)
		(drill 0.3048)
		(layers "F.Cu" "B.Cu")
		(net "GND")
	)
	(via
		(at 282.956 -363.22)
		(size 0.5588)
		(drill 0.3048)
		(layers "F.Cu" "B.Cu")
		(net "GND")
	)
	(via
		(at 178.943 -103.759)
		(size 0.5588)
		(drill 0.3048)
		(layers "F.Cu" "B.Cu")
		(net "GND")
	)
	(via
		(at 85.725 -240.411)
		(size 0.5588)
		(drill 0.3048)
		(layers "F.Cu" "B.Cu")
		(net "GND")
	)
	(via
		(at 357.124 -366.776)
		(size 0.5588)
		(drill 0.3048)
		(layers "F.Cu" "B.Cu")
		(net "GND")
	)
	(via
		(at 288.911284 -202.69454)
		(size 0.6604)
		(drill 0.3556)
		(layers "F.Cu" "B.Cu")
		(net "GND")
	)
	(via
		(at 313.634882 -380.775972)
		(size 0.7112)
		(drill 0.4064)
		(layers "F.Cu" "B.Cu")
		(net "GND")
	)
	(via
		(at 205.476094 -58.846212)
		(size 0.7112)
		(drill 0.4064)
		(layers "F.Cu" "B.Cu")
		(net "GND")
	)
	(via
		(at 22.606 -41.3258)
		(size 0.5588)
		(drill 0.3048)
		(layers "F.Cu" "B.Cu")
		(net "GND")
	)
	(via
		(at 1.524 -141.373352)
		(size 0.7112)
		(drill 0.4064)
		(layers "F.Cu" "B.Cu")
		(net "GND")
	)
	(via
		(at 64.008 -230.124)
		(size 0.5588)
		(drill 0.3048)
		(layers "F.Cu" "B.Cu")
		(net "GND")
	)
	(via
		(at 489.926122 -163.57219)
		(size 0.7112)
		(drill 0.4064)
		(layers "F.Cu" "B.Cu")
		(net "GND")
	)
	(via
		(at 147.997418 -216.81567)
		(size 0.5588)
		(drill 0.3048)
		(layers "F.Cu" "B.Cu")
		(net "GND")
	)
	(via
		(at 98.933 -256.286)
		(size 0.5588)
		(drill 0.3048)
		(layers "F.Cu" "B.Cu")
		(net "GND")
	)
	(via
		(at 489.926122 -114.04219)
		(size 0.7112)
		(drill 0.4064)
		(layers "F.Cu" "B.Cu")
		(net "GND")
	)
	(via
		(at 197.47611 -35.292538)
		(size 0.7112)
		(drill 0.4064)
		(layers "F.Cu" "B.Cu")
		(net "GND")
	)
	(via
		(at 118.872 -277.241)
		(size 0.5588)
		(drill 0.3048)
		(layers "F.Cu" "B.Cu")
		(net "GND")
	)
	(via
		(at 25.4 -342.9)
		(size 0.5588)
		(drill 0.3048)
		(layers "F.Cu" "B.Cu")
		(net "GND")
	)
	(via
		(at 440.935872 -384.47599)
		(size 0.7112)
		(drill 0.4064)
		(layers "F.Cu" "B.Cu")
		(net "GND")
	)
	(via
		(at 82.169 -18.6182)
		(size 0.5588)
		(drill 0.3048)
		(layers "F.Cu" "B.Cu")
		(net "GND")
	)
	(via
		(at 34.394648 -1.524)
		(size 0.7112)
		(drill 0.4064)
		(layers "F.Cu" "B.Cu")
		(net "GND")
	)
	(via
		(at 489.926122 -365.50219)
		(size 0.7112)
		(drill 0.4064)
		(layers "F.Cu" "B.Cu")
		(net "GND")
	)
	(via
		(at 208.504282 -223.374712)
		(size 0.5588)
		(drill 0.3048)
		(layers "F.Cu" "B.Cu")
		(net "GND")
	)
	(via
		(at 167.553894 -216.682828)
		(size 0.5588)
		(drill 0.3048)
		(layers "F.Cu" "B.Cu")
		(net "GND")
	)
	(via
		(at 51.6382 -18.2118)
		(size 0.5588)
		(drill 0.3048)
		(layers "F.Cu" "B.Cu")
		(net "GND")
	)
	(via
		(at 356.062026 -23.830026)
		(size 0.5588)
		(drill 0.3048)
		(layers "F.Cu" "B.Cu")
		(net "GND")
	)
	(via
		(at 312.523886 -4.46151)
		(size 0.7112)
		(drill 0.4064)
		(layers "F.Cu" "B.Cu")
		(net "GND")
	)
	(via
		(at 468.66937 -216.8144)
		(size 0.5588)
		(drill 0.3048)
		(layers "F.Cu" "B.Cu")
		(net "GND")
	)
	(via
		(at 1.524 -128.673352)
		(size 0.7112)
		(drill 0.4064)
		(layers "F.Cu" "B.Cu")
		(net "GND")
	)
	(via
		(at 466.852 -105.537)
		(size 0.5588)
		(drill 0.3048)
		(layers "F.Cu" "B.Cu")
		(net "GND")
	)
	(via
		(at 133.155944 -371.772688)
		(size 0.5588)
		(drill 0.3048)
		(layers "F.Cu" "B.Cu")
		(net "GND")
	)
	(via
		(at 397.891 -135.382)
		(size 0.5588)
		(drill 0.3048)
		(layers "F.Cu" "B.Cu")
		(net "GND")
	)
	(via
		(at 162.052 -26.416)
		(size 0.5588)
		(drill 0.3048)
		(layers "F.Cu" "B.Cu")
		(net "GND")
	)
	(via
		(at 1.524 -132.483352)
		(size 0.7112)
		(drill 0.4064)
		(layers "F.Cu" "B.Cu")
		(net "GND")
	)
	(via
		(at 217.163142 -198.230998)
		(size 0.5588)
		(drill 0.3048)
		(layers "F.Cu" "B.Cu")
		(net "GND")
	)
	(via
		(at 489.926122 -13.71219)
		(size 0.7112)
		(drill 0.4064)
		(layers "F.Cu" "B.Cu")
		(net "GND")
	)
	(via
		(at 368.3 -304.8)
		(size 0.5588)
		(drill 0.3048)
		(layers "F.Cu" "B.Cu")
		(net "GND")
	)
	(via
		(at 489.926122 -178.81219)
		(size 0.7112)
		(drill 0.4064)
		(layers "F.Cu" "B.Cu")
		(net "GND")
	)
	(via
		(at 36.899596 -364.40999)
		(size 0.5588)
		(drill 0.3048)
		(layers "F.Cu" "B.Cu")
		(net "GND")
	)
	(via
		(at 324.612 -205.74)
		(size 0.5588)
		(drill 0.3048)
		(layers "F.Cu" "B.Cu")
		(net "GND")
	)
	(via
		(at 482.6 -101.6)
		(size 0.5588)
		(drill 0.3048)
		(layers "F.Cu" "B.Cu")
		(net "GND")
	)
	(via
		(at 152.146 -283.337)
		(size 0.5588)
		(drill 0.3048)
		(layers "F.Cu" "B.Cu")
		(net "GND")
	)
	(via
		(at 1.524 -267.103352)
		(size 0.7112)
		(drill 0.4064)
		(layers "F.Cu" "B.Cu")
		(net "GND")
	)
	(via
		(at 368.3 -330.2)
		(size 0.5588)
		(drill 0.3048)
		(layers "F.Cu" "B.Cu")
		(net "GND")
	)
	(via
		(at 395.224 -127.381)
		(size 0.5588)
		(drill 0.3048)
		(layers "F.Cu" "B.Cu")
		(net "GND")
	)
	(via
		(at 78.507844 -333.554832)
		(size 0.5588)
		(drill 0.3048)
		(layers "F.Cu" "B.Cu")
		(net "GND")
	)
	(via
		(at 85.725 -156.2608)
		(size 0.5588)
		(drill 0.3048)
		(layers "F.Cu" "B.Cu")
		(net "GND")
	)
	(via
		(at 489.926122 -267.71219)
		(size 0.7112)
		(drill 0.4064)
		(layers "F.Cu" "B.Cu")
		(net "GND")
	)
	(via
		(at 59.854846 -250.655074)
		(size 0.5588)
		(drill 0.3048)
		(layers "F.Cu" "B.Cu")
		(net "GND")
	)
	(via
		(at 469.965024 -380.775972)
		(size 0.7112)
		(drill 0.4064)
		(layers "F.Cu" "B.Cu")
		(net "GND")
	)
	(via
		(at 208.737962 -378.476002)
		(size 0.7112)
		(drill 0.4064)
		(layers "F.Cu" "B.Cu")
		(net "GND")
	)
	(via
		(at 312.523886 -34.94151)
		(size 0.7112)
		(drill 0.4064)
		(layers "F.Cu" "B.Cu")
		(net "GND")
	)
	(via
		(at 472.2622 -248.285)
		(size 0.5588)
		(drill 0.3048)
		(layers "F.Cu" "B.Cu")
		(net "GND")
	)
	(via
		(at 443.417198 -101.763322)
		(size 0.5588)
		(drill 0.3048)
		(layers "F.Cu" "B.Cu")
		(net "GND")
	)
	(via
		(at 298.704 -271.78)
		(size 0.5588)
		(drill 0.3048)
		(layers "F.Cu" "B.Cu")
		(net "GND")
	)
	(via
		(at 77.237844 -333.554832)
		(size 0.5588)
		(drill 0.3048)
		(layers "F.Cu" "B.Cu")
		(net "GND")
	)
	(via
		(at 489.926122 -36.57219)
		(size 0.7112)
		(drill 0.4064)
		(layers "F.Cu" "B.Cu")
		(net "GND")
	)
	(via
		(at 150.495 -7.112)
		(size 0.5588)
		(drill 0.3048)
		(layers "F.Cu" "B.Cu")
		(net "GND")
	)
	(via
		(at 342.46947 -216.8144)
		(size 0.5588)
		(drill 0.3048)
		(layers "F.Cu" "B.Cu")
		(net "GND")
	)
	(via
		(at 456.0824 -11.4046)
		(size 0.5588)
		(drill 0.3048)
		(layers "F.Cu" "B.Cu")
		(net "GND")
	)
	(via
		(at 351.399856 -384.47599)
		(size 0.7112)
		(drill 0.4064)
		(layers "F.Cu" "B.Cu")
		(net "GND")
	)
	(via
		(at 205.141322 -103.884984)
		(size 0.7112)
		(drill 0.4064)
		(layers "F.Cu" "B.Cu")
		(net "GND")
	)
	(via
		(at 312.523886 -24.78151)
		(size 0.7112)
		(drill 0.4064)
		(layers "F.Cu" "B.Cu")
		(net "GND")
	)
	(via
		(at 154.504898 -135.65505)
		(size 0.5588)
		(drill 0.3048)
		(layers "F.Cu" "B.Cu")
		(net "GND")
	)
	(via
		(at 154.504898 -20.655026)
		(size 0.5588)
		(drill 0.3048)
		(layers "F.Cu" "B.Cu")
		(net "GND")
	)
	(via
		(at 136.144 -163.576)
		(size 0.5588)
		(drill 0.3048)
		(layers "F.Cu" "B.Cu")
		(net "GND")
	)
	(via
		(at 204.927962 -378.476002)
		(size 0.7112)
		(drill 0.4064)
		(layers "F.Cu" "B.Cu")
		(net "GND")
	)
	(via
		(at 91.404948 -268.435074)
		(size 0.5588)
		(drill 0.3048)
		(layers "F.Cu" "B.Cu")
		(net "GND")
	)
	(via
		(at 94.866968 -343.520014)
		(size 0.5588)
		(drill 0.3048)
		(layers "F.Cu" "B.Cu")
		(net "GND")
	)
	(via
		(at 360.289856 -384.47599)
		(size 0.7112)
		(drill 0.4064)
		(layers "F.Cu" "B.Cu")
		(net "GND")
	)
	(via
		(at 375.92 -259.08)
		(size 0.5588)
		(drill 0.3048)
		(layers "F.Cu" "B.Cu")
		(net "GND")
	)
	(via
		(at 4.523994 -372.794022)
		(size 0.7112)
		(drill 0.4064)
		(layers "F.Cu" "B.Cu")
		(net "GND")
	)
	(via
		(at 422.082976 -50.785014)
		(size 0.5588)
		(drill 0.3048)
		(layers "F.Cu" "B.Cu")
		(net "GND")
	)
	(via
		(at 276.334982 -358.476042)
		(size 0.7112)
		(drill 0.4064)
		(layers "F.Cu" "B.Cu")
		(net "GND")
	)
	(via
		(at 81.788 -145.542)
		(size 0.5588)
		(drill 0.3048)
		(layers "F.Cu" "B.Cu")
		(net "GND")
	)
	(via
		(at 489.926122 -213.10219)
		(size 0.7112)
		(drill 0.4064)
		(layers "F.Cu" "B.Cu")
		(net "GND")
	)
	(via
		(at 478.6884 -12.446)
		(size 0.5588)
		(drill 0.3048)
		(layers "F.Cu" "B.Cu")
		(net "GND")
	)
	(via
		(at 333.716376 -1.524)
		(size 0.7112)
		(drill 0.4064)
		(layers "F.Cu" "B.Cu")
		(net "GND")
	)
	(via
		(at 65.913 -379.476)
		(size 0.5588)
		(drill 0.3048)
		(layers "F.Cu" "B.Cu")
		(net "GND")
	)
	(via
		(at 197.47611 -39.102538)
		(size 0.7112)
		(drill 0.4064)
		(layers "F.Cu" "B.Cu")
		(net "GND")
	)
	(via
		(at 489.926122 -35.30219)
		(size 0.7112)
		(drill 0.4064)
		(layers "F.Cu" "B.Cu")
		(net "GND")
	)
	(via
		(at 285.190692 -384.47599)
		(size 0.7112)
		(drill 0.4064)
		(layers "F.Cu" "B.Cu")
		(net "GND")
	)
	(via
		(at 304.885598 -231.7242)
		(size 0.5588)
		(drill 0.3048)
		(layers "F.Cu" "B.Cu")
		(net "GND")
	)
	(via
		(at 458.216 -52.07)
		(size 0.5588)
		(drill 0.3048)
		(layers "F.Cu" "B.Cu")
		(net "GND")
	)
	(via
		(at 80.114648 -1.524)
		(size 0.7112)
		(drill 0.4064)
		(layers "F.Cu" "B.Cu")
		(net "GND")
	)
	(via
		(at 489.926122 -126.74219)
		(size 0.7112)
		(drill 0.4064)
		(layers "F.Cu" "B.Cu")
		(net "GND")
	)
	(via
		(at 206.5274 -306.5526)
		(size 0.7112)
		(drill 0.4064)
		(layers "F.Cu" "B.Cu")
		(net "GND")
	)
	(via
		(at 242.0874 -307.6956)
		(size 0.5588)
		(drill 0.3048)
		(layers "F.Cu" "B.Cu")
		(net "GND")
	)
	(via
		(at 489.926122 -350.26219)
		(size 0.7112)
		(drill 0.4064)
		(layers "F.Cu" "B.Cu")
		(net "GND")
	)
	(via
		(at 489.926122 -322.32219)
		(size 0.7112)
		(drill 0.4064)
		(layers "F.Cu" "B.Cu")
		(net "GND")
	)
	(via
		(at 441.452 -229.616)
		(size 0.5588)
		(drill 0.3048)
		(layers "F.Cu" "B.Cu")
		(net "GND")
	)
	(via
		(at 75.034648 -1.524)
		(size 0.7112)
		(drill 0.4064)
		(layers "F.Cu" "B.Cu")
		(net "GND")
	)
	(via
		(at 259.541772 -373.59971)
		(size 0.5588)
		(drill 0.3048)
		(layers "F.Cu" "B.Cu")
		(net "GND")
	)
	(via
		(at 305.510692 -384.47599)
		(size 0.7112)
		(drill 0.4064)
		(layers "F.Cu" "B.Cu")
		(net "GND")
	)
	(via
		(at 324.826376 -1.524)
		(size 0.7112)
		(drill 0.4064)
		(layers "F.Cu" "B.Cu")
		(net "GND")
	)
	(via
		(at 278.274018 -371.108478)
		(size 0.7112)
		(drill 0.4064)
		(layers "F.Cu" "B.Cu")
		(net "GND")
	)
	(via
		(at 1.524 -343.303352)
		(size 0.7112)
		(drill 0.4064)
		(layers "F.Cu" "B.Cu")
		(net "GND")
	)
	(via
		(at 270.52397 -55.09133)
		(size 0.7112)
		(drill 0.4064)
		(layers "F.Cu" "B.Cu")
		(net "GND")
	)
	(via
		(at 489.926122 -34.03219)
		(size 0.7112)
		(drill 0.4064)
		(layers "F.Cu" "B.Cu")
		(net "GND")
	)
	(via
		(at 432.776376 -1.524)
		(size 0.7112)
		(drill 0.4064)
		(layers "F.Cu" "B.Cu")
		(net "GND")
	)
	(via
		(at 331.88275 -364.236)
		(size 0.5588)
		(drill 0.3048)
		(layers "F.Cu" "B.Cu")
		(net "GND")
	)
	(via
		(at 489.926122 -319.78219)
		(size 0.7112)
		(drill 0.4064)
		(layers "F.Cu" "B.Cu")
		(net "GND")
	)
	(via
		(at 158.75 -257.683)
		(size 0.5588)
		(drill 0.3048)
		(layers "F.Cu" "B.Cu")
		(net "GND")
	)
	(via
		(at 1.524 -288.693352)
		(size 0.7112)
		(drill 0.4064)
		(layers "F.Cu" "B.Cu")
		(net "GND")
	)
	(via
		(at 241.3508 -354.203)
		(size 0.7112)
		(drill 0.4064)
		(layers "F.Cu" "B.Cu")
		(net "GND")
	)
	(via
		(at 181.1655 -250.444)
		(size 0.5588)
		(drill 0.3048)
		(layers "F.Cu" "B.Cu")
		(net "GND")
	)
	(via
		(at 325.654924 -38.435026)
		(size 0.5588)
		(drill 0.3048)
		(layers "F.Cu" "B.Cu")
		(net "GND")
	)
	(via
		(at 141.074648 -1.524)
		(size 0.7112)
		(drill 0.4064)
		(layers "F.Cu" "B.Cu")
		(net "GND")
	)
	(via
		(at 50.8 -164.084)
		(size 0.5588)
		(drill 0.3048)
		(layers "F.Cu" "B.Cu")
		(net "GND")
	)
	(via
		(at 483.404926 -128.03505)
		(size 0.5588)
		(drill 0.3048)
		(layers "F.Cu" "B.Cu")
		(net "GND")
	)
	(via
		(at 91.404948 -135.65505)
		(size 0.5588)
		(drill 0.3048)
		(layers "F.Cu" "B.Cu")
		(net "GND")
	)
	(via
		(at 234.137962 -378.476002)
		(size 0.7112)
		(drill 0.4064)
		(layers "F.Cu" "B.Cu")
		(net "GND")
	)
	(via
		(at 184.912 -251.430028)
		(size 0.5588)
		(drill 0.3048)
		(layers "F.Cu" "B.Cu")
		(net "GND")
	)
	(via
		(at 464.693 -78.994)
		(size 0.5588)
		(drill 0.3048)
		(layers "F.Cu" "B.Cu")
		(net "GND")
	)
	(via
		(at 93.646752 -344.864944)
		(size 0.5588)
		(drill 0.3048)
		(layers "F.Cu" "B.Cu")
		(net "GND")
	)
	(via
		(at 285.667958 -102.431088)
		(size 0.7112)
		(drill 0.4064)
		(layers "F.Cu" "B.Cu")
		(net "GND")
	)
	(via
		(at 381 -162.56)
		(size 0.5588)
		(drill 0.3048)
		(layers "F.Cu" "B.Cu")
		(net "GND")
	)
	(via
		(at 109.28985 -101.435154)
		(size 0.5588)
		(drill 0.3048)
		(layers "F.Cu" "B.Cu")
		(net "GND")
	)
	(via
		(at 14.163802 -225.30435)
		(size 0.5588)
		(drill 0.3048)
		(layers "F.Cu" "B.Cu")
		(net "GND")
	)
	(via
		(at 434.457094 -211.310728)
		(size 0.5588)
		(drill 0.3048)
		(layers "F.Cu" "B.Cu")
		(net "GND")
	)
	(via
		(at 170.18 -303.784)
		(size 0.5588)
		(drill 0.3048)
		(layers "F.Cu" "B.Cu")
		(net "GND")
	)
	(via
		(at 483.404926 -38.435026)
		(size 0.5588)
		(drill 0.3048)
		(layers "F.Cu" "B.Cu")
		(net "GND")
	)
	(via
		(at 54.356 -83.312)
		(size 0.5588)
		(drill 0.3048)
		(layers "F.Cu" "B.Cu")
		(net "GND")
	)
	(via
		(at 83.486752 -344.864944)
		(size 0.5588)
		(drill 0.3048)
		(layers "F.Cu" "B.Cu")
		(net "GND")
	)
	(via
		(at 482.261926 -253.830074)
		(size 0.5588)
		(drill 0.3048)
		(layers "F.Cu" "B.Cu")
		(net "GND")
	)
	(via
		(at 419.161976 -23.830026)
		(size 0.5588)
		(drill 0.3048)
		(layers "F.Cu" "B.Cu")
		(net "GND")
	)
	(via
		(at 473.6592 -33.655)
		(size 0.5588)
		(drill 0.3048)
		(layers "F.Cu" "B.Cu")
		(net "GND")
	)
	(via
		(at 195.719954 -384.47599)
		(size 0.7112)
		(drill 0.4064)
		(layers "F.Cu" "B.Cu")
		(net "GND")
	)
	(via
		(at 447.961004 -361.95)
		(size 0.7112)
		(drill 0.4064)
		(layers "F.Cu" "B.Cu")
		(net "GND")
	)
	(via
		(at 489.926122 -40.38219)
		(size 0.7112)
		(drill 0.4064)
		(layers "F.Cu" "B.Cu")
		(net "GND")
	)
	(via
		(at 467.614 -150.622)
		(size 0.5588)
		(drill 0.3048)
		(layers "F.Cu" "B.Cu")
		(net "GND")
	)
	(via
		(at 122.85599 -378.476002)
		(size 0.7112)
		(drill 0.4064)
		(layers "F.Cu" "B.Cu")
		(net "GND")
	)
	(via
		(at 122.74931 -153.985722)
		(size 0.5588)
		(drill 0.3048)
		(layers "F.Cu" "B.Cu")
		(net "GND")
	)
	(via
		(at 1.524 -16.913352)
		(size 0.7112)
		(drill 0.4064)
		(layers "F.Cu" "B.Cu")
		(net "GND")
	)
	(via
		(at 270.52397 -60.17133)
		(size 0.7112)
		(drill 0.4064)
		(layers "F.Cu" "B.Cu")
		(net "GND")
	)
	(via
		(at 260.413754 -226.822)
		(size 0.5588)
		(drill 0.3048)
		(layers "F.Cu" "B.Cu")
		(net "GND")
	)
	(via
		(at 321.564 -265.684)
		(size 0.5588)
		(drill 0.3048)
		(layers "F.Cu" "B.Cu")
		(net "GND")
	)
	(via
		(at 382.197864 -378.476002)
		(size 0.7112)
		(drill 0.4064)
		(layers "F.Cu" "B.Cu")
		(net "GND")
	)
	(via
		(at 419.161976 -138.83005)
		(size 0.5588)
		(drill 0.3048)
		(layers "F.Cu" "B.Cu")
		(net "GND")
	)
	(via
		(at 82.317844 -333.554832)
		(size 0.5588)
		(drill 0.3048)
		(layers "F.Cu" "B.Cu")
		(net "GND")
	)
	(via
		(at 87.296752 -344.864944)
		(size 0.5588)
		(drill 0.3048)
		(layers "F.Cu" "B.Cu")
		(net "GND")
	)
	(via
		(at 42.544746 -364.236)
		(size 0.5588)
		(drill 0.3048)
		(layers "F.Cu" "B.Cu")
		(net "GND")
	)
	(via
		(at 263.728962 -366.194086)
		(size 0.5588)
		(drill 0.3048)
		(layers "F.Cu" "B.Cu")
		(net "GND")
	)
	(via
		(at 476.651828 -384.47599)
		(size 0.7112)
		(drill 0.4064)
		(layers "F.Cu" "B.Cu")
		(net "GND")
	)
	(via
		(at 1.524 -333.143352)
		(size 0.7112)
		(drill 0.4064)
		(layers "F.Cu" "B.Cu")
		(net "GND")
	)
	(via
		(at 58.711846 -26.230072)
		(size 0.5588)
		(drill 0.3048)
		(layers "F.Cu" "B.Cu")
		(net "GND")
	)
	(via
		(at 325.550022 -120.197372)
		(size 0.5588)
		(drill 0.3048)
		(layers "F.Cu" "B.Cu")
		(net "GND")
	)
	(via
		(at 477.226376 -1.524)
		(size 0.7112)
		(drill 0.4064)
		(layers "F.Cu" "B.Cu")
		(net "GND")
	)
	(via
		(at 28.304998 -270.975074)
		(size 0.5588)
		(drill 0.3048)
		(layers "F.Cu" "B.Cu")
		(net "GND")
	)
	(via
		(at 85.852 -126.492)
		(size 0.5588)
		(drill 0.3048)
		(layers "F.Cu" "B.Cu")
		(net "GND")
	)
	(via
		(at 150.495 -47.244)
		(size 0.5588)
		(drill 0.3048)
		(layers "F.Cu" "B.Cu")
		(net "GND")
	)
	(via
		(at 489.926122 -315.97219)
		(size 0.7112)
		(drill 0.4064)
		(layers "F.Cu" "B.Cu")
		(net "GND")
	)
	(via
		(at 148.59 -240.792)
		(size 0.5588)
		(drill 0.3048)
		(layers "F.Cu" "B.Cu")
		(net "GND")
	)
	(via
		(at 322.189856 -384.47599)
		(size 0.7112)
		(drill 0.4064)
		(layers "F.Cu" "B.Cu")
		(net "GND")
	)
	(via
		(at 126.9492 -243.035074)
		(size 0.5588)
		(drill 0.3048)
		(layers "F.Cu" "B.Cu")
		(net "GND")
	)
	(via
		(at 339.807296 -211.56549)
		(size 0.5588)
		(drill 0.3048)
		(layers "F.Cu" "B.Cu")
		(net "GND")
	)
	(via
		(at 489.926122 -12.44219)
		(size 0.7112)
		(drill 0.4064)
		(layers "F.Cu" "B.Cu")
		(net "GND")
	)
	(via
		(at 1.524 -216.303352)
		(size 0.7112)
		(drill 0.4064)
		(layers "F.Cu" "B.Cu")
		(net "GND")
	)
	(via
		(at 463.256376 -1.524)
		(size 0.7112)
		(drill 0.4064)
		(layers "F.Cu" "B.Cu")
		(net "GND")
	)
	(via
		(at 55.227982 -384.47599)
		(size 0.7112)
		(drill 0.4064)
		(layers "F.Cu" "B.Cu")
		(net "GND")
	)
	(via
		(at 70.776084 -383.387092)
		(size 0.7112)
		(drill 0.4064)
		(layers "F.Cu" "B.Cu")
		(net "GND")
	)
	(via
		(at 426.426376 -1.524)
		(size 0.7112)
		(drill 0.4064)
		(layers "F.Cu" "B.Cu")
		(net "GND")
	)
	(via
		(at 479.298 -277.241)
		(size 0.5588)
		(drill 0.3048)
		(layers "F.Cu" "B.Cu")
		(net "GND")
	)
	(via
		(at 462.3308 -17.81556)
		(size 0.5588)
		(drill 0.3048)
		(layers "F.Cu" "B.Cu")
		(net "GND")
	)
	(via
		(at 208.90738 -249.29338)
		(size 0.5588)
		(drill 0.3048)
		(layers "F.Cu" "B.Cu")
		(net "GND")
	)
	(via
		(at 263.7028 -193.6242)
		(size 0.7112)
		(drill 0.4064)
		(layers "F.Cu" "B.Cu")
		(net "GND")
	)
	(via
		(at 477.774 -41.1988)
		(size 0.5588)
		(drill 0.3048)
		(layers "F.Cu" "B.Cu")
		(net "GND")
	)
	(via
		(at 1.524 -320.443352)
		(size 0.7112)
		(drill 0.4064)
		(layers "F.Cu" "B.Cu")
		(net "GND")
	)
	(via
		(at 135.128 -249.682)
		(size 0.5588)
		(drill 0.3048)
		(layers "F.Cu" "B.Cu")
		(net "GND")
	)
	(via
		(at 459.867 -268.224)
		(size 0.5588)
		(drill 0.3048)
		(layers "F.Cu" "B.Cu")
		(net "GND")
	)
	(via
		(at 388.754874 -263.355074)
		(size 0.5588)
		(drill 0.3048)
		(layers "F.Cu" "B.Cu")
		(net "GND")
	)
	(via
		(at 73.04786 -119.326406)
		(size 0.5588)
		(drill 0.3048)
		(layers "F.Cu" "B.Cu")
		(net "GND")
	)
	(via
		(at 249.555 -309.118)
		(size 0.5588)
		(drill 0.3048)
		(layers "F.Cu" "B.Cu")
		(net "GND")
	)
	(via
		(at 143.580866 -146.952208)
		(size 0.5588)
		(drill 0.3048)
		(layers "F.Cu" "B.Cu")
		(net "GND")
	)
	(via
		(at 59.854846 -268.435074)
		(size 0.5588)
		(drill 0.3048)
		(layers "F.Cu" "B.Cu")
		(net "GND")
	)
	(via
		(at 158.854648 -1.524)
		(size 0.7112)
		(drill 0.4064)
		(layers "F.Cu" "B.Cu")
		(net "GND")
	)
	(via
		(at 1.524 -184.553352)
		(size 0.7112)
		(drill 0.4064)
		(layers "F.Cu" "B.Cu")
		(net "GND")
	)
	(via
		(at 91.404948 -38.435026)
		(size 0.5588)
		(drill 0.3048)
		(layers "F.Cu" "B.Cu")
		(net "GND")
	)
	(via
		(at 489.926122 -346.45219)
		(size 0.7112)
		(drill 0.4064)
		(layers "F.Cu" "B.Cu")
		(net "GND")
	)
	(via
		(at 40.254936 -359.664)
		(size 0.5588)
		(drill 0.3048)
		(layers "F.Cu" "B.Cu")
		(net "GND")
	)
	(via
		(at 262.393684 -96.515174)
		(size 0.5588)
		(drill 0.3048)
		(layers "F.Cu" "B.Cu")
		(net "GND")
	)
	(via
		(at 197.47611 -23.862538)
		(size 0.7112)
		(drill 0.4064)
		(layers "F.Cu" "B.Cu")
		(net "GND")
	)
	(via
		(at 278.274018 -364.758478)
		(size 0.7112)
		(drill 0.4064)
		(layers "F.Cu" "B.Cu")
		(net "GND")
	)
	(via
		(at 149.964648 -1.524)
		(size 0.7112)
		(drill 0.4064)
		(layers "F.Cu" "B.Cu")
		(net "GND")
	)
	(via
		(at 263.684004 -384.457956)
		(size 0.7112)
		(drill 0.4064)
		(layers "F.Cu" "B.Cu")
		(net "GND")
	)
	(via
		(at 388.326376 -1.524)
		(size 0.7112)
		(drill 0.4064)
		(layers "F.Cu" "B.Cu")
		(net "GND")
	)
	(via
		(at 306.197 -383.286)
		(size 0.7112)
		(drill 0.4064)
		(layers "F.Cu" "B.Cu")
		(net "GND")
	)
	(via
		(at 24.257 -47.244)
		(size 0.5588)
		(drill 0.3048)
		(layers "F.Cu" "B.Cu")
		(net "GND")
	)
	(via
		(at 9.652 -106.172)
		(size 0.5588)
		(drill 0.3048)
		(layers "F.Cu" "B.Cu")
		(net "GND")
	)
	(via
		(at 223.19996 -164.38626)
		(size 0.5588)
		(drill 0.3048)
		(layers "F.Cu" "B.Cu")
		(net "GND")
	)
	(via
		(at 489.926122 -337.56219)
		(size 0.7112)
		(drill 0.4064)
		(layers "F.Cu" "B.Cu")
		(net "GND")
	)
	(via
		(at 176.403 -145.542)
		(size 0.5588)
		(drill 0.3048)
		(layers "F.Cu" "B.Cu")
		(net "GND")
	)
	(via
		(at 482.261926 -138.83005)
		(size 0.5588)
		(drill 0.3048)
		(layers "F.Cu" "B.Cu")
		(net "GND")
	)
	(via
		(at 458.357224 -124.62002)
		(size 0.5588)
		(drill 0.3048)
		(layers "F.Cu" "B.Cu")
		(net "GND")
	)
	(via
		(at 197.47611 -22.592538)
		(size 0.7112)
		(drill 0.4064)
		(layers "F.Cu" "B.Cu")
		(net "GND")
	)
	(via
		(at 27.161998 -251.430028)
		(size 0.5588)
		(drill 0.3048)
		(layers "F.Cu" "B.Cu")
		(net "GND")
	)
	(via
		(at 201.117962 -378.476002)
		(size 0.7112)
		(drill 0.4064)
		(layers "F.Cu" "B.Cu")
		(net "GND")
	)
	(via
		(at 236.677962 -378.476002)
		(size 0.7112)
		(drill 0.4064)
		(layers "F.Cu" "B.Cu")
		(net "GND")
	)
	(via
		(at 483.001828 -384.47599)
		(size 0.7112)
		(drill 0.4064)
		(layers "F.Cu" "B.Cu")
		(net "GND")
	)
	(via
		(at 183.388 -381.889)
		(size 0.7112)
		(drill 0.4064)
		(layers "F.Cu" "B.Cu")
		(net "GND")
	)
	(via
		(at 450.711824 -251.430028)
		(size 0.5588)
		(drill 0.3048)
		(layers "F.Cu" "B.Cu")
		(net "GND")
	)
	(via
		(at 351.453196 -360.426)
		(size 0.7112)
		(drill 0.4064)
		(layers "F.Cu" "B.Cu")
		(net "GND")
	)
	(via
		(at 154.504898 -13.035026)
		(size 0.5588)
		(drill 0.3048)
		(layers "F.Cu" "B.Cu")
		(net "GND")
	)
	(via
		(at 125.222 -55.499)
		(size 0.5588)
		(drill 0.3048)
		(layers "F.Cu" "B.Cu")
		(net "GND")
	)
	(via
		(at 430.775872 -384.47599)
		(size 0.7112)
		(drill 0.4064)
		(layers "F.Cu" "B.Cu")
		(net "GND")
	)
	(via
		(at 356.062026 -251.430028)
		(size 0.5588)
		(drill 0.3048)
		(layers "F.Cu" "B.Cu")
		(net "GND")
	)
	(via
		(at 281.8384 -305.2826)
		(size 0.7112)
		(drill 0.4064)
		(layers "F.Cu" "B.Cu")
		(net "GND")
	)
	(via
		(at 489.926122 -274.06219)
		(size 0.7112)
		(drill 0.4064)
		(layers "F.Cu" "B.Cu")
		(net "GND")
	)
	(via
		(at 189.695328 -368.562636)
		(size 0.5588)
		(drill 0.3048)
		(layers "F.Cu" "B.Cu")
		(net "GND")
	)
	(via
		(at 489.926122 -282.95219)
		(size 0.7112)
		(drill 0.4064)
		(layers "F.Cu" "B.Cu")
		(net "GND")
	)
	(via
		(at 148.2598 -135.4328)
		(size 0.5588)
		(drill 0.3048)
		(layers "F.Cu" "B.Cu")
		(net "GND")
	)
	(via
		(at 243.205 -213.9696)
		(size 0.5588)
		(drill 0.3048)
		(layers "F.Cu" "B.Cu")
		(net "GND")
	)
	(via
		(at 489.926122 -291.84219)
		(size 0.7112)
		(drill 0.4064)
		(layers "F.Cu" "B.Cu")
		(net "GND")
	)
	(via
		(at 228.96449 -356.157784)
		(size 0.5588)
		(drill 0.3048)
		(layers "F.Cu" "B.Cu")
		(net "GND")
	)
	(via
		(at 487.045 -371.729)
		(size 0.7112)
		(drill 0.4064)
		(layers "F.Cu" "B.Cu")
		(net "GND")
	)
	(via
		(at 63.5 -63.5)
		(size 0.5588)
		(drill 0.3048)
		(layers "F.Cu" "B.Cu")
		(net "GND")
	)
	(via
		(at 37.86886 -116.024406)
		(size 0.5588)
		(drill 0.3048)
		(layers "F.Cu" "B.Cu")
		(net "GND")
	)
	(via
		(at 208.8896 -141.605)
		(size 0.7112)
		(drill 0.4064)
		(layers "F.Cu" "B.Cu")
		(net "GND")
	)
	(via
		(at 148.854922 -156.454348)
		(size 0.5588)
		(drill 0.3048)
		(layers "F.Cu" "B.Cu")
		(net "GND")
	)
	(via
		(at 199.847962 -378.476002)
		(size 0.7112)
		(drill 0.4064)
		(layers "F.Cu" "B.Cu")
		(net "GND")
	)
	(via
		(at 489.926122 -154.68219)
		(size 0.7112)
		(drill 0.4064)
		(layers "F.Cu" "B.Cu")
		(net "GND")
	)
	(via
		(at 469.9 -304.8)
		(size 0.5588)
		(drill 0.3048)
		(layers "F.Cu" "B.Cu")
		(net "GND")
	)
	(via
		(at 489.926122 -21.33219)
		(size 0.7112)
		(drill 0.4064)
		(layers "F.Cu" "B.Cu")
		(net "GND")
	)
	(via
		(at 135.994648 -1.524)
		(size 0.7112)
		(drill 0.4064)
		(layers "F.Cu" "B.Cu")
		(net "GND")
	)
	(via
		(at 130.3655 -145.860008)
		(size 0.5588)
		(drill 0.3048)
		(layers "F.Cu" "B.Cu")
		(net "GND")
	)
	(via
		(at 47.607982 -384.47599)
		(size 0.7112)
		(drill 0.4064)
		(layers "F.Cu" "B.Cu")
		(net "GND")
	)
	(via
		(at 44.845732 -211.074)
		(size 0.5588)
		(drill 0.3048)
		(layers "F.Cu" "B.Cu")
		(net "GND")
	)
	(via
		(at 489.926122 -100.07219)
		(size 0.7112)
		(drill 0.4064)
		(layers "F.Cu" "B.Cu")
		(net "GND")
	)
	(via
		(at 90.261948 -21.42998)
		(size 0.5588)
		(drill 0.3048)
		(layers "F.Cu" "B.Cu")
		(net "GND")
	)
	(via
		(at 419.1 -330.2)
		(size 0.5588)
		(drill 0.3048)
		(layers "F.Cu" "B.Cu")
		(net "GND")
	)
	(via
		(at 300.709076 -334.208882)
		(size 0.5588)
		(drill 0.3048)
		(layers "F.Cu" "B.Cu")
		(net "GND")
	)
	(via
		(at 21.694648 -1.524)
		(size 0.7112)
		(drill 0.4064)
		(layers "F.Cu" "B.Cu")
		(net "GND")
	)
	(via
		(at 325.654924 -135.65505)
		(size 0.5588)
		(drill 0.3048)
		(layers "F.Cu" "B.Cu")
		(net "GND")
	)
	(via
		(at 280.6954 -344.17)
		(size 0.5588)
		(drill 0.3048)
		(layers "F.Cu" "B.Cu")
		(net "GND")
	)
	(via
		(at 116.6368 -135.4328)
		(size 0.5588)
		(drill 0.3048)
		(layers "F.Cu" "B.Cu")
		(net "GND")
	)
	(via
		(at 357.205026 -13.035026)
		(size 0.5588)
		(drill 0.3048)
		(layers "F.Cu" "B.Cu")
		(net "GND")
	)
	(via
		(at 1.524 -312.823352)
		(size 0.7112)
		(drill 0.4064)
		(layers "F.Cu" "B.Cu")
		(net "GND")
	)
	(via
		(at 28.304998 -30.815026)
		(size 0.5588)
		(drill 0.3048)
		(layers "F.Cu" "B.Cu")
		(net "GND")
	)
	(via
		(at 474.862398 -216.26703)
		(size 0.5588)
		(drill 0.3048)
		(layers "F.Cu" "B.Cu")
		(net "GND")
	)
	(via
		(at 284.821884 -334.181704)
		(size 0.5588)
		(drill 0.3048)
		(layers "F.Cu" "B.Cu")
		(net "GND")
	)
	(via
		(at 424.9928 -135.9154)
		(size 0.5588)
		(drill 0.3048)
		(layers "F.Cu" "B.Cu")
		(net "GND")
	)
	(via
		(at 475.615 -256.667)
		(size 0.5588)
		(drill 0.3048)
		(layers "F.Cu" "B.Cu")
		(net "GND")
	)
	(via
		(at 124.732796 -165.785038)
		(size 0.5588)
		(drill 0.3048)
		(layers "F.Cu" "B.Cu")
		(net "GND")
	)
	(via
		(at 279.29205 -383.386838)
		(size 0.7112)
		(drill 0.4064)
		(layers "F.Cu" "B.Cu")
		(net "GND")
	)
	(via
		(at 127 -304.8)
		(size 0.5588)
		(drill 0.3048)
		(layers "F.Cu" "B.Cu")
		(net "GND")
	)
	(via
		(at 4.523994 -379.144022)
		(size 0.7112)
		(drill 0.4064)
		(layers "F.Cu" "B.Cu")
		(net "GND")
	)
	(via
		(at 375.099326 -101.49713)
		(size 0.5588)
		(drill 0.3048)
		(layers "F.Cu" "B.Cu")
		(net "GND")
	)
	(via
		(at 270.52397 -61.44133)
		(size 0.7112)
		(drill 0.4064)
		(layers "F.Cu" "B.Cu")
		(net "GND")
	)
	(via
		(at 109.21365 -216.257886)
		(size 0.5588)
		(drill 0.3048)
		(layers "F.Cu" "B.Cu")
		(net "GND")
	)
	(via
		(at 69.954648 -1.524)
		(size 0.7112)
		(drill 0.4064)
		(layers "F.Cu" "B.Cu")
		(net "GND")
	)
	(via
		(at 419.1 -304.8)
		(size 0.5588)
		(drill 0.3048)
		(layers "F.Cu" "B.Cu")
		(net "GND")
	)
	(via
		(at 1.524 -103.273352)
		(size 0.7112)
		(drill 0.4064)
		(layers "F.Cu" "B.Cu")
		(net "GND")
	)
	(via
		(at 376.428 -16.764)
		(size 0.5588)
		(drill 0.3048)
		(layers "F.Cu" "B.Cu")
		(net "GND")
	)
	(via
		(at 489.926122 -164.84219)
		(size 0.7112)
		(drill 0.4064)
		(layers "F.Cu" "B.Cu")
		(net "GND")
	)
	(via
		(at 403.566376 -1.524)
		(size 0.7112)
		(drill 0.4064)
		(layers "F.Cu" "B.Cu")
		(net "GND")
	)
	(via
		(at 249.555 -290.703)
		(size 0.5588)
		(drill 0.3048)
		(layers "F.Cu" "B.Cu")
		(net "GND")
	)
	(via
		(at 322.286376 -1.524)
		(size 0.7112)
		(drill 0.4064)
		(layers "F.Cu" "B.Cu")
		(net "GND")
	)
	(via
		(at 188.064648 -1.524)
		(size 0.7112)
		(drill 0.4064)
		(layers "F.Cu" "B.Cu")
		(net "GND")
	)
	(via
		(at 279.55875 -328.17435)
		(size 0.5588)
		(drill 0.3048)
		(layers "F.Cu" "B.Cu")
		(net "GND")
	)
	(via
		(at 456.4126 -250.7488)
		(size 0.5588)
		(drill 0.3048)
		(layers "F.Cu" "B.Cu")
		(net "GND")
	)
	(via
		(at 426.085 -277.114)
		(size 0.5588)
		(drill 0.3048)
		(layers "F.Cu" "B.Cu")
		(net "GND")
	)
	(via
		(at 368.3 -292.1)
		(size 0.5588)
		(drill 0.3048)
		(layers "F.Cu" "B.Cu")
		(net "GND")
	)
	(via
		(at 1.524 -368.703352)
		(size 0.7112)
		(drill 0.4064)
		(layers "F.Cu" "B.Cu")
		(net "GND")
	)
	(via
		(at 453.574912 -136.838944)
		(size 0.5588)
		(drill 0.3048)
		(layers "F.Cu" "B.Cu")
		(net "GND")
	)
	(via
		(at 30.082998 -122.035062)
		(size 0.5588)
		(drill 0.3048)
		(layers "F.Cu" "B.Cu")
		(net "GND")
	)
	(via
		(at 107.188 -173.736)
		(size 0.5588)
		(drill 0.3048)
		(layers "F.Cu" "B.Cu")
		(net "GND")
	)
	(via
		(at 185.524648 -1.524)
		(size 0.7112)
		(drill 0.4064)
		(layers "F.Cu" "B.Cu")
		(net "GND")
	)
	(via
		(at 357.205026 -135.65505)
		(size 0.5588)
		(drill 0.3048)
		(layers "F.Cu" "B.Cu")
		(net "GND")
	)
	(via
		(at 406.4 -279.4)
		(size 0.5588)
		(drill 0.3048)
		(layers "F.Cu" "B.Cu")
		(net "GND")
	)
	(via
		(at 489.926122 -149.60219)
		(size 0.7112)
		(drill 0.4064)
		(layers "F.Cu" "B.Cu")
		(net "GND")
	)
	(via
		(at 107.61599 -378.476002)
		(size 0.7112)
		(drill 0.4064)
		(layers "F.Cu" "B.Cu")
		(net "GND")
	)
	(via
		(at 197.47611 -41.642538)
		(size 0.7112)
		(drill 0.4064)
		(layers "F.Cu" "B.Cu")
		(net "GND")
	)
	(via
		(at 404.876 -128.524)
		(size 0.5588)
		(drill 0.3048)
		(layers "F.Cu" "B.Cu")
		(net "GND")
	)
	(via
		(at 486.925874 -374.430036)
		(size 0.7112)
		(drill 0.4064)
		(layers "F.Cu" "B.Cu")
		(net "GND")
	)
	(via
		(at 16.685768 -99.615498)
		(size 0.5588)
		(drill 0.3048)
		(layers "F.Cu" "B.Cu")
		(net "GND")
	)
	(via
		(at 418.592 -53.848)
		(size 0.5588)
		(drill 0.3048)
		(layers "F.Cu" "B.Cu")
		(net "GND")
	)
	(via
		(at 1.524 -218.843352)
		(size 0.7112)
		(drill 0.4064)
		(layers "F.Cu" "B.Cu")
		(net "GND")
	)
	(via
		(at 1.524 -246.783352)
		(size 0.7112)
		(drill 0.4064)
		(layers "F.Cu" "B.Cu")
		(net "GND")
	)
	(via
		(at 485.182926 -50.785014)
		(size 0.5588)
		(drill 0.3048)
		(layers "F.Cu" "B.Cu")
		(net "GND")
	)
	(via
		(at 166.474648 -1.524)
		(size 0.7112)
		(drill 0.4064)
		(layers "F.Cu" "B.Cu")
		(net "GND")
	)
	(via
		(at 12.7 -342.9)
		(size 0.5588)
		(drill 0.3048)
		(layers "F.Cu" "B.Cu")
		(net "GND")
	)
	(via
		(at 66.438018 -103.984044)
		(size 0.5588)
		(drill 0.3048)
		(layers "F.Cu" "B.Cu")
		(net "GND")
	)
	(via
		(at 210.018122 -102.691184)
		(size 0.7112)
		(drill 0.4064)
		(layers "F.Cu" "B.Cu")
		(net "GND")
	)
	(via
		(at 456.185016 -384.429)
		(size 0.7112)
		(drill 0.4064)
		(layers "F.Cu" "B.Cu")
		(net "GND")
	)
	(via
		(at 482.6 -317.5)
		(size 0.5588)
		(drill 0.3048)
		(layers "F.Cu" "B.Cu")
		(net "GND")
	)
	(via
		(at 124.732796 -7.035038)
		(size 0.5588)
		(drill 0.3048)
		(layers "F.Cu" "B.Cu")
		(net "GND")
	)
	(via
		(at 271.458436 -49.724056)
		(size 0.7112)
		(drill 0.4064)
		(layers "F.Cu" "B.Cu")
		(net "GND")
	)
	(via
		(at 239.649 -313.182)
		(size 0.5588)
		(drill 0.3048)
		(layers "F.Cu" "B.Cu")
		(net "GND")
	)
	(via
		(at 305.662076 -342.077802)
		(size 0.5588)
		(drill 0.3048)
		(layers "F.Cu" "B.Cu")
		(net "GND")
	)
	(via
		(at 158.496 -30.3276)
		(size 0.5588)
		(drill 0.3048)
		(layers "F.Cu" "B.Cu")
		(net "GND")
	)
	(via
		(at 489.926122 -97.53219)
		(size 0.7112)
		(drill 0.4064)
		(layers "F.Cu" "B.Cu")
		(net "GND")
	)
	(via
		(at 489.926122 -88.64219)
		(size 0.7112)
		(drill 0.4064)
		(layers "F.Cu" "B.Cu")
		(net "GND")
	)
	(via
		(at 1.524 -305.203352)
		(size 0.7112)
		(drill 0.4064)
		(layers "F.Cu" "B.Cu")
		(net "GND")
	)
	(via
		(at 424.425872 -384.47599)
		(size 0.7112)
		(drill 0.4064)
		(layers "F.Cu" "B.Cu")
		(net "GND")
	)
	(via
		(at 254.428498 -282.320746)
		(size 0.5588)
		(drill 0.3048)
		(layers "F.Cu" "B.Cu")
		(net "GND")
	)
	(via
		(at 6.604 -230.632)
		(size 0.5588)
		(drill 0.3048)
		(layers "F.Cu" "B.Cu")
		(net "GND")
	)
	(via
		(at 28.304998 -250.655074)
		(size 0.5588)
		(drill 0.3048)
		(layers "F.Cu" "B.Cu")
		(net "GND")
	)
	(via
		(at 280.6954 -343.154)
		(size 0.5588)
		(drill 0.3048)
		(layers "F.Cu" "B.Cu")
		(net "GND")
	)
	(via
		(at 489.926122 -218.18219)
		(size 0.7112)
		(drill 0.4064)
		(layers "F.Cu" "B.Cu")
		(net "GND")
	)
	(via
		(at 383.54 -123.952)
		(size 0.5588)
		(drill 0.3048)
		(layers "F.Cu" "B.Cu")
		(net "GND")
	)
	(via
		(at 489.926122 -22.60219)
		(size 0.7112)
		(drill 0.4064)
		(layers "F.Cu" "B.Cu")
		(net "GND")
	)
	(via
		(at 414.528 -164.592)
		(size 0.5588)
		(drill 0.3048)
		(layers "F.Cu" "B.Cu")
		(net "GND")
	)
	(via
		(at 1.524 -282.343352)
		(size 0.7112)
		(drill 0.4064)
		(layers "F.Cu" "B.Cu")
		(net "GND")
	)
	(via
		(at 1.524 -347.113352)
		(size 0.7112)
		(drill 0.4064)
		(layers "F.Cu" "B.Cu")
		(net "GND")
	)
	(via
		(at 489.926122 -196.59219)
		(size 0.7112)
		(drill 0.4064)
		(layers "F.Cu" "B.Cu")
		(net "GND")
	)
	(via
		(at 85.194648 -1.524)
		(size 0.7112)
		(drill 0.4064)
		(layers "F.Cu" "B.Cu")
		(net "GND")
	)
	(via
		(at 365.252 -268.224)
		(size 0.5588)
		(drill 0.3048)
		(layers "F.Cu" "B.Cu")
		(net "GND")
	)
	(via
		(at 1.524 -287.423352)
		(size 0.7112)
		(drill 0.4064)
		(layers "F.Cu" "B.Cu")
		(net "GND")
	)
	(via
		(at 312.523886 -22.24151)
		(size 0.7112)
		(drill 0.4064)
		(layers "F.Cu" "B.Cu")
		(net "GND")
	)
	(via
		(at 59.854846 -145.81505)
		(size 0.5588)
		(drill 0.3048)
		(layers "F.Cu" "B.Cu")
		(net "GND")
	)
	(via
		(at 286.460692 -384.47599)
		(size 0.7112)
		(drill 0.4064)
		(layers "F.Cu" "B.Cu")
		(net "GND")
	)
	(via
		(at 481.777802 -230.51135)
		(size 0.5588)
		(drill 0.3048)
		(layers "F.Cu" "B.Cu")
		(net "GND")
	)
	(via
		(at 184.912 -253.830074)
		(size 0.5588)
		(drill 0.3048)
		(layers "F.Cu" "B.Cu")
		(net "GND")
	)
	(via
		(at 320.792856 -101.719126)
		(size 0.5588)
		(drill 0.3048)
		(layers "F.Cu" "B.Cu")
		(net "GND")
	)
	(via
		(at 76.58735 -216.8144)
		(size 0.5588)
		(drill 0.3048)
		(layers "F.Cu" "B.Cu")
		(net "GND")
	)
	(via
		(at 195.684648 -1.524)
		(size 0.7112)
		(drill 0.4064)
		(layers "F.Cu" "B.Cu")
		(net "GND")
	)
	(via
		(at 1.524 -357.273352)
		(size 0.7112)
		(drill 0.4064)
		(layers "F.Cu" "B.Cu")
		(net "GND")
	)
	(via
		(at 205.141322 -101.446584)
		(size 0.7112)
		(drill 0.4064)
		(layers "F.Cu" "B.Cu")
		(net "GND")
	)
	(via
		(at 489.926122 -238.50219)
		(size 0.7112)
		(drill 0.4064)
		(layers "F.Cu" "B.Cu")
		(net "GND")
	)
	(via
		(at 1.524 -198.523352)
		(size 0.7112)
		(drill 0.4064)
		(layers "F.Cu" "B.Cu")
		(net "GND")
	)
	(via
		(at 323.596 -333.756)
		(size 0.5588)
		(drill 0.3048)
		(layers "F.Cu" "B.Cu")
		(net "GND")
	)
	(via
		(at 98.72599 -378.476002)
		(size 0.7112)
		(drill 0.4064)
		(layers "F.Cu" "B.Cu")
		(net "GND")
	)
	(via
		(at 218.354656 -173.590712)
		(size 0.5588)
		(drill 0.3048)
		(layers "F.Cu" "B.Cu")
		(net "GND")
	)
	(via
		(at 426.965872 -384.47599)
		(size 0.7112)
		(drill 0.4064)
		(layers "F.Cu" "B.Cu")
		(net "GND")
	)
	(via
		(at 79.676752 -344.864944)
		(size 0.5588)
		(drill 0.3048)
		(layers "F.Cu" "B.Cu")
		(net "GND")
	)
	(via
		(at 67.927982 -384.47599)
		(size 0.7112)
		(drill 0.4064)
		(layers "F.Cu" "B.Cu")
		(net "GND")
	)
	(via
		(at 248.107962 -378.476002)
		(size 0.7112)
		(drill 0.4064)
		(layers "F.Cu" "B.Cu")
		(net "GND")
	)
	(via
		(at 231.597962 -378.476002)
		(size 0.7112)
		(drill 0.4064)
		(layers "F.Cu" "B.Cu")
		(net "GND")
	)
	(via
		(at 1.524 -354.733352)
		(size 0.7112)
		(drill 0.4064)
		(layers "F.Cu" "B.Cu")
		(net "GND")
	)
	(via
		(at 95.19412 -359.816146)
		(size 0.7112)
		(drill 0.4064)
		(layers "F.Cu" "B.Cu")
		(net "GND")
	)
	(via
		(at 81.661 -33.782)
		(size 0.5588)
		(drill 0.3048)
		(layers "F.Cu" "B.Cu")
		(net "GND")
	)
	(via
		(at 1.524 -202.333352)
		(size 0.7112)
		(drill 0.4064)
		(layers "F.Cu" "B.Cu")
		(net "GND")
	)
	(via
		(at 134.603998 -384.47599)
		(size 0.7112)
		(drill 0.4064)
		(layers "F.Cu" "B.Cu")
		(net "GND")
	)
	(via
		(at 59.854846 -38.435026)
		(size 0.5588)
		(drill 0.3048)
		(layers "F.Cu" "B.Cu")
		(net "GND")
	)
	(via
		(at 483.576376 -1.524)
		(size 0.7112)
		(drill 0.4064)
		(layers "F.Cu" "B.Cu")
		(net "GND")
	)
	(via
		(at 421.346376 -1.524)
		(size 0.7112)
		(drill 0.4064)
		(layers "F.Cu" "B.Cu")
		(net "GND")
	)
	(via
		(at 4.523994 -380.414022)
		(size 0.7112)
		(drill 0.4064)
		(layers "F.Cu" "B.Cu")
		(net "GND")
	)
	(via
		(at 1.524 -13.103352)
		(size 0.7112)
		(drill 0.4064)
		(layers "F.Cu" "B.Cu")
		(net "GND")
	)
	(via
		(at 22.606 -222.885)
		(size 0.5588)
		(drill 0.3048)
		(layers "F.Cu" "B.Cu")
		(net "GND")
	)
	(via
		(at 153.361898 -21.42998)
		(size 0.5588)
		(drill 0.3048)
		(layers "F.Cu" "B.Cu")
		(net "GND")
	)
	(via
		(at 294.080692 -384.47599)
		(size 0.7112)
		(drill 0.4064)
		(layers "F.Cu" "B.Cu")
		(net "GND")
	)
	(via
		(at 261.986522 -362.432346)
		(size 0.5588)
		(drill 0.3048)
		(layers "F.Cu" "B.Cu")
		(net "GND")
	)
	(via
		(at 1.524 -10.563352)
		(size 0.7112)
		(drill 0.4064)
		(layers "F.Cu" "B.Cu")
		(net "GND")
	)
	(via
		(at 1.524 -127.403352)
		(size 0.7112)
		(drill 0.4064)
		(layers "F.Cu" "B.Cu")
		(net "GND")
	)
	(via
		(at 428.117 -162.179)
		(size 0.5588)
		(drill 0.3048)
		(layers "F.Cu" "B.Cu")
		(net "GND")
	)
	(via
		(at 489.926122 -360.42219)
		(size 0.7112)
		(drill 0.4064)
		(layers "F.Cu" "B.Cu")
		(net "GND")
	)
	(via
		(at 373.307864 -378.476002)
		(size 0.7112)
		(drill 0.4064)
		(layers "F.Cu" "B.Cu")
		(net "GND")
	)
	(via
		(at 110.15599 -378.476002)
		(size 0.7112)
		(drill 0.4064)
		(layers "F.Cu" "B.Cu")
		(net "GND")
	)
	(via
		(at 87.29599 -378.476002)
		(size 0.7112)
		(drill 0.4064)
		(layers "F.Cu" "B.Cu")
		(net "GND")
	)
	(via
		(at 396.875 -268.224)
		(size 0.5588)
		(drill 0.3048)
		(layers "F.Cu" "B.Cu")
		(net "GND")
	)
	(via
		(at 1.524 -114.703352)
		(size 0.7112)
		(drill 0.4064)
		(layers "F.Cu" "B.Cu")
		(net "GND")
	)
	(via
		(at 146.154648 -1.524)
		(size 0.7112)
		(drill 0.4064)
		(layers "F.Cu" "B.Cu")
		(net "GND")
	)
	(via
		(at 127.104648 -1.524)
		(size 0.7112)
		(drill 0.4064)
		(layers "F.Cu" "B.Cu")
		(net "GND")
	)
	(via
		(at 45.847 -146.304)
		(size 0.5588)
		(drill 0.3048)
		(layers "F.Cu" "B.Cu")
		(net "GND")
	)
	(via
		(at 65.387982 -384.47599)
		(size 0.7112)
		(drill 0.4064)
		(layers "F.Cu" "B.Cu")
		(net "GND")
	)
	(via
		(at 88.667844 -333.554832)
		(size 0.5588)
		(drill 0.3048)
		(layers "F.Cu" "B.Cu")
		(net "GND")
	)
	(via
		(at 457.2 -342.9)
		(size 0.5588)
		(drill 0.3048)
		(layers "F.Cu" "B.Cu")
		(net "GND")
	)
	(via
		(at 257.334004 -384.457956)
		(size 0.7112)
		(drill 0.4064)
		(layers "F.Cu" "B.Cu")
		(net "GND")
	)
	(via
		(at 357.205026 -30.815026)
		(size 0.5588)
		(drill 0.3048)
		(layers "F.Cu" "B.Cu")
		(net "GND")
	)
	(via
		(at 197.47611 -14.972538)
		(size 0.7112)
		(drill 0.4064)
		(layers "F.Cu" "B.Cu")
		(net "GND")
	)
	(via
		(at 489.926122 -54.35219)
		(size 0.7112)
		(drill 0.4064)
		(layers "F.Cu" "B.Cu")
		(net "GND")
	)
	(via
		(at 39.9796 -9.0932)
		(size 0.5588)
		(drill 0.3048)
		(layers "F.Cu" "B.Cu")
		(net "GND")
	)
	(via
		(at 146.033998 -384.47599)
		(size 0.7112)
		(drill 0.4064)
		(layers "F.Cu" "B.Cu")
		(net "GND")
	)
	(via
		(at 420.304976 -270.975074)
		(size 0.5588)
		(drill 0.3048)
		(layers "F.Cu" "B.Cu")
		(net "GND")
	)
	(via
		(at 288.544 -96.012)
		(size 0.5588)
		(drill 0.3048)
		(layers "F.Cu" "B.Cu")
		(net "GND")
	)
	(via
		(at 174.0535 -255.016)
		(size 0.5588)
		(drill 0.3048)
		(layers "F.Cu" "B.Cu")
		(net "GND")
	)
	(via
		(at 25.908 -111.76)
		(size 0.5588)
		(drill 0.3048)
		(layers "F.Cu" "B.Cu")
		(net "GND")
	)
	(via
		(at 489.926122 -289.30219)
		(size 0.7112)
		(drill 0.4064)
		(layers "F.Cu" "B.Cu")
		(net "GND")
	)
	(via
		(at 141.224 -39.624)
		(size 0.5588)
		(drill 0.3048)
		(layers "F.Cu" "B.Cu")
		(net "GND")
	)
	(via
		(at 177.673 -20.955)
		(size 0.5588)
		(drill 0.3048)
		(layers "F.Cu" "B.Cu")
		(net "GND")
	)
	(via
		(at 284.158436 -49.724056)
		(size 0.7112)
		(drill 0.4064)
		(layers "F.Cu" "B.Cu")
		(net "GND")
	)
	(via
		(at 232.55732 -217.78468)
		(size 0.5588)
		(drill 0.3048)
		(layers "F.Cu" "B.Cu")
		(net "GND")
	)
	(via
		(at 139.683998 -384.47599)
		(size 0.7112)
		(drill 0.4064)
		(layers "F.Cu" "B.Cu")
		(net "GND")
	)
	(via
		(at 470.2556 -158.4452)
		(size 0.5588)
		(drill 0.3048)
		(layers "F.Cu" "B.Cu")
		(net "GND")
	)
	(via
		(at 325.654924 -128.03505)
		(size 0.5588)
		(drill 0.3048)
		(layers "F.Cu" "B.Cu")
		(net "GND")
	)
	(via
		(at 469.9 -342.9)
		(size 0.5588)
		(drill 0.3048)
		(layers "F.Cu" "B.Cu")
		(net "GND")
	)
	(via
		(at 118.625366 -155.13685)
		(size 0.5588)
		(drill 0.3048)
		(layers "F.Cu" "B.Cu")
		(net "GND")
	)
	(via
		(at 228.6 -368.3)
		(size 0.5588)
		(drill 0.3048)
		(layers "F.Cu" "B.Cu")
		(net "GND")
	)
	(via
		(at 90.932 -80.772)
		(size 0.5588)
		(drill 0.3048)
		(layers "F.Cu" "B.Cu")
		(net "GND")
	)
	(via
		(at 309.140606 -214.930228)
		(size 0.5588)
		(drill 0.3048)
		(layers "F.Cu" "B.Cu")
		(net "GND")
	)
	(via
		(at 366.957864 -378.476002)
		(size 0.7112)
		(drill 0.4064)
		(layers "F.Cu" "B.Cu")
		(net "GND")
	)
	(via
		(at 453.632824 -122.035062)
		(size 0.5588)
		(drill 0.3048)
		(layers "F.Cu" "B.Cu")
		(net "GND")
	)
	(via
		(at 483.404926 -30.815026)
		(size 0.5588)
		(drill 0.3048)
		(layers "F.Cu" "B.Cu")
		(net "GND")
	)
	(via
		(at 196.476112 -383.708148)
		(size 0.7112)
		(drill 0.4064)
		(layers "F.Cu" "B.Cu")
		(net "GND")
	)
	(via
		(at 1.524 -207.413352)
		(size 0.7112)
		(drill 0.4064)
		(layers "F.Cu" "B.Cu")
		(net "GND")
	)
	(via
		(at 222.707962 -378.476002)
		(size 0.7112)
		(drill 0.4064)
		(layers "F.Cu" "B.Cu")
		(net "GND")
	)
	(via
		(at 82.13852 -149.720808)
		(size 0.5588)
		(drill 0.3048)
		(layers "F.Cu" "B.Cu")
		(net "GND")
	)
	(via
		(at 459.1558 -244.856)
		(size 0.5588)
		(drill 0.3048)
		(layers "F.Cu" "B.Cu")
		(net "GND")
	)
	(via
		(at 20.701 -26.67)
		(size 0.5588)
		(drill 0.3048)
		(layers "F.Cu" "B.Cu")
		(net "GND")
	)
	(via
		(at 394.676376 -1.524)
		(size 0.7112)
		(drill 0.4064)
		(layers "F.Cu" "B.Cu")
		(net "GND")
	)
	(via
		(at 312.523886 -23.51151)
		(size 0.7112)
		(drill 0.4064)
		(layers "F.Cu" "B.Cu")
		(net "GND")
	)
	(via
		(at 489.926122 -55.62219)
		(size 0.7112)
		(drill 0.4064)
		(layers "F.Cu" "B.Cu")
		(net "GND")
	)
	(via
		(at 482.6 -292.1)
		(size 0.5588)
		(drill 0.3048)
		(layers "F.Cu" "B.Cu")
		(net "GND")
	)
	(via
		(at 489.926122 -14.98219)
		(size 0.7112)
		(drill 0.4064)
		(layers "F.Cu" "B.Cu")
		(net "GND")
	)
	(via
		(at 370.205 -73.406)
		(size 0.5588)
		(drill 0.3048)
		(layers "F.Cu" "B.Cu")
		(net "GND")
	)
	(via
		(at 284.000448 -346.271342)
		(size 0.5588)
		(drill 0.3048)
		(layers "F.Cu" "B.Cu")
		(net "GND")
	)
	(via
		(at 475.1832 -247.1674)
		(size 0.5588)
		(drill 0.3048)
		(layers "F.Cu" "B.Cu")
		(net "GND")
	)
	(via
		(at 1.524 -161.693352)
		(size 0.7112)
		(drill 0.4064)
		(layers "F.Cu" "B.Cu")
		(net "GND")
	)
	(via
		(at 1.524 -293.773352)
		(size 0.7112)
		(drill 0.4064)
		(layers "F.Cu" "B.Cu")
		(net "GND")
	)
	(via
		(at 144.7546 -148.717)
		(size 0.5588)
		(drill 0.3048)
		(layers "F.Cu" "B.Cu")
		(net "GND")
	)
	(via
		(at 36.576 -22.352)
		(size 0.5588)
		(drill 0.3048)
		(layers "F.Cu" "B.Cu")
		(net "GND")
	)
	(via
		(at 312.9534 -342.077802)
		(size 0.5588)
		(drill 0.3048)
		(layers "F.Cu" "B.Cu")
		(net "GND")
	)
	(via
		(at 64.151256 -105.031286)
		(size 0.5588)
		(drill 0.3048)
		(layers "F.Cu" "B.Cu")
		(net "GND")
	)
	(via
		(at 7.724648 -1.524)
		(size 0.7112)
		(drill 0.4064)
		(layers "F.Cu" "B.Cu")
		(net "GND")
	)
	(via
		(at 82.216752 -344.864944)
		(size 0.5588)
		(drill 0.3048)
		(layers "F.Cu" "B.Cu")
		(net "GND")
	)
	(via
		(at 311.3024 -93.6498)
		(size 0.5588)
		(drill 0.3048)
		(layers "F.Cu" "B.Cu")
		(net "GND")
	)
	(via
		(at 47.094648 -1.524)
		(size 0.7112)
		(drill 0.4064)
		(layers "F.Cu" "B.Cu")
		(net "GND")
	)
	(via
		(at 395.4018 -11.43)
		(size 0.5588)
		(drill 0.3048)
		(layers "F.Cu" "B.Cu")
		(net "GND")
	)
	(via
		(at 1.524 -105.813352)
		(size 0.7112)
		(drill 0.4064)
		(layers "F.Cu" "B.Cu")
		(net "GND")
	)
	(via
		(at 263.040876 -196.032882)
		(size 0.7112)
		(drill 0.4064)
		(layers "F.Cu" "B.Cu")
		(net "GND")
	)
	(via
		(at 361.188 -24.892)
		(size 0.5588)
		(drill 0.3048)
		(layers "F.Cu" "B.Cu")
		(net "GND")
	)
	(via
		(at 416.052 -274.828)
		(size 0.5588)
		(drill 0.3048)
		(layers "F.Cu" "B.Cu")
		(net "GND")
	)
	(via
		(at 9.652 -167.64)
		(size 0.5588)
		(drill 0.3048)
		(layers "F.Cu" "B.Cu")
		(net "GND")
	)
	(via
		(at 160.124648 -1.524)
		(size 0.7112)
		(drill 0.4064)
		(layers "F.Cu" "B.Cu")
		(net "GND")
	)
	(via
		(at 197.47611 -13.702538)
		(size 0.7112)
		(drill 0.4064)
		(layers "F.Cu" "B.Cu")
		(net "GND")
	)
	(via
		(at 394.462 -8.89)
		(size 0.5588)
		(drill 0.3048)
		(layers "F.Cu" "B.Cu")
		(net "GND")
	)
	(via
		(at 24.234648 -1.524)
		(size 0.7112)
		(drill 0.4064)
		(layers "F.Cu" "B.Cu")
		(net "GND")
	)
	(via
		(at 43.797982 -384.47599)
		(size 0.7112)
		(drill 0.4064)
		(layers "F.Cu" "B.Cu")
		(net "GND")
	)
	(via
		(at 1.524 -356.003352)
		(size 0.7112)
		(drill 0.4064)
		(layers "F.Cu" "B.Cu")
		(net "GND")
	)
	(via
		(at 483.404926 -153.43505)
		(size 0.5588)
		(drill 0.3048)
		(layers "F.Cu" "B.Cu")
		(net "GND")
	)
	(via
		(at 28.044648 -1.524)
		(size 0.7112)
		(drill 0.4064)
		(layers "F.Cu" "B.Cu")
		(net "GND")
	)
	(via
		(at 329.809856 -384.47599)
		(size 0.7112)
		(drill 0.4064)
		(layers "F.Cu" "B.Cu")
		(net "GND")
	)
	(via
		(at 311.999376 -216.497154)
		(size 0.5588)
		(drill 0.3048)
		(layers "F.Cu" "B.Cu")
		(net "GND")
	)
	(via
		(at 244.0686 -305.7144)
		(size 0.5588)
		(drill 0.3048)
		(layers "F.Cu" "B.Cu")
		(net "GND")
	)
	(via
		(at 108.839 -261.239)
		(size 0.5588)
		(drill 0.3048)
		(layers "F.Cu" "B.Cu")
		(net "GND")
	)
	(via
		(at 197.47611 -34.022538)
		(size 0.7112)
		(drill 0.4064)
		(layers "F.Cu" "B.Cu")
		(net "GND")
	)
	(via
		(at 471.235024 -380.775972)
		(size 0.7112)
		(drill 0.4064)
		(layers "F.Cu" "B.Cu")
		(net "GND")
	)
	(via
		(at 299.72 -215.392)
		(size 0.5588)
		(drill 0.3048)
		(layers "F.Cu" "B.Cu")
		(net "GND")
	)
	(via
		(at 39.474648 -1.524)
		(size 0.7112)
		(drill 0.4064)
		(layers "F.Cu" "B.Cu")
		(net "GND")
	)
	(via
		(at 51.417982 -384.47599)
		(size 0.7112)
		(drill 0.4064)
		(layers "F.Cu" "B.Cu")
		(net "GND")
	)
	(via
		(at 177.8762 -18.2118)
		(size 0.5588)
		(drill 0.3048)
		(layers "F.Cu" "B.Cu")
		(net "GND")
	)
	(via
		(at 181.356 -60.96)
		(size 0.5588)
		(drill 0.3048)
		(layers "F.Cu" "B.Cu")
		(net "GND")
	)
	(via
		(at 388.754874 -243.035074)
		(size 0.5588)
		(drill 0.3048)
		(layers "F.Cu" "B.Cu")
		(net "GND")
	)
	(via
		(at 262.6614 -381.143256)
		(size 0.5588)
		(drill 0.3048)
		(layers "F.Cu" "B.Cu")
		(net "GND")
	)
	(via
		(at 1.524 -39.773352)
		(size 0.7112)
		(drill 0.4064)
		(layers "F.Cu" "B.Cu")
		(net "GND")
	)
	(via
		(at 120.31599 -378.476002)
		(size 0.7112)
		(drill 0.4064)
		(layers "F.Cu" "B.Cu")
		(net "GND")
	)
	(via
		(at 489.926122 -190.24219)
		(size 0.7112)
		(drill 0.4064)
		(layers "F.Cu" "B.Cu")
		(net "GND")
	)
	(via
		(at 370.546376 -1.524)
		(size 0.7112)
		(drill 0.4064)
		(layers "F.Cu" "B.Cu")
		(net "GND")
	)
	(via
		(at 489.926122 -58.16219)
		(size 0.7112)
		(drill 0.4064)
		(layers "F.Cu" "B.Cu")
		(net "GND")
	)
	(via
		(at 420.304976 -148.35505)
		(size 0.5588)
		(drill 0.3048)
		(layers "F.Cu" "B.Cu")
		(net "GND")
	)
	(via
		(at 438.395872 -384.47599)
		(size 0.7112)
		(drill 0.4064)
		(layers "F.Cu" "B.Cu")
		(net "GND")
	)
	(via
		(at 419.914324 -34.177986)
		(size 0.5588)
		(drill 0.3048)
		(layers "F.Cu" "B.Cu")
		(net "GND")
	)
	(via
		(at 334.645 -135.509)
		(size 0.5588)
		(drill 0.3048)
		(layers "F.Cu" "B.Cu")
		(net "GND")
	)
	(via
		(at 197.47611 -30.212538)
		(size 0.7112)
		(drill 0.4064)
		(layers "F.Cu" "B.Cu")
		(net "GND")
	)
	(via
		(at 312.523886 -27.32151)
		(size 0.7112)
		(drill 0.4064)
		(layers "F.Cu" "B.Cu")
		(net "GND")
	)
	(via
		(at 321.252596 -373.5578)
		(size 0.5588)
		(drill 0.3048)
		(layers "F.Cu" "B.Cu")
		(net "GND")
	)
	(via
		(at 62.847982 -384.47599)
		(size 0.7112)
		(drill 0.4064)
		(layers "F.Cu" "B.Cu")
		(net "GND")
	)
	(via
		(at 489.926122 -74.67219)
		(size 0.7112)
		(drill 0.4064)
		(layers "F.Cu" "B.Cu")
		(net "GND")
	)
	(via
		(at 12.7 -50.8)
		(size 0.5588)
		(drill 0.3048)
		(layers "F.Cu" "B.Cu")
		(net "GND")
	)
	(via
		(at 446.015872 -384.47599)
		(size 0.7112)
		(drill 0.4064)
		(layers "F.Cu" "B.Cu")
		(net "GND")
	)
	(via
		(at 425.196 -358.14)
		(size 0.5588)
		(drill 0.3048)
		(layers "F.Cu" "B.Cu")
		(net "GND")
	)
	(via
		(at 489.926122 -185.16219)
		(size 0.7112)
		(drill 0.4064)
		(layers "F.Cu" "B.Cu")
		(net "GND")
	)
	(via
		(at 448.098672 -102.997254)
		(size 0.5588)
		(drill 0.3048)
		(layers "F.Cu" "B.Cu")
		(net "GND")
	)
	(via
		(at 357.205026 -40.975026)
		(size 0.5588)
		(drill 0.3048)
		(layers "F.Cu" "B.Cu")
		(net "GND")
	)
	(via
		(at 210.018122 -103.910384)
		(size 0.7112)
		(drill 0.4064)
		(layers "F.Cu" "B.Cu")
		(net "GND")
	)
	(via
		(at 1.524 -350.923352)
		(size 0.7112)
		(drill 0.4064)
		(layers "F.Cu" "B.Cu")
		(net "GND")
	)
	(via
		(at 140.208 -174.244)
		(size 0.5588)
		(drill 0.3048)
		(layers "F.Cu" "B.Cu")
		(net "GND")
	)
	(via
		(at 422.0972 -237.0836)
		(size 0.5588)
		(drill 0.3048)
		(layers "F.Cu" "B.Cu")
		(net "GND")
	)
	(via
		(at 68.072 -138.176)
		(size 0.5588)
		(drill 0.3048)
		(layers "F.Cu" "B.Cu")
		(net "GND")
	)
	(via
		(at 102.53599 -378.476002)
		(size 0.7112)
		(drill 0.4064)
		(layers "F.Cu" "B.Cu")
		(net "GND")
	)
	(via
		(at 1.524 -110.893352)
		(size 0.7112)
		(drill 0.4064)
		(layers "F.Cu" "B.Cu")
		(net "GND")
	)
	(via
		(at 473.416376 -1.524)
		(size 0.7112)
		(drill 0.4064)
		(layers "F.Cu" "B.Cu")
		(net "GND")
	)
	(via
		(at 166.660068 -211.234528)
		(size 0.5588)
		(drill 0.3048)
		(layers "F.Cu" "B.Cu")
		(net "GND")
	)
	(via
		(at 304.478436 -49.724056)
		(size 0.7112)
		(drill 0.4064)
		(layers "F.Cu" "B.Cu")
		(net "GND")
	)
	(via
		(at 489.926122 -253.74219)
		(size 0.7112)
		(drill 0.4064)
		(layers "F.Cu" "B.Cu")
		(net "GND")
	)
	(via
		(at 20.701 -141.605)
		(size 0.5588)
		(drill 0.3048)
		(layers "F.Cu" "B.Cu")
		(net "GND")
	)
	(via
		(at 478.3074 -250.1265)
		(size 0.5588)
		(drill 0.3048)
		(layers "F.Cu" "B.Cu")
		(net "GND")
	)
	(via
		(at 446.024 -164.084)
		(size 0.5588)
		(drill 0.3048)
		(layers "F.Cu" "B.Cu")
		(net "GND")
	)
	(via
		(at 318.516 -189.992)
		(size 0.5588)
		(drill 0.3048)
		(layers "F.Cu" "B.Cu")
		(net "GND")
	)
	(via
		(at 146.812 -13.208)
		(size 0.5588)
		(drill 0.3048)
		(layers "F.Cu" "B.Cu")
		(net "GND")
	)
	(via
		(at 489.926122 -223.26219)
		(size 0.7112)
		(drill 0.4064)
		(layers "F.Cu" "B.Cu")
		(net "GND")
	)
	(via
		(at 458.298804 -376.047)
		(size 0.5588)
		(drill 0.3048)
		(layers "F.Cu" "B.Cu")
		(net "GND")
	)
	(via
		(at 402.907246 -96.310704)
		(size 0.5588)
		(drill 0.3048)
		(layers "F.Cu" "B.Cu")
		(net "GND")
	)
	(via
		(at 197.47611 -37.832538)
		(size 0.7112)
		(drill 0.4064)
		(layers "F.Cu" "B.Cu")
		(net "GND")
	)
	(via
		(at 44.554648 -1.524)
		(size 0.7112)
		(drill 0.4064)
		(layers "F.Cu" "B.Cu")
		(net "GND")
	)
	(via
		(at 1.524 -159.153352)
		(size 0.7112)
		(drill 0.4064)
		(layers "F.Cu" "B.Cu")
		(net "GND")
	)
	(via
		(at 1.524 -264.563352)
		(size 0.7112)
		(drill 0.4064)
		(layers "F.Cu" "B.Cu")
		(net "GND")
	)
	(via
		(at 79.676752 -339.784944)
		(size 0.5588)
		(drill 0.3048)
		(layers "F.Cu" "B.Cu")
		(net "GND")
	)
	(via
		(at 489.926122 -128.01219)
		(size 0.7112)
		(drill 0.4064)
		(layers "F.Cu" "B.Cu")
		(net "GND")
	)
	(via
		(at 440.396376 -1.524)
		(size 0.7112)
		(drill 0.4064)
		(layers "F.Cu" "B.Cu")
		(net "GND")
	)
	(via
		(at 253.524004 -383.187956)
		(size 0.7112)
		(drill 0.4064)
		(layers "F.Cu" "B.Cu")
		(net "GND")
	)
	(via
		(at 35.7505 -261.239)
		(size 0.5588)
		(drill 0.3048)
		(layers "F.Cu" "B.Cu")
		(net "GND")
	)
	(via
		(at 18.4404 -263.7536)
		(size 0.5588)
		(drill 0.3048)
		(layers "F.Cu" "B.Cu")
		(net "GND")
	)
	(via
		(at 207.6704 -142.8242)
		(size 0.7112)
		(drill 0.4064)
		(layers "F.Cu" "B.Cu")
		(net "GND")
	)
	(via
		(at 18.5166 -33.782)
		(size 0.5588)
		(drill 0.3048)
		(layers "F.Cu" "B.Cu")
		(net "GND")
	)
	(via
		(at 184.819544 -23.833836)
		(size 0.5588)
		(drill 0.3048)
		(layers "F.Cu" "B.Cu")
		(net "GND")
	)
	(via
		(at 387.611874 -21.42998)
		(size 0.5588)
		(drill 0.3048)
		(layers "F.Cu" "B.Cu")
		(net "GND")
	)
	(via
		(at 159.004 -35.56)
		(size 0.5588)
		(drill 0.3048)
		(layers "F.Cu" "B.Cu")
		(net "GND")
	)
	(via
		(at 397.764 -196.088)
		(size 0.5588)
		(drill 0.3048)
		(layers "F.Cu" "B.Cu")
		(net "GND")
	)
	(via
		(at 225.749104 -356.165912)
		(size 0.5588)
		(drill 0.3048)
		(layers "F.Cu" "B.Cu")
		(net "GND")
	)
	(via
		(at 299.160692 -384.47599)
		(size 0.7112)
		(drill 0.4064)
		(layers "F.Cu" "B.Cu")
		(net "GND")
	)
	(via
		(at 60.191396 -361.95)
		(size 0.7112)
		(drill 0.4064)
		(layers "F.Cu" "B.Cu")
		(net "GND")
	)
	(via
		(at 1.524 -25.803352)
		(size 0.7112)
		(drill 0.4064)
		(layers "F.Cu" "B.Cu")
		(net "GND")
	)
	(via
		(at 1.524 -314.093352)
		(size 0.7112)
		(drill 0.4064)
		(layers "F.Cu" "B.Cu")
		(net "GND")
	)
	(via
		(at 489.926122 -324.86219)
		(size 0.7112)
		(drill 0.4064)
		(layers "F.Cu" "B.Cu")
		(net "GND")
	)
	(via
		(at 325.654924 -33.355026)
		(size 0.5588)
		(drill 0.3048)
		(layers "F.Cu" "B.Cu")
		(net "GND")
	)
	(via
		(at 342.606376 -1.524)
		(size 0.7112)
		(drill 0.4064)
		(layers "F.Cu" "B.Cu")
		(net "GND")
	)
	(via
		(at 393.7 -342.9)
		(size 0.5588)
		(drill 0.3048)
		(layers "F.Cu" "B.Cu")
		(net "GND")
	)
	(via
		(at 28.304998 -148.35505)
		(size 0.5588)
		(drill 0.3048)
		(layers "F.Cu" "B.Cu")
		(net "GND")
	)
	(via
		(at 389.596376 -1.524)
		(size 0.7112)
		(drill 0.4064)
		(layers "F.Cu" "B.Cu")
		(net "GND")
	)
	(via
		(at 93.747844 -333.554832)
		(size 0.5588)
		(drill 0.3048)
		(layers "F.Cu" "B.Cu")
		(net "GND")
	)
	(via
		(at 1.524 -81.683352)
		(size 0.7112)
		(drill 0.4064)
		(layers "F.Cu" "B.Cu")
		(net "GND")
	)
	(via
		(at 361.656376 -1.524)
		(size 0.7112)
		(drill 0.4064)
		(layers "F.Cu" "B.Cu")
		(net "GND")
	)
	(via
		(at 427.696376 -1.524)
		(size 0.7112)
		(drill 0.4064)
		(layers "F.Cu" "B.Cu")
		(net "GND")
	)
	(via
		(at 94.866968 -338.440014)
		(size 0.5588)
		(drill 0.3048)
		(layers "F.Cu" "B.Cu")
		(net "GND")
	)
	(via
		(at 84.756752 -344.864944)
		(size 0.5588)
		(drill 0.3048)
		(layers "F.Cu" "B.Cu")
		(net "GND")
	)
	(via
		(at 483.404926 -148.35505)
		(size 0.5588)
		(drill 0.3048)
		(layers "F.Cu" "B.Cu")
		(net "GND")
	)
	(via
		(at 23.4315 -250.444)
		(size 0.5588)
		(drill 0.3048)
		(layers "F.Cu" "B.Cu")
		(net "GND")
	)
	(via
		(at 1.524 -206.143352)
		(size 0.7112)
		(drill 0.4064)
		(layers "F.Cu" "B.Cu")
		(net "GND")
	)
	(via
		(at 489.926122 -44.19219)
		(size 0.7112)
		(drill 0.4064)
		(layers "F.Cu" "B.Cu")
		(net "GND")
	)
	(via
		(at 80.94599 -378.476002)
		(size 0.7112)
		(drill 0.4064)
		(layers "F.Cu" "B.Cu")
		(net "GND")
	)
	(via
		(at 457.2 -222.885)
		(size 0.5588)
		(drill 0.3048)
		(layers "F.Cu" "B.Cu")
		(net "GND")
	)
	(via
		(at 489.926122 -17.52219)
		(size 0.7112)
		(drill 0.4064)
		(layers "F.Cu" "B.Cu")
		(net "GND")
	)
	(via
		(at 90.261948 -253.830074)
		(size 0.5588)
		(drill 0.3048)
		(layers "F.Cu" "B.Cu")
		(net "GND")
	)
	(via
		(at 35.7505 -146.177)
		(size 0.5588)
		(drill 0.3048)
		(layers "F.Cu" "B.Cu")
		(net "GND")
	)
	(via
		(at 447.285872 -384.47599)
		(size 0.7112)
		(drill 0.4064)
		(layers "F.Cu" "B.Cu")
		(net "GND")
	)
	(via
		(at 489.926122 -92.45219)
		(size 0.7112)
		(drill 0.4064)
		(layers "F.Cu" "B.Cu")
		(net "GND")
	)
	(via
		(at 1.524 -142.643352)
		(size 0.7112)
		(drill 0.4064)
		(layers "F.Cu" "B.Cu")
		(net "GND")
	)
	(via
		(at 287.02 -293.116)
		(size 0.5588)
		(drill 0.3048)
		(layers "F.Cu" "B.Cu")
		(net "GND")
	)
	(via
		(at 1.524 -99.463352)
		(size 0.7112)
		(drill 0.4064)
		(layers "F.Cu" "B.Cu")
		(net "GND")
	)
	(via
		(at 472.505024 -380.775972)
		(size 0.7112)
		(drill 0.4064)
		(layers "F.Cu" "B.Cu")
		(net "GND")
	)
	(via
		(at 1.524 -242.973352)
		(size 0.7112)
		(drill 0.4064)
		(layers "F.Cu" "B.Cu")
		(net "GND")
	)
	(via
		(at 69.197982 -384.47599)
		(size 0.7112)
		(drill 0.4064)
		(layers "F.Cu" "B.Cu")
		(net "GND")
	)
	(via
		(at 85.852 -11.176)
		(size 0.5588)
		(drill 0.3048)
		(layers "F.Cu" "B.Cu")
		(net "GND")
	)
	(via
		(at 104.312466 -7.898892)
		(size 0.5588)
		(drill 0.3048)
		(layers "F.Cu" "B.Cu")
		(net "GND")
	)
	(via
		(at 325.654924 -243.035074)
		(size 0.5588)
		(drill 0.3048)
		(layers "F.Cu" "B.Cu")
		(net "GND")
	)
	(via
		(at 203.708 -66.929)
		(size 0.5588)
		(drill 0.3048)
		(layers "F.Cu" "B.Cu")
		(net "GND")
	)
	(via
		(at 113.157 -33.782)
		(size 0.5588)
		(drill 0.3048)
		(layers "F.Cu" "B.Cu")
		(net "GND")
	)
	(via
		(at 1.524 -300.123352)
		(size 0.7112)
		(drill 0.4064)
		(layers "F.Cu" "B.Cu")
		(net "GND")
	)
	(via
		(at 489.926122 -317.24219)
		(size 0.7112)
		(drill 0.4064)
		(layers "F.Cu" "B.Cu")
		(net "GND")
	)
	(via
		(at 211.277962 -378.476002)
		(size 0.7112)
		(drill 0.4064)
		(layers "F.Cu" "B.Cu")
		(net "GND")
	)
	(via
		(at 105.156 -14.732)
		(size 0.5588)
		(drill 0.3048)
		(layers "F.Cu" "B.Cu")
		(net "GND")
	)
	(via
		(at 489.926122 -51.81219)
		(size 0.7112)
		(drill 0.4064)
		(layers "F.Cu" "B.Cu")
		(net "GND")
	)
	(via
		(at 324.789292 -21.42236)
		(size 0.5588)
		(drill 0.3048)
		(layers "F.Cu" "B.Cu")
		(net "GND")
	)
	(via
		(at 1.524 -349.653352)
		(size 0.7112)
		(drill 0.4064)
		(layers "F.Cu" "B.Cu")
		(net "GND")
	)
	(via
		(at 113.96599 -378.476002)
		(size 0.7112)
		(drill 0.4064)
		(layers "F.Cu" "B.Cu")
		(net "GND")
	)
	(via
		(at 489.926122 -368.04219)
		(size 0.7112)
		(drill 0.4064)
		(layers "F.Cu" "B.Cu")
		(net "GND")
	)
	(via
		(at 59.854846 -263.355074)
		(size 0.5588)
		(drill 0.3048)
		(layers "F.Cu" "B.Cu")
		(net "GND")
	)
	(via
		(at 50.292 -260.604)
		(size 0.5588)
		(drill 0.3048)
		(layers "F.Cu" "B.Cu")
		(net "GND")
	)
	(via
		(at 390.532874 -7.035038)
		(size 0.5588)
		(drill 0.3048)
		(layers "F.Cu" "B.Cu")
		(net "GND")
	)
	(via
		(at 110.594648 -1.524)
		(size 0.7112)
		(drill 0.4064)
		(layers "F.Cu" "B.Cu")
		(net "GND")
	)
	(via
		(at 448.697604 -363.0676)
		(size 0.7112)
		(drill 0.4064)
		(layers "F.Cu" "B.Cu")
		(net "GND")
	)
	(via
		(at 446.3288 -141.9606)
		(size 0.5588)
		(drill 0.3048)
		(layers "F.Cu" "B.Cu")
		(net "GND")
	)
	(via
		(at 17.765268 -103.26497)
		(size 0.5588)
		(drill 0.3048)
		(layers "F.Cu" "B.Cu")
		(net "GND")
	)
	(via
		(at 357.205026 -153.43505)
		(size 0.5588)
		(drill 0.3048)
		(layers "F.Cu" "B.Cu")
		(net "GND")
	)
	(via
		(at 81.384648 -1.524)
		(size 0.7112)
		(drill 0.4064)
		(layers "F.Cu" "B.Cu")
		(net "GND")
	)
	(via
		(at 50.165 -145.542)
		(size 0.5588)
		(drill 0.3048)
		(layers "F.Cu" "B.Cu")
		(net "GND")
	)
	(via
		(at 314.452 -366.776)
		(size 0.5588)
		(drill 0.3048)
		(layers "F.Cu" "B.Cu")
		(net "GND")
	)
	(via
		(at 267.494004 -384.457956)
		(size 0.7112)
		(drill 0.4064)
		(layers "F.Cu" "B.Cu")
		(net "GND")
	)
	(via
		(at 222.631 -358.354122)
		(size 0.5588)
		(drill 0.3048)
		(layers "F.Cu" "B.Cu")
		(net "GND")
	)
	(via
		(at 67.31 -256.159)
		(size 0.5588)
		(drill 0.3048)
		(layers "F.Cu" "B.Cu")
		(net "GND")
	)
	(via
		(at 485.182926 -122.035062)
		(size 0.5588)
		(drill 0.3048)
		(layers "F.Cu" "B.Cu")
		(net "GND")
	)
	(via
		(at 74.818494 -216.759028)
		(size 0.5588)
		(drill 0.3048)
		(layers "F.Cu" "B.Cu")
		(net "GND")
	)
	(via
		(at 393.7 -368.3)
		(size 0.5588)
		(drill 0.3048)
		(layers "F.Cu" "B.Cu")
		(net "GND")
	)
	(via
		(at 288.911284 -224.294446)
		(size 0.6604)
		(drill 0.3556)
		(layers "F.Cu" "B.Cu")
		(net "GND")
	)
	(via
		(at 6.604 -238.76)
		(size 0.5588)
		(drill 0.3048)
		(layers "F.Cu" "B.Cu")
		(net "GND")
	)
	(via
		(at 80.772 -268.732)
		(size 0.5588)
		(drill 0.3048)
		(layers "F.Cu" "B.Cu")
		(net "GND")
	)
	(via
		(at 456.946 -38.608)
		(size 0.5588)
		(drill 0.3048)
		(layers "F.Cu" "B.Cu")
		(net "GND")
	)
	(via
		(at 447.660268 -227.431854)
		(size 0.6096)
		(drill 0.3048)
		(layers "F.Cu" "B.Cu")
		(net "GND")
	)
	(via
		(at 152.504648 -1.524)
		(size 0.7112)
		(drill 0.4064)
		(layers "F.Cu" "B.Cu")
		(net "GND")
	)
	(via
		(at 91.404948 -131.84505)
		(size 0.5588)
		(drill 0.3048)
		(layers "F.Cu" "B.Cu")
		(net "GND")
	)
	(via
		(at 429.387 -250.444)
		(size 0.5588)
		(drill 0.3048)
		(layers "F.Cu" "B.Cu")
		(net "GND")
	)
	(via
		(at 489.926122 -228.34219)
		(size 0.7112)
		(drill 0.4064)
		(layers "F.Cu" "B.Cu")
		(net "GND")
	)
	(via
		(at 270.926052 -371.451632)
		(size 0.7112)
		(drill 0.4064)
		(layers "F.Cu" "B.Cu")
		(net "GND")
	)
	(via
		(at 474.1418 -130.2512)
		(size 0.5588)
		(drill 0.3048)
		(layers "F.Cu" "B.Cu")
		(net "GND")
	)
	(via
		(at 489.926122 -356.61219)
		(size 0.7112)
		(drill 0.4064)
		(layers "F.Cu" "B.Cu")
		(net "GND")
	)
	(via
		(at 72.136 -40.64)
		(size 0.5588)
		(drill 0.3048)
		(layers "F.Cu" "B.Cu")
		(net "GND")
	)
	(via
		(at 489.926122 -305.81219)
		(size 0.7112)
		(drill 0.4064)
		(layers "F.Cu" "B.Cu")
		(net "GND")
	)
	(via
		(at 130.048 -7.112)
		(size 0.5588)
		(drill 0.3048)
		(layers "F.Cu" "B.Cu")
		(net "GND")
	)
	(via
		(at 342.46947 -101.814376)
		(size 0.5588)
		(drill 0.3048)
		(layers "F.Cu" "B.Cu")
		(net "GND")
	)
	(via
		(at 457.2762 -247.65)
		(size 0.5588)
		(drill 0.3048)
		(layers "F.Cu" "B.Cu")
		(net "GND")
	)
	(via
		(at 119.484648 -1.524)
		(size 0.7112)
		(drill 0.4064)
		(layers "F.Cu" "B.Cu")
		(net "GND")
	)
	(via
		(at 301.752 -191.389)
		(size 0.5588)
		(drill 0.3048)
		(layers "F.Cu" "B.Cu")
		(net "GND")
	)
	(via
		(at 401.247864 -378.476002)
		(size 0.7112)
		(drill 0.4064)
		(layers "F.Cu" "B.Cu")
		(net "GND")
	)
	(via
		(at 66.548 -7.62)
		(size 0.5588)
		(drill 0.3048)
		(layers "F.Cu" "B.Cu")
		(net "GND")
	)
	(via
		(at 450.711824 -256.23012)
		(size 0.5588)
		(drill 0.3048)
		(layers "F.Cu" "B.Cu")
		(net "GND")
	)
	(via
		(at 82.296 -165.1)
		(size 0.5588)
		(drill 0.3048)
		(layers "F.Cu" "B.Cu")
		(net "GND")
	)
	(via
		(at 338.328 -164.084)
		(size 0.5588)
		(drill 0.3048)
		(layers "F.Cu" "B.Cu")
		(net "GND")
	)
	(via
		(at 456.906376 -1.524)
		(size 0.7112)
		(drill 0.4064)
		(layers "F.Cu" "B.Cu")
		(net "GND")
	)
	(via
		(at 282.984448 -346.271342)
		(size 0.5588)
		(drill 0.3048)
		(layers "F.Cu" "B.Cu")
		(net "GND")
	)
	(via
		(at 334.772 -250.444)
		(size 0.5588)
		(drill 0.3048)
		(layers "F.Cu" "B.Cu")
		(net "GND")
	)
	(via
		(at 457.310744 -104.852216)
		(size 0.5588)
		(drill 0.3048)
		(layers "F.Cu" "B.Cu")
		(net "GND")
	)
	(via
		(at 257.811778 -227.33)
		(size 0.5588)
		(drill 0.3048)
		(layers "F.Cu" "B.Cu")
		(net "GND")
	)
	(via
		(at 287.909 -305.2318)
		(size 0.7112)
		(drill 0.4064)
		(layers "F.Cu" "B.Cu")
		(net "GND")
	)
	(via
		(at 48.877982 -384.47599)
		(size 0.7112)
		(drill 0.4064)
		(layers "F.Cu" "B.Cu")
		(net "GND")
	)
	(via
		(at 358.983026 -280.785062)
		(size 0.5588)
		(drill 0.3048)
		(layers "F.Cu" "B.Cu")
		(net "GND")
	)
	(via
		(at 388.754874 -250.655074)
		(size 0.5588)
		(drill 0.3048)
		(layers "F.Cu" "B.Cu")
		(net "GND")
	)
	(via
		(at 177.295048 -380.775972)
		(size 0.7112)
		(drill 0.4064)
		(layers "F.Cu" "B.Cu")
		(net "GND")
	)
	(via
		(at 1.524 -118.513352)
		(size 0.7112)
		(drill 0.4064)
		(layers "F.Cu" "B.Cu")
		(net "GND")
	)
	(via
		(at 312.523886 -45.10151)
		(size 0.7112)
		(drill 0.4064)
		(layers "F.Cu" "B.Cu")
		(net "GND")
	)
	(via
		(at 416.1028 -145.3388)
		(size 0.5588)
		(drill 0.3048)
		(layers "F.Cu" "B.Cu")
		(net "GND")
	)
	(via
		(at 158.162498 -155.979114)
		(size 0.5588)
		(drill 0.3048)
		(layers "F.Cu" "B.Cu")
		(net "GND")
	)
	(via
		(at 81.28 -107.188)
		(size 0.5588)
		(drill 0.3048)
		(layers "F.Cu" "B.Cu")
		(net "GND")
	)
	(via
		(at 237.363 -224.829624)
		(size 0.5588)
		(drill 0.3048)
		(layers "F.Cu" "B.Cu")
		(net "GND")
	)
	(via
		(at 213.817962 -378.476002)
		(size 0.7112)
		(drill 0.4064)
		(layers "F.Cu" "B.Cu")
		(net "GND")
	)
	(via
		(at 326.096376 -1.524)
		(size 0.7112)
		(drill 0.4064)
		(layers "F.Cu" "B.Cu")
		(net "GND")
	)
	(via
		(at 104.14 -271.272)
		(size 0.5588)
		(drill 0.3048)
		(layers "F.Cu" "B.Cu")
		(net "GND")
	)
	(via
		(at 486.925874 -376.970036)
		(size 0.7112)
		(drill 0.4064)
		(layers "F.Cu" "B.Cu")
		(net "GND")
	)
	(via
		(at 39.116 -26.924)
		(size 0.5588)
		(drill 0.3048)
		(layers "F.Cu" "B.Cu")
		(net "GND")
	)
	(via
		(at 59.854846 -260.815074)
		(size 0.5588)
		(drill 0.3048)
		(layers "F.Cu" "B.Cu")
		(net "GND")
	)
	(via
		(at 1.524 -68.983352)
		(size 0.7112)
		(drill 0.4064)
		(layers "F.Cu" "B.Cu")
		(net "GND")
	)
	(via
		(at 156.282898 -122.035062)
		(size 0.5588)
		(drill 0.3048)
		(layers "F.Cu" "B.Cu")
		(net "GND")
	)
	(via
		(at 345.049856 -384.47599)
		(size 0.7112)
		(drill 0.4064)
		(layers "F.Cu" "B.Cu")
		(net "GND")
	)
	(via
		(at 249.377962 -378.476002)
		(size 0.7112)
		(drill 0.4064)
		(layers "F.Cu" "B.Cu")
		(net "GND")
	)
	(via
		(at 1.524 -140.103352)
		(size 0.7112)
		(drill 0.4064)
		(layers "F.Cu" "B.Cu")
		(net "GND")
	)
	(via
		(at 172.824648 -1.524)
		(size 0.7112)
		(drill 0.4064)
		(layers "F.Cu" "B.Cu")
		(net "GND")
	)
	(via
		(at 204.343 -96.266)
		(size 0.5588)
		(drill 0.3048)
		(layers "F.Cu" "B.Cu")
		(net "GND")
	)
	(via
		(at 489.926122 -263.90219)
		(size 0.7112)
		(drill 0.4064)
		(layers "F.Cu" "B.Cu")
		(net "GND")
	)
	(via
		(at 161.544 -238.506)
		(size 0.5588)
		(drill 0.3048)
		(layers "F.Cu" "B.Cu")
		(net "GND")
	)
	(via
		(at 1.524 -244.243352)
		(size 0.7112)
		(drill 0.4064)
		(layers "F.Cu" "B.Cu")
		(net "GND")
	)
	(via
		(at 247.42648 -218.16568)
		(size 0.5588)
		(drill 0.3048)
		(layers "F.Cu" "B.Cu")
		(net "GND")
	)
	(via
		(at 205.141322 -102.665784)
		(size 0.7112)
		(drill 0.4064)
		(layers "F.Cu" "B.Cu")
		(net "GND")
	)
	(via
		(at 330.1492 -14.224)
		(size 0.5588)
		(drill 0.3048)
		(layers "F.Cu" "B.Cu")
		(net "GND")
	)
	(via
		(at 288.911284 -227.894388)
		(size 0.6604)
		(drill 0.3556)
		(layers "F.Cu" "B.Cu")
		(net "GND")
	)
	(via
		(at 114.3 -292.1)
		(size 0.5588)
		(drill 0.3048)
		(layers "F.Cu" "B.Cu")
		(net "GND")
	)
	(via
		(at 117.348 -271.3228)
		(size 0.5588)
		(drill 0.3048)
		(layers "F.Cu" "B.Cu")
		(net "GND")
	)
	(via
		(at 289.052 -246.38)
		(size 0.5588)
		(drill 0.3048)
		(layers "F.Cu" "B.Cu")
		(net "GND")
	)
	(via
		(at 357.205026 -131.84505)
		(size 0.5588)
		(drill 0.3048)
		(layers "F.Cu" "B.Cu")
		(net "GND")
	)
	(via
		(at 1.524 -245.513352)
		(size 0.7112)
		(drill 0.4064)
		(layers "F.Cu" "B.Cu")
		(net "GND")
	)
	(via
		(at 379.476 -24.892)
		(size 0.5588)
		(drill 0.3048)
		(layers "F.Cu" "B.Cu")
		(net "GND")
	)
	(via
		(at 197.47611 -26.402538)
		(size 0.7112)
		(drill 0.4064)
		(layers "F.Cu" "B.Cu")
		(net "GND")
	)
	(via
		(at 302.970692 -384.47599)
		(size 0.7112)
		(drill 0.4064)
		(layers "F.Cu" "B.Cu")
		(net "GND")
	)
	(via
		(at 365.252 -153.289)
		(size 0.5588)
		(drill 0.3048)
		(layers "F.Cu" "B.Cu")
		(net "GND")
	)
	(via
		(at 438.912 -254.508)
		(size 0.5588)
		(drill 0.3048)
		(layers "F.Cu" "B.Cu")
		(net "GND")
	)
	(via
		(at 1.524 -53.743352)
		(size 0.7112)
		(drill 0.4064)
		(layers "F.Cu" "B.Cu")
		(net "GND")
	)
	(via
		(at 437.119268 -216.8144)
		(size 0.5588)
		(drill 0.3048)
		(layers "F.Cu" "B.Cu")
		(net "GND")
	)
	(via
		(at 1.524 -173.123352)
		(size 0.7112)
		(drill 0.4064)
		(layers "F.Cu" "B.Cu")
		(net "GND")
	)
	(via
		(at 1.524 -296.313352)
		(size 0.7112)
		(drill 0.4064)
		(layers "F.Cu" "B.Cu")
		(net "GND")
	)
	(via
		(at 324.621652 -23.830534)
		(size 0.5588)
		(drill 0.3048)
		(layers "F.Cu" "B.Cu")
		(net "GND")
	)
	(via
		(at 85.344 -118.364)
		(size 0.5588)
		(drill 0.3048)
		(layers "F.Cu" "B.Cu")
		(net "GND")
	)
	(via
		(at 249.986038 -135.479282)
		(size 0.5588)
		(drill 0.3048)
		(layers "F.Cu" "B.Cu")
		(net "GND")
	)
	(via
		(at 100.076 -44.196)
		(size 0.5588)
		(drill 0.3048)
		(layers "F.Cu" "B.Cu")
		(net "GND")
	)
	(via
		(at 425.695872 -384.47599)
		(size 0.7112)
		(drill 0.4064)
		(layers "F.Cu" "B.Cu")
		(net "GND")
	)
	(via
		(at 340.701122 -216.759028)
		(size 0.5588)
		(drill 0.3048)
		(layers "F.Cu" "B.Cu")
		(net "GND")
	)
	(via
		(at 156.314648 -1.524)
		(size 0.7112)
		(drill 0.4064)
		(layers "F.Cu" "B.Cu")
		(net "GND")
	)
	(via
		(at 202.7936 -144.018)
		(size 0.7112)
		(drill 0.4064)
		(layers "F.Cu" "B.Cu")
		(net "GND")
	)
	(via
		(at 331.183996 -369.2525)
		(size 0.5588)
		(drill 0.3048)
		(layers "F.Cu" "B.Cu")
		(net "GND")
	)
	(via
		(at 327.152 -329.184)
		(size 0.5588)
		(drill 0.3048)
		(layers "F.Cu" "B.Cu")
		(net "GND")
	)
	(via
		(at 435.864 -223.012)
		(size 0.5588)
		(drill 0.3048)
		(layers "F.Cu" "B.Cu")
		(net "GND")
	)
	(via
		(at 1.524 -284.883352)
		(size 0.7112)
		(drill 0.4064)
		(layers "F.Cu" "B.Cu")
		(net "GND")
	)
	(via
		(at 312.523886 -26.05151)
		(size 0.7112)
		(drill 0.4064)
		(layers "F.Cu" "B.Cu")
		(net "GND")
	)
	(via
		(at 177.904648 -1.524)
		(size 0.7112)
		(drill 0.4064)
		(layers "F.Cu" "B.Cu")
		(net "GND")
	)
	(via
		(at 486.925874 -380.780036)
		(size 0.7112)
		(drill 0.4064)
		(layers "F.Cu" "B.Cu")
		(net "GND")
	)
	(via
		(at 180.444648 -1.524)
		(size 0.7112)
		(drill 0.4064)
		(layers "F.Cu" "B.Cu")
		(net "GND")
	)
	(via
		(at 214.376 -277.368)
		(size 0.5588)
		(drill 0.3048)
		(layers "F.Cu" "B.Cu")
		(net "GND")
	)
	(via
		(at 352.679 -58.42)
		(size 0.5588)
		(drill 0.3048)
		(layers "F.Cu" "B.Cu")
		(net "GND")
	)
	(via
		(at 91.404948 -155.97505)
		(size 0.5588)
		(drill 0.3048)
		(layers "F.Cu" "B.Cu")
		(net "GND")
	)
	(via
		(at 321.709796 -368.8842)
		(size 0.5588)
		(drill 0.3048)
		(layers "F.Cu" "B.Cu")
		(net "GND")
	)
	(via
		(at 295.588436 -49.724056)
		(size 0.7112)
		(drill 0.4064)
		(layers "F.Cu" "B.Cu")
		(net "GND")
	)
	(via
		(at 489.926122 -290.57219)
		(size 0.7112)
		(drill 0.4064)
		(layers "F.Cu" "B.Cu")
		(net "GND")
	)
	(via
		(at 10.907268 -211.310728)
		(size 0.5588)
		(drill 0.3048)
		(layers "F.Cu" "B.Cu")
		(net "GND")
	)
	(via
		(at 288.911284 -188.294518)
		(size 0.6604)
		(drill 0.3556)
		(layers "F.Cu" "B.Cu")
		(net "GND")
	)
	(via
		(at 396.621 -162.52444)
		(size 0.5588)
		(drill 0.3048)
		(layers "F.Cu" "B.Cu")
		(net "GND")
	)
	(via
		(at 455.733404 -374.2182)
		(size 0.5588)
		(drill 0.3048)
		(layers "F.Cu" "B.Cu")
		(net "GND")
	)
	(via
		(at 222.56877 -208.025492)
		(size 0.5588)
		(drill 0.3048)
		(layers "F.Cu" "B.Cu")
		(net "GND")
	)
	(via
		(at 56.497982 -384.47599)
		(size 0.7112)
		(drill 0.4064)
		(layers "F.Cu" "B.Cu")
		(net "GND")
	)
	(via
		(at 304.240692 -384.47599)
		(size 0.7112)
		(drill 0.4064)
		(layers "F.Cu" "B.Cu")
		(net "GND")
	)
	(via
		(at 304.519076 -342.077802)
		(size 0.5588)
		(drill 0.3048)
		(layers "F.Cu" "B.Cu")
		(net "GND")
	)
	(via
		(at 61.632846 -280.785062)
		(size 0.5588)
		(drill 0.3048)
		(layers "F.Cu" "B.Cu")
		(net "GND")
	)
	(via
		(at 25.908 -382.397)
		(size 0.7112)
		(drill 0.4064)
		(layers "F.Cu" "B.Cu")
		(net "GND")
	)
	(via
		(at 14.859 -383.032)
		(size 0.7112)
		(drill 0.4064)
		(layers "F.Cu" "B.Cu")
		(net "GND")
	)
	(via
		(at 312.523886 -40.02151)
		(size 0.7112)
		(drill 0.4064)
		(layers "F.Cu" "B.Cu")
		(net "GND")
	)
	(via
		(at 489.926122 -260.09219)
		(size 0.7112)
		(drill 0.4064)
		(layers "F.Cu" "B.Cu")
		(net "GND")
	)
	(via
		(at 90.274648 -1.524)
		(size 0.7112)
		(drill 0.4064)
		(layers "F.Cu" "B.Cu")
		(net "GND")
	)
	(via
		(at 416.3822 -30.353)
		(size 0.5588)
		(drill 0.3048)
		(layers "F.Cu" "B.Cu")
		(net "GND")
	)
	(via
		(at 359.116376 -1.524)
		(size 0.7112)
		(drill 0.4064)
		(layers "F.Cu" "B.Cu")
		(net "GND")
	)
	(via
		(at 1.524 -37.233352)
		(size 0.7112)
		(drill 0.4064)
		(layers "F.Cu" "B.Cu")
		(net "GND")
	)
	(via
		(at 261.239 -223.393)
		(size 0.5588)
		(drill 0.3048)
		(layers "F.Cu" "B.Cu")
		(net "GND")
	)
	(via
		(at 489.926122 -32.76219)
		(size 0.7112)
		(drill 0.4064)
		(layers "F.Cu" "B.Cu")
		(net "GND")
	)
	(via
		(at 167.64 -271.272)
		(size 0.5588)
		(drill 0.3048)
		(layers "F.Cu" "B.Cu")
		(net "GND")
	)
	(via
		(at 403.787864 -378.476002)
		(size 0.7112)
		(drill 0.4064)
		(layers "F.Cu" "B.Cu")
		(net "GND")
	)
	(via
		(at 226.517962 -378.476002)
		(size 0.7112)
		(drill 0.4064)
		(layers "F.Cu" "B.Cu")
		(net "GND")
	)
	(via
		(at 444.206376 -1.524)
		(size 0.7112)
		(drill 0.4064)
		(layers "F.Cu" "B.Cu")
		(net "GND")
	)
	(via
		(at 456.039982 -105.899458)
		(size 0.5588)
		(drill 0.3048)
		(layers "F.Cu" "B.Cu")
		(net "GND")
	)
	(via
		(at 1.524 -14.373352)
		(size 0.7112)
		(drill 0.4064)
		(layers "F.Cu" "B.Cu")
		(net "GND")
	)
	(via
		(at 383.159 -74.295)
		(size 0.5588)
		(drill 0.3048)
		(layers "F.Cu" "B.Cu")
		(net "GND")
	)
	(via
		(at 52.687982 -384.47599)
		(size 0.7112)
		(drill 0.4064)
		(layers "F.Cu" "B.Cu")
		(net "GND")
	)
	(via
		(at 393.954 -268.605)
		(size 0.5588)
		(drill 0.3048)
		(layers "F.Cu" "B.Cu")
		(net "GND")
	)
	(via
		(at 75.692 -35.687)
		(size 0.5588)
		(drill 0.3048)
		(layers "F.Cu" "B.Cu")
		(net "GND")
	)
	(via
		(at 1.524 -201.063352)
		(size 0.7112)
		(drill 0.4064)
		(layers "F.Cu" "B.Cu")
		(net "GND")
	)
	(via
		(at 489.926122 -130.55219)
		(size 0.7112)
		(drill 0.4064)
		(layers "F.Cu" "B.Cu")
		(net "GND")
	)
	(via
		(at 362.712 -60.452)
		(size 0.5588)
		(drill 0.3048)
		(layers "F.Cu" "B.Cu")
		(net "GND")
	)
	(via
		(at 489.926122 -18.79219)
		(size 0.7112)
		(drill 0.4064)
		(layers "F.Cu" "B.Cu")
		(net "GND")
	)
	(via
		(at 275.268436 -49.724056)
		(size 0.7112)
		(drill 0.4064)
		(layers "F.Cu" "B.Cu")
		(net "GND")
	)
	(via
		(at 304.138076 -326.593962)
		(size 0.5588)
		(drill 0.3048)
		(layers "F.Cu" "B.Cu")
		(net "GND")
	)
	(via
		(at 343.281 -36.703)
		(size 0.5588)
		(drill 0.3048)
		(layers "F.Cu" "B.Cu")
		(net "GND")
	)
	(via
		(at 273.998436 -49.724056)
		(size 0.7112)
		(drill 0.4064)
		(layers "F.Cu" "B.Cu")
		(net "GND")
	)
	(via
		(at 145.288 -133.5532)
		(size 0.5588)
		(drill 0.3048)
		(layers "F.Cu" "B.Cu")
		(net "GND")
	)
	(via
		(at 110.9345 -255.016)
		(size 0.5588)
		(drill 0.3048)
		(layers "F.Cu" "B.Cu")
		(net "GND")
	)
	(via
		(at 439.317384 -115.616228)
		(size 0.5588)
		(drill 0.3048)
		(layers "F.Cu" "B.Cu")
		(net "GND")
	)
	(via
		(at 243.713 -313.182)
		(size 0.5588)
		(drill 0.3048)
		(layers "F.Cu" "B.Cu")
		(net "GND")
	)
	(via
		(at 213.692486 -202.347576)
		(size 0.5588)
		(drill 0.3048)
		(layers "F.Cu" "B.Cu")
		(net "GND")
	)
	(via
		(at 264.954004 -384.457956)
		(size 0.7112)
		(drill 0.4064)
		(layers "F.Cu" "B.Cu")
		(net "GND")
	)
	(via
		(at 489.926122 -220.72219)
		(size 0.7112)
		(drill 0.4064)
		(layers "F.Cu" "B.Cu")
		(net "GND")
	)
	(via
		(at 25.4 -317.5)
		(size 0.5588)
		(drill 0.3048)
		(layers "F.Cu" "B.Cu")
		(net "GND")
	)
	(via
		(at 153.361898 -253.830074)
		(size 0.5588)
		(drill 0.3048)
		(layers "F.Cu" "B.Cu")
		(net "GND")
	)
	(via
		(at 317.5 -304.8)
		(size 0.5588)
		(drill 0.3048)
		(layers "F.Cu" "B.Cu")
		(net "GND")
	)
	(via
		(at 435.35092 -216.759028)
		(size 0.5588)
		(drill 0.3048)
		(layers "F.Cu" "B.Cu")
		(net "GND")
	)
	(via
		(at 1.524 -277.263352)
		(size 0.7112)
		(drill 0.4064)
		(layers "F.Cu" "B.Cu")
		(net "GND")
	)
	(via
		(at 395.732 -122.428)
		(size 0.5588)
		(drill 0.3048)
		(layers "F.Cu" "B.Cu")
		(net "GND")
	)
	(via
		(at 317.5 -208.28)
		(size 0.5588)
		(drill 0.3048)
		(layers "F.Cu" "B.Cu")
		(net "GND")
	)
	(via
		(at 203.922122 -103.884984)
		(size 0.7112)
		(drill 0.4064)
		(layers "F.Cu" "B.Cu")
		(net "GND")
	)
	(via
		(at 116.84 -125.984)
		(size 0.5588)
		(drill 0.3048)
		(layers "F.Cu" "B.Cu")
		(net "GND")
	)
	(via
		(at 437.327548 -116.442744)
		(size 0.5588)
		(drill 0.3048)
		(layers "F.Cu" "B.Cu")
		(net "GND")
	)
	(via
		(at 363.22 -191.008)
		(size 0.5588)
		(drill 0.3048)
		(layers "F.Cu" "B.Cu")
		(net "GND")
	)
	(via
		(at 1.524 -60.093352)
		(size 0.7112)
		(drill 0.4064)
		(layers "F.Cu" "B.Cu")
		(net "GND")
	)
	(via
		(at 118.0465 -250.444)
		(size 0.5588)
		(drill 0.3048)
		(layers "F.Cu" "B.Cu")
		(net "GND")
	)
	(via
		(at 428.589186 -116.130578)
		(size 0.5588)
		(drill 0.3048)
		(layers "F.Cu" "B.Cu")
		(net "GND")
	)
	(via
		(at 357.205026 -148.35505)
		(size 0.5588)
		(drill 0.3048)
		(layers "F.Cu" "B.Cu")
		(net "GND")
	)
	(via
		(at 86.5505 -20.447)
		(size 0.5588)
		(drill 0.3048)
		(layers "F.Cu" "B.Cu")
		(net "GND")
	)
	(via
		(at 86.02599 -378.476002)
		(size 0.7112)
		(drill 0.4064)
		(layers "F.Cu" "B.Cu")
		(net "GND")
	)
	(via
		(at 108.054648 -1.524)
		(size 0.7112)
		(drill 0.4064)
		(layers "F.Cu" "B.Cu")
		(net "GND")
	)
	(via
		(at 1.524 -340.763352)
		(size 0.7112)
		(drill 0.4064)
		(layers "F.Cu" "B.Cu")
		(net "GND")
	)
	(via
		(at 318.008 -256.54)
		(size 0.5588)
		(drill 0.3048)
		(layers "F.Cu" "B.Cu")
		(net "GND")
	)
	(via
		(at 388.547864 -378.476002)
		(size 0.7112)
		(drill 0.4064)
		(layers "F.Cu" "B.Cu")
		(net "GND")
	)
	(via
		(at 489.926122 -180.08219)
		(size 0.7112)
		(drill 0.4064)
		(layers "F.Cu" "B.Cu")
		(net "GND")
	)
	(via
		(at 262.89 -94.107)
		(size 0.5588)
		(drill 0.3048)
		(layers "F.Cu" "B.Cu")
		(net "GND")
	)
	(via
		(at 288.911284 -195.494402)
		(size 0.6604)
		(drill 0.3556)
		(layers "F.Cu" "B.Cu")
		(net "GND")
	)
	(via
		(at 91.404948 -260.815074)
		(size 0.5588)
		(drill 0.3048)
		(layers "F.Cu" "B.Cu")
		(net "GND")
	)
	(via
		(at 210.018122 -101.471984)
		(size 0.7112)
		(drill 0.4064)
		(layers "F.Cu" "B.Cu")
		(net "GND")
	)
	(via
		(at 35.32886 -114.119406)
		(size 0.5588)
		(drill 0.3048)
		(layers "F.Cu" "B.Cu")
		(net "GND")
	)
	(via
		(at 352.669856 -384.47599)
		(size 0.7112)
		(drill 0.4064)
		(layers "F.Cu" "B.Cu")
		(net "GND")
	)
	(via
		(at 438.301384 -112.568228)
		(size 0.5588)
		(drill 0.3048)
		(layers "F.Cu" "B.Cu")
		(net "GND")
	)
	(via
		(at 355.306376 -1.524)
		(size 0.7112)
		(drill 0.4064)
		(layers "F.Cu" "B.Cu")
		(net "GND")
	)
	(via
		(at 1.524 -180.743352)
		(size 0.7112)
		(drill 0.4064)
		(layers "F.Cu" "B.Cu")
		(net "GND")
	)
	(via
		(at 170.163998 -384.47599)
		(size 0.7112)
		(drill 0.4064)
		(layers "F.Cu" "B.Cu")
		(net "GND")
	)
	(via
		(at 48.364648 -1.524)
		(size 0.7112)
		(drill 0.4064)
		(layers "F.Cu" "B.Cu")
		(net "GND")
	)
	(via
		(at 361.315 -47.117)
		(size 0.5588)
		(drill 0.3048)
		(layers "F.Cu" "B.Cu")
		(net "GND")
	)
	(via
		(at 36.576 -139.7)
		(size 0.5588)
		(drill 0.3048)
		(layers "F.Cu" "B.Cu")
		(net "GND")
	)
	(via
		(at 309.1434 -342.077802)
		(size 0.5588)
		(drill 0.3048)
		(layers "F.Cu" "B.Cu")
		(net "GND")
	)
	(via
		(at 454.915016 -384.429)
		(size 0.7112)
		(drill 0.4064)
		(layers "F.Cu" "B.Cu")
		(net "GND")
	)
	(via
		(at 424.847004 -368.935)
		(size 0.5588)
		(drill 0.3048)
		(layers "F.Cu" "B.Cu")
		(net "GND")
	)
	(via
		(at 354.036376 -1.524)
		(size 0.7112)
		(drill 0.4064)
		(layers "F.Cu" "B.Cu")
		(net "GND")
	)
	(via
		(at 1.524 -352.193352)
		(size 0.7112)
		(drill 0.4064)
		(layers "F.Cu" "B.Cu")
		(net "GND")
	)
	(via
		(at 1.524 -55.013352)
		(size 0.7112)
		(drill 0.4064)
		(layers "F.Cu" "B.Cu")
		(net "GND")
	)
	(via
		(at 76.2 -304.8)
		(size 0.5588)
		(drill 0.3048)
		(layers "F.Cu" "B.Cu")
		(net "GND")
	)
	(via
		(at 59.854846 -246.845074)
		(size 0.5588)
		(drill 0.3048)
		(layers "F.Cu" "B.Cu")
		(net "GND")
	)
	(via
		(at 1.524 -331.873352)
		(size 0.7112)
		(drill 0.4064)
		(layers "F.Cu" "B.Cu")
		(net "GND")
	)
	(via
		(at 22.606 -156.2608)
		(size 0.5588)
		(drill 0.3048)
		(layers "F.Cu" "B.Cu")
		(net "GND")
	)
	(via
		(at 35.502596 -360.8324)
		(size 0.5588)
		(drill 0.3048)
		(layers "F.Cu" "B.Cu")
		(net "GND")
	)
	(via
		(at 1.524 -176.933352)
		(size 0.7112)
		(drill 0.4064)
		(layers "F.Cu" "B.Cu")
		(net "GND")
	)
	(via
		(at 489.926122 -331.21219)
		(size 0.7112)
		(drill 0.4064)
		(layers "F.Cu" "B.Cu")
		(net "GND")
	)
	(via
		(at 419.1 -292.1)
		(size 0.5588)
		(drill 0.3048)
		(layers "F.Cu" "B.Cu")
		(net "GND")
	)
	(via
		(at 489.926122 -197.86219)
		(size 0.7112)
		(drill 0.4064)
		(layers "F.Cu" "B.Cu")
		(net "GND")
	)
	(via
		(at 457.2 -224.917)
		(size 0.5588)
		(drill 0.3048)
		(layers "F.Cu" "B.Cu")
		(net "GND")
	)
	(via
		(at 163.322 -80.645)
		(size 0.5588)
		(drill 0.3048)
		(layers "F.Cu" "B.Cu")
		(net "GND")
	)
	(via
		(at 183.896 -365.6838)
		(size 0.5588)
		(drill 0.3048)
		(layers "F.Cu" "B.Cu")
		(net "GND")
	)
	(via
		(at 1.524 -307.743352)
		(size 0.7112)
		(drill 0.4064)
		(layers "F.Cu" "B.Cu")
		(net "GND")
	)
	(via
		(at 1.524 -336.953352)
		(size 0.7112)
		(drill 0.4064)
		(layers "F.Cu" "B.Cu")
		(net "GND")
	)
	(via
		(at 47.454058 -114.748056)
		(size 0.5588)
		(drill 0.3048)
		(layers "F.Cu" "B.Cu")
		(net "GND")
	)
	(via
		(at 489.926122 -141.98219)
		(size 0.7112)
		(drill 0.4064)
		(layers "F.Cu" "B.Cu")
		(net "GND")
	)
	(via
		(at 286.698436 -49.724056)
		(size 0.7112)
		(drill 0.4064)
		(layers "F.Cu" "B.Cu")
		(net "GND")
	)
	(via
		(at 68.684648 -1.524)
		(size 0.7112)
		(drill 0.4064)
		(layers "F.Cu" "B.Cu")
		(net "GND")
	)
	(via
		(at 1.524 -256.943352)
		(size 0.7112)
		(drill 0.4064)
		(layers "F.Cu" "B.Cu")
		(net "GND")
	)
	(via
		(at 330.835 -153.67)
		(size 0.5588)
		(drill 0.3048)
		(layers "F.Cu" "B.Cu")
		(net "GND")
	)
	(via
		(at 91.404948 -270.975074)
		(size 0.5588)
		(drill 0.3048)
		(layers "F.Cu" "B.Cu")
		(net "GND")
	)
	(via
		(at 360.386376 -1.524)
		(size 0.7112)
		(drill 0.4064)
		(layers "F.Cu" "B.Cu")
		(net "GND")
	)
	(via
		(at 205.476094 -61.386212)
		(size 0.7112)
		(drill 0.4064)
		(layers "F.Cu" "B.Cu")
		(net "GND")
	)
	(via
		(at 85.1408 -135.4328)
		(size 0.5588)
		(drill 0.3048)
		(layers "F.Cu" "B.Cu")
		(net "GND")
	)
	(via
		(at 10.16 -155.956)
		(size 0.5588)
		(drill 0.3048)
		(layers "F.Cu" "B.Cu")
		(net "GND")
	)
	(via
		(at 1.524 -112.163352)
		(size 0.7112)
		(drill 0.4064)
		(layers "F.Cu" "B.Cu")
		(net "GND")
	)
	(via
		(at 477.14916 -215.219788)
		(size 0.5588)
		(drill 0.3048)
		(layers "F.Cu" "B.Cu")
		(net "GND")
	)
	(via
		(at 197.47611 -36.562538)
		(size 0.7112)
		(drill 0.4064)
		(layers "F.Cu" "B.Cu")
		(net "GND")
	)
	(via
		(at 489.926122 -83.56219)
		(size 0.7112)
		(drill 0.4064)
		(layers "F.Cu" "B.Cu")
		(net "GND")
	)
	(via
		(at 423.886376 -1.524)
		(size 0.7112)
		(drill 0.4064)
		(layers "F.Cu" "B.Cu")
		(net "GND")
	)
	(via
		(at 327.269856 -384.47599)
		(size 0.7112)
		(drill 0.4064)
		(layers "F.Cu" "B.Cu")
		(net "GND")
	)
	(via
		(at 180.848 -182.88)
		(size 0.5588)
		(drill 0.3048)
		(layers "F.Cu" "B.Cu")
		(net "GND")
	)
	(via
		(at 46.438058 -114.748056)
		(size 0.5588)
		(drill 0.3048)
		(layers "F.Cu" "B.Cu")
		(net "GND")
	)
	(via
		(at 205.3082 -305.3334)
		(size 0.7112)
		(drill 0.4064)
		(layers "F.Cu" "B.Cu")
		(net "GND")
	)
	(via
		(at 393.627864 -378.476002)
		(size 0.7112)
		(drill 0.4064)
		(layers "F.Cu" "B.Cu")
		(net "GND")
	)
	(via
		(at 88.9 -203.2)
		(size 0.5588)
		(drill 0.3048)
		(layers "F.Cu" "B.Cu")
		(net "GND")
	)
	(via
		(at 402.517864 -378.476002)
		(size 0.7112)
		(drill 0.4064)
		(layers "F.Cu" "B.Cu")
		(net "GND")
	)
	(via
		(at 453.632824 -280.785062)
		(size 0.5588)
		(drill 0.3048)
		(layers "F.Cu" "B.Cu")
		(net "GND")
	)
	(via
		(at 130.048 -26.416)
		(size 0.5588)
		(drill 0.3048)
		(layers "F.Cu" "B.Cu")
		(net "GND")
	)
	(via
		(at 20.616164 -226.759516)
		(size 0.5588)
		(drill 0.3048)
		(layers "F.Cu" "B.Cu")
		(net "GND")
	)
	(via
		(at 258.604004 -384.457956)
		(size 0.7112)
		(drill 0.4064)
		(layers "F.Cu" "B.Cu")
		(net "GND")
	)
	(via
		(at 154.504898 -250.655074)
		(size 0.5588)
		(drill 0.3048)
		(layers "F.Cu" "B.Cu")
		(net "GND")
	)
	(via
		(at 375.412 -247.904)
		(size 0.5588)
		(drill 0.3048)
		(layers "F.Cu" "B.Cu")
		(net "GND")
	)
	(via
		(at 489.926122 -359.15219)
		(size 0.7112)
		(drill 0.4064)
		(layers "F.Cu" "B.Cu")
		(net "GND")
	)
	(via
		(at 254.794004 -384.457956)
		(size 0.7112)
		(drill 0.4064)
		(layers "F.Cu" "B.Cu")
		(net "GND")
	)
	(via
		(at 384.9116 -30.3276)
		(size 0.5588)
		(drill 0.3048)
		(layers "F.Cu" "B.Cu")
		(net "GND")
	)
	(via
		(at 28.304998 -263.355074)
		(size 0.5588)
		(drill 0.3048)
		(layers "F.Cu" "B.Cu")
		(net "GND")
	)
	(via
		(at 29.314648 -1.524)
		(size 0.7112)
		(drill 0.4064)
		(layers "F.Cu" "B.Cu")
		(net "GND")
	)
	(via
		(at 197.47611 -9.892538)
		(size 0.7112)
		(drill 0.4064)
		(layers "F.Cu" "B.Cu")
		(net "GND")
	)
	(via
		(at 489.926122 -138.17219)
		(size 0.7112)
		(drill 0.4064)
		(layers "F.Cu" "B.Cu")
		(net "GND")
	)
	(via
		(at 358.983026 -165.785038)
		(size 0.5588)
		(drill 0.3048)
		(layers "F.Cu" "B.Cu")
		(net "GND")
	)
	(via
		(at 1.524 -231.543352)
		(size 0.7112)
		(drill 0.4064)
		(layers "F.Cu" "B.Cu")
		(net "GND")
	)
	(via
		(at 218.44 -358.354122)
		(size 0.5588)
		(drill 0.3048)
		(layers "F.Cu" "B.Cu")
		(net "GND")
	)
	(via
		(at 73.924668 -211.310728)
		(size 0.5588)
		(drill 0.3048)
		(layers "F.Cu" "B.Cu")
		(net "GND")
	)
	(via
		(at 245.745 -313.182)
		(size 0.5588)
		(drill 0.3048)
		(layers "F.Cu" "B.Cu")
		(net "GND")
	)
	(via
		(at 344.932 -152.4)
		(size 0.5588)
		(drill 0.3048)
		(layers "F.Cu" "B.Cu")
		(net "GND")
	)
	(via
		(at 439.317384 -113.584228)
		(size 0.5588)
		(drill 0.3048)
		(layers "F.Cu" "B.Cu")
		(net "GND")
	)
	(via
		(at 381 -279.4)
		(size 0.5588)
		(drill 0.3048)
		(layers "F.Cu" "B.Cu")
		(net "GND")
	)
	(via
		(at 268.764004 -384.457956)
		(size 0.7112)
		(drill 0.4064)
		(layers "F.Cu" "B.Cu")
		(net "GND")
	)
	(via
		(at 339.969856 -384.47599)
		(size 0.7112)
		(drill 0.4064)
		(layers "F.Cu" "B.Cu")
		(net "GND")
	)
	(via
		(at 158.496 -214.884)
		(size 0.5588)
		(drill 0.3048)
		(layers "F.Cu" "B.Cu")
		(net "GND")
	)
	(via
		(at 323.696584 -103.61041)
		(size 0.5588)
		(drill 0.3048)
		(layers "F.Cu" "B.Cu")
		(net "GND")
	)
	(via
		(at 224.300288 -225.097594)
		(size 0.5588)
		(drill 0.3048)
		(layers "F.Cu" "B.Cu")
		(net "GND")
	)
	(via
		(at 64.117982 -384.47599)
		(size 0.7112)
		(drill 0.4064)
		(layers "F.Cu" "B.Cu")
		(net "GND")
	)
	(via
		(at 381 -330.2)
		(size 0.5588)
		(drill 0.3048)
		(layers "F.Cu" "B.Cu")
		(net "GND")
	)
	(via
		(at 95.19412 -362.864146)
		(size 0.7112)
		(drill 0.4064)
		(layers "F.Cu" "B.Cu")
		(net "GND")
	)
	(via
		(at 100.076 -41.656)
		(size 0.5588)
		(drill 0.3048)
		(layers "F.Cu" "B.Cu")
		(net "GND")
	)
	(via
		(at 28.304998 -260.815074)
		(size 0.5588)
		(drill 0.3048)
		(layers "F.Cu" "B.Cu")
		(net "GND")
	)
	(via
		(at 16.3195 -255.016)
		(size 0.5588)
		(drill 0.3048)
		(layers "F.Cu" "B.Cu")
		(net "GND")
	)
	(via
		(at 361.7214 -250.698)
		(size 0.5588)
		(drill 0.3048)
		(layers "F.Cu" "B.Cu")
		(net "GND")
	)
	(via
		(at 314.071 -54.864)
		(size 0.5588)
		(drill 0.3048)
		(layers "F.Cu" "B.Cu")
		(net "GND")
	)
	(via
		(at 186.055 -148.35505)
		(size 0.5588)
		(drill 0.3048)
		(layers "F.Cu" "B.Cu")
		(net "GND")
	)
	(via
		(at 98.8695 -261.239)
		(size 0.5588)
		(drill 0.3048)
		(layers "F.Cu" "B.Cu")
		(net "GND")
	)
	(via
		(at 453.096376 -1.524)
		(size 0.7112)
		(drill 0.4064)
		(layers "F.Cu" "B.Cu")
		(net "GND")
	)
	(via
		(at 86.5505 -250.444)
		(size 0.5588)
		(drill 0.3048)
		(layers "F.Cu" "B.Cu")
		(net "GND")
	)
	(via
		(at 52.578 -20.447)
		(size 0.5588)
		(drill 0.3048)
		(layers "F.Cu" "B.Cu")
		(net "GND")
	)
	(via
		(at 124.732796 -280.785062)
		(size 0.5588)
		(drill 0.3048)
		(layers "F.Cu" "B.Cu")
		(net "GND")
	)
	(via
		(at 406.4 -292.1)
		(size 0.5588)
		(drill 0.3048)
		(layers "F.Cu" "B.Cu")
		(net "GND")
	)
	(via
		(at 122.954796 -16.845026)
		(size 0.5588)
		(drill 0.3048)
		(layers "F.Cu" "B.Cu")
		(net "GND")
	)
	(via
		(at 332.0288 -11.43)
		(size 0.5588)
		(drill 0.3048)
		(layers "F.Cu" "B.Cu")
		(net "GND")
	)
	(via
		(at 50.1142 -263.779)
		(size 0.5588)
		(drill 0.3048)
		(layers "F.Cu" "B.Cu")
		(net "GND")
	)
	(via
		(at 358.983026 -237.035086)
		(size 0.5588)
		(drill 0.3048)
		(layers "F.Cu" "B.Cu")
		(net "GND")
	)
	(via
		(at 420.304976 -128.03505)
		(size 0.5588)
		(drill 0.3048)
		(layers "F.Cu" "B.Cu")
		(net "GND")
	)
	(via
		(at 331.47 -162.179)
		(size 0.5588)
		(drill 0.3048)
		(layers "F.Cu" "B.Cu")
		(net "GND")
	)
	(via
		(at 247.965468 -224.6884)
		(size 0.5588)
		(drill 0.3048)
		(layers "F.Cu" "B.Cu")
		(net "GND")
	)
	(via
		(at 312.523886 -7.00151)
		(size 0.7112)
		(drill 0.4064)
		(layers "F.Cu" "B.Cu")
		(net "GND")
	)
	(via
		(at 426.72 -12.319)
		(size 0.5588)
		(drill 0.3048)
		(layers "F.Cu" "B.Cu")
		(net "GND")
	)
	(via
		(at 332.105 -127.381)
		(size 0.5588)
		(drill 0.3048)
		(layers "F.Cu" "B.Cu")
		(net "GND")
	)
	(via
		(at 23.142956 -231.086914)
		(size 0.5588)
		(drill 0.3048)
		(layers "F.Cu" "B.Cu")
		(net "GND")
	)
	(via
		(at 489.926122 -310.89219)
		(size 0.7112)
		(drill 0.4064)
		(layers "F.Cu" "B.Cu")
		(net "GND")
	)
	(via
		(at 241.681 -313.182)
		(size 0.5588)
		(drill 0.3048)
		(layers "F.Cu" "B.Cu")
		(net "GND")
	)
	(via
		(at 489.926122 -239.77219)
		(size 0.7112)
		(drill 0.4064)
		(layers "F.Cu" "B.Cu")
		(net "GND")
	)
	(via
		(at 288.911284 -209.894424)
		(size 0.6604)
		(drill 0.3556)
		(layers "F.Cu" "B.Cu")
		(net "GND")
	)
	(via
		(at 451.854824 -16.845026)
		(size 0.5588)
		(drill 0.3048)
		(layers "F.Cu" "B.Cu")
		(net "GND")
	)
	(via
		(at 19.05 -133.5532)
		(size 0.5588)
		(drill 0.3048)
		(layers "F.Cu" "B.Cu")
		(net "GND")
	)
	(via
		(at 72.644 -128.524)
		(size 0.5588)
		(drill 0.3048)
		(layers "F.Cu" "B.Cu")
		(net "GND")
	)
	(via
		(at 404.749 -40.767)
		(size 0.5588)
		(drill 0.3048)
		(layers "F.Cu" "B.Cu")
		(net "GND")
	)
	(via
		(at 153.035 -92.71)
		(size 0.5588)
		(drill 0.3048)
		(layers "F.Cu" "B.Cu")
		(net "GND")
	)
	(via
		(at 244.377972 -135.665718)
		(size 0.5588)
		(drill 0.3048)
		(layers "F.Cu" "B.Cu")
		(net "GND")
	)
	(via
		(at 278.13 -157.48)
		(size 0.5588)
		(drill 0.3048)
		(layers "F.Cu" "B.Cu")
		(net "GND")
	)
	(via
		(at 18.669 -260.604)
		(size 0.5588)
		(drill 0.3048)
		(layers "F.Cu" "B.Cu")
		(net "GND")
	)
	(via
		(at 165.1 -21.336)
		(size 0.5588)
		(drill 0.3048)
		(layers "F.Cu" "B.Cu")
		(net "GND")
	)
	(via
		(at 79.4385 -25.019)
		(size 0.5588)
		(drill 0.3048)
		(layers "F.Cu" "B.Cu")
		(net "GND")
	)
	(via
		(at 358.983026 -122.035062)
		(size 0.5588)
		(drill 0.3048)
		(layers "F.Cu" "B.Cu")
		(net "GND")
	)
	(via
		(at 114.404648 -1.524)
		(size 0.7112)
		(drill 0.4064)
		(layers "F.Cu" "B.Cu")
		(net "GND")
	)
	(via
		(at 489.926122 -329.94219)
		(size 0.7112)
		(drill 0.4064)
		(layers "F.Cu" "B.Cu")
		(net "GND")
	)
	(via
		(at 180.4162 -41.3258)
		(size 0.5588)
		(drill 0.3048)
		(layers "F.Cu" "B.Cu")
		(net "GND")
	)
	(via
		(at 1.524 -5.483352)
		(size 0.7112)
		(drill 0.4064)
		(layers "F.Cu" "B.Cu")
		(net "GND")
	)
	(via
		(at 9.652 -138.176)
		(size 0.5588)
		(drill 0.3048)
		(layers "F.Cu" "B.Cu")
		(net "GND")
	)
	(via
		(at 213.8172 -204.342746)
		(size 0.5588)
		(drill 0.3048)
		(layers "F.Cu" "B.Cu")
		(net "GND")
	)
	(via
		(at 41.257982 -384.47599)
		(size 0.7112)
		(drill 0.4064)
		(layers "F.Cu" "B.Cu")
		(net "GND")
	)
	(via
		(at 386.8674 -49.1998)
		(size 0.5588)
		(drill 0.3048)
		(layers "F.Cu" "B.Cu")
		(net "GND")
	)
	(via
		(at 468.884 -174.244)
		(size 0.5588)
		(drill 0.3048)
		(layers "F.Cu" "B.Cu")
		(net "GND")
	)
	(via
		(at 129.54 -166.624)
		(size 0.5588)
		(drill 0.3048)
		(layers "F.Cu" "B.Cu")
		(net "GND")
	)
	(via
		(at 303.208436 -49.724056)
		(size 0.7112)
		(drill 0.4064)
		(layers "F.Cu" "B.Cu")
		(net "GND")
	)
	(via
		(at 1.524 -51.203352)
		(size 0.7112)
		(drill 0.4064)
		(layers "F.Cu" "B.Cu")
		(net "GND")
	)
	(via
		(at 458.725016 -384.429)
		(size 0.7112)
		(drill 0.4064)
		(layers "F.Cu" "B.Cu")
		(net "GND")
	)
	(via
		(at 364.998 -277.114)
		(size 0.5588)
		(drill 0.3048)
		(layers "F.Cu" "B.Cu")
		(net "GND")
	)
	(via
		(at 166.182294 -101.697028)
		(size 0.5588)
		(drill 0.3048)
		(layers "F.Cu" "B.Cu")
		(net "GND")
	)
	(via
		(at 393.4206 -250.8504)
		(size 0.5588)
		(drill 0.3048)
		(layers "F.Cu" "B.Cu")
		(net "GND")
	)
	(via
		(at 285.667958 -103.650288)
		(size 0.7112)
		(drill 0.4064)
		(layers "F.Cu" "B.Cu")
		(net "GND")
	)
	(via
		(at 113.665 -248.6152)
		(size 0.5588)
		(drill 0.3048)
		(layers "F.Cu" "B.Cu")
		(net "GND")
	)
	(via
		(at 489.926122 -332.48219)
		(size 0.7112)
		(drill 0.4064)
		(layers "F.Cu" "B.Cu")
		(net "GND")
	)
	(via
		(at 239.395 -202.658218)
		(size 0.5588)
		(drill 0.3048)
		(layers "F.Cu" "B.Cu")
		(net "GND")
	)
	(via
		(at 121.811796 -21.42998)
		(size 0.5588)
		(drill 0.3048)
		(layers "F.Cu" "B.Cu")
		(net "GND")
	)
	(via
		(at 398.272 -167.64)
		(size 0.5588)
		(drill 0.3048)
		(layers "F.Cu" "B.Cu")
		(net "GND")
	)
	(via
		(at 429.732186 -116.892578)
		(size 0.5588)
		(drill 0.3048)
		(layers "F.Cu" "B.Cu")
		(net "GND")
	)
	(via
		(at 307.018436 -49.724056)
		(size 0.7112)
		(drill 0.4064)
		(layers "F.Cu" "B.Cu")
		(net "GND")
	)
	(via
		(at 96.71812 -358.292146)
		(size 0.7112)
		(drill 0.4064)
		(layers "F.Cu" "B.Cu")
		(net "GND")
	)
	(via
		(at 1.524 -107.083352)
		(size 0.7112)
		(drill 0.4064)
		(layers "F.Cu" "B.Cu")
		(net "GND")
	)
	(via
		(at 431.506376 -1.524)
		(size 0.7112)
		(drill 0.4064)
		(layers "F.Cu" "B.Cu")
		(net "GND")
	)
	(via
		(at 349.504 -105.156)
		(size 0.5588)
		(drill 0.3048)
		(layers "F.Cu" "B.Cu")
		(net "GND")
	)
	(via
		(at 457.2 -317.5)
		(size 0.5588)
		(drill 0.3048)
		(layers "F.Cu" "B.Cu")
		(net "GND")
	)
	(via
		(at 279.571958 -103.624888)
		(size 0.7112)
		(drill 0.4064)
		(layers "F.Cu" "B.Cu")
		(net "GND")
	)
	(via
		(at 489.926122 -333.75219)
		(size 0.7112)
		(drill 0.4064)
		(layers "F.Cu" "B.Cu")
		(net "GND")
	)
	(via
		(at 483.404926 -268.435074)
		(size 0.5588)
		(drill 0.3048)
		(layers "F.Cu" "B.Cu")
		(net "GND")
	)
	(via
		(at 362.6612 -17.653)
		(size 0.5588)
		(drill 0.3048)
		(layers "F.Cu" "B.Cu")
		(net "GND")
	)
	(via
		(at 197.47611 -8.622538)
		(size 0.7112)
		(drill 0.4064)
		(layers "F.Cu" "B.Cu")
		(net "GND")
	)
	(via
		(at 250.571 -287.401)
		(size 0.5588)
		(drill 0.3048)
		(layers "F.Cu" "B.Cu")
		(net "GND")
	)
	(via
		(at 479.298 -162.179)
		(size 0.5588)
		(drill 0.3048)
		(layers "F.Cu" "B.Cu")
		(net "GND")
	)
	(via
		(at 22.0218 -250.4948)
		(size 0.5588)
		(drill 0.3048)
		(layers "F.Cu" "B.Cu")
		(net "GND")
	)
	(via
		(at 133.454648 -1.524)
		(size 0.7112)
		(drill 0.4064)
		(layers "F.Cu" "B.Cu")
		(net "GND")
	)
	(via
		(at 1.524 -109.623352)
		(size 0.7112)
		(drill 0.4064)
		(layers "F.Cu" "B.Cu")
		(net "GND")
	)
	(via
		(at 489.926122 -187.70219)
		(size 0.7112)
		(drill 0.4064)
		(layers "F.Cu" "B.Cu")
		(net "GND")
	)
	(via
		(at 1.524 -70.253352)
		(size 0.7112)
		(drill 0.4064)
		(layers "F.Cu" "B.Cu")
		(net "GND")
	)
	(via
		(at 161.394648 -1.524)
		(size 0.7112)
		(drill 0.4064)
		(layers "F.Cu" "B.Cu")
		(net "GND")
	)
	(via
		(at 292.1 -76.2)
		(size 0.5588)
		(drill 0.3048)
		(layers "F.Cu" "B.Cu")
		(net "GND")
	)
	(via
		(at 45.824648 -1.524)
		(size 0.7112)
		(drill 0.4064)
		(layers "F.Cu" "B.Cu")
		(net "GND")
	)
	(via
		(at 197.47611 -44.182538)
		(size 0.7112)
		(drill 0.4064)
		(layers "F.Cu" "B.Cu")
		(net "GND")
	)
	(via
		(at 447.015616 -101.764338)
		(size 0.5588)
		(drill 0.3048)
		(layers "F.Cu" "B.Cu")
		(net "GND")
	)
	(via
		(at 153.653998 -384.47599)
		(size 0.7112)
		(drill 0.4064)
		(layers "F.Cu" "B.Cu")
		(net "GND")
	)
	(via
		(at 458.070204 -368.9604)
		(size 0.5588)
		(drill 0.3048)
		(layers "F.Cu" "B.Cu")
		(net "GND")
	)
	(via
		(at 72.644 -124.46)
		(size 0.5588)
		(drill 0.3048)
		(layers "F.Cu" "B.Cu")
		(net "GND")
	)
	(via
		(at 129.644648 -1.524)
		(size 0.7112)
		(drill 0.4064)
		(layers "F.Cu" "B.Cu")
		(net "GND")
	)
	(via
		(at 1.524 -137.563352)
		(size 0.7112)
		(drill 0.4064)
		(layers "F.Cu" "B.Cu")
		(net "GND")
	)
	(via
		(at 333.248 -206.248)
		(size 0.5588)
		(drill 0.3048)
		(layers "F.Cu" "B.Cu")
		(net "GND")
	)
	(via
		(at 457.2 -226.949)
		(size 0.5588)
		(drill 0.3048)
		(layers "F.Cu" "B.Cu")
		(net "GND")
	)
	(via
		(at 1.524 -89.303352)
		(size 0.7112)
		(drill 0.4064)
		(layers "F.Cu" "B.Cu")
		(net "GND")
	)
	(via
		(at 149.843998 -384.47599)
		(size 0.7112)
		(drill 0.4064)
		(layers "F.Cu" "B.Cu")
		(net "GND")
	)
	(via
		(at 365.252 -38.227)
		(size 0.5588)
		(drill 0.3048)
		(layers "F.Cu" "B.Cu")
		(net "GND")
	)
	(via
		(at 113.0554 -263.779)
		(size 0.5588)
		(drill 0.3048)
		(layers "F.Cu" "B.Cu")
		(net "GND")
	)
	(via
		(at 319.89903 -96.270826)
		(size 0.5588)
		(drill 0.3048)
		(layers "F.Cu" "B.Cu")
		(net "GND")
	)
	(via
		(at 133.279388 -364.835948)
		(size 0.5588)
		(drill 0.3048)
		(layers "F.Cu" "B.Cu")
		(net "GND")
	)
	(via
		(at 176.149 -172.72)
		(size 0.5588)
		(drill 0.3048)
		(layers "F.Cu" "B.Cu")
		(net "GND")
	)
	(via
		(at 33.637982 -384.47599)
		(size 0.7112)
		(drill 0.4064)
		(layers "F.Cu" "B.Cu")
		(net "GND")
	)
	(via
		(at 330.1746 -135.6868)
		(size 0.5588)
		(drill 0.3048)
		(layers "F.Cu" "B.Cu")
		(net "GND")
	)
	(via
		(at 462.54416 -384.38201)
		(size 0.7112)
		(drill 0.4064)
		(layers "F.Cu" "B.Cu")
		(net "GND")
	)
	(via
		(at 357.205026 -33.355026)
		(size 0.5588)
		(drill 0.3048)
		(layers "F.Cu" "B.Cu")
		(net "GND")
	)
	(via
		(at 435.855872 -384.47599)
		(size 0.7112)
		(drill 0.4064)
		(layers "F.Cu" "B.Cu")
		(net "GND")
	)
	(via
		(at 402.336 -164.592)
		(size 0.5588)
		(drill 0.3048)
		(layers "F.Cu" "B.Cu")
		(net "GND")
	)
	(via
		(at 364.998 -162.179)
		(size 0.5588)
		(drill 0.3048)
		(layers "F.Cu" "B.Cu")
		(net "GND")
	)
	(via
		(at 312.523886 -5.73151)
		(size 0.7112)
		(drill 0.4064)
		(layers "F.Cu" "B.Cu")
		(net "GND")
	)
	(via
		(at 428.117 -277.114)
		(size 0.5588)
		(drill 0.3048)
		(layers "F.Cu" "B.Cu")
		(net "GND")
	)
	(via
		(at 489.926122 -144.52219)
		(size 0.7112)
		(drill 0.4064)
		(layers "F.Cu" "B.Cu")
		(net "GND")
	)
	(via
		(at 17.154906 -380.775972)
		(size 0.7112)
		(drill 0.4064)
		(layers "F.Cu" "B.Cu")
		(net "GND")
	)
	(via
		(at 318.379856 -384.47599)
		(size 0.7112)
		(drill 0.4064)
		(layers "F.Cu" "B.Cu")
		(net "GND")
	)
	(via
		(at 264.260076 -196.032882)
		(size 0.7112)
		(drill 0.4064)
		(layers "F.Cu" "B.Cu")
		(net "GND")
	)
	(via
		(at 419.223952 -383.32791)
		(size 0.7112)
		(drill 0.4064)
		(layers "F.Cu" "B.Cu")
		(net "GND")
	)
	(via
		(at 111.975646 -28.358592)
		(size 0.5588)
		(drill 0.3048)
		(layers "F.Cu" "B.Cu")
		(net "GND")
	)
	(via
		(at 489.926122 -108.96219)
		(size 0.7112)
		(drill 0.4064)
		(layers "F.Cu" "B.Cu")
		(net "GND")
	)
	(via
		(at 40.64 -249.428)
		(size 0.5588)
		(drill 0.3048)
		(layers "F.Cu" "B.Cu")
		(net "GND")
	)
	(via
		(at 109.324648 -1.524)
		(size 0.7112)
		(drill 0.4064)
		(layers "F.Cu" "B.Cu")
		(net "GND")
	)
	(via
		(at 1.524 -1.673352)
		(size 0.7112)
		(drill 0.4064)
		(layers "F.Cu" "B.Cu")
		(net "GND")
	)
	(via
		(at 308.257194 -211.310728)
		(size 0.5588)
		(drill 0.3048)
		(layers "F.Cu" "B.Cu")
		(net "GND")
	)
	(via
		(at 420.304976 -243.035074)
		(size 0.5588)
		(drill 0.3048)
		(layers "F.Cu" "B.Cu")
		(net "GND")
	)
	(via
		(at 32.2326 -10.033)
		(size 0.5588)
		(drill 0.3048)
		(layers "F.Cu" "B.Cu")
		(net "GND")
	)
	(via
		(at 2.794 -369.697)
		(size 0.7112)
		(drill 0.4064)
		(layers "F.Cu" "B.Cu")
		(net "GND")
	)
	(via
		(at 196.476112 -381.168148)
		(size 0.7112)
		(drill 0.4064)
		(layers "F.Cu" "B.Cu")
		(net "GND")
	)
	(via
		(at 21.844 -366.776)
		(size 0.5588)
		(drill 0.3048)
		(layers "F.Cu" "B.Cu")
		(net "GND")
	)
	(via
		(at 85.1408 -250.4948)
		(size 0.5588)
		(drill 0.3048)
		(layers "F.Cu" "B.Cu")
		(net "GND")
	)
	(via
		(at 232.867962 -378.476002)
		(size 0.7112)
		(drill 0.4064)
		(layers "F.Cu" "B.Cu")
		(net "GND")
	)
	(via
		(at 1.524 -155.343352)
		(size 0.7112)
		(drill 0.4064)
		(layers "F.Cu" "B.Cu")
		(net "GND")
	)
	(via
		(at 260.511544 -217.124026)
		(size 0.5588)
		(drill 0.3048)
		(layers "F.Cu" "B.Cu")
		(net "GND")
	)
	(via
		(at 72.263 -249.428)
		(size 0.5588)
		(drill 0.3048)
		(layers "F.Cu" "B.Cu")
		(net "GND")
	)
	(via
		(at 31.854648 -1.524)
		(size 0.7112)
		(drill 0.4064)
		(layers "F.Cu" "B.Cu")
		(net "GND")
	)
	(via
		(at 432.045872 -384.47599)
		(size 0.7112)
		(drill 0.4064)
		(layers "F.Cu" "B.Cu")
		(net "GND")
	)
	(via
		(at 197.47611 -16.242538)
		(size 0.7112)
		(drill 0.4064)
		(layers "F.Cu" "B.Cu")
		(net "GND")
	)
	(via
		(at 197.47611 -17.512538)
		(size 0.7112)
		(drill 0.4064)
		(layers "F.Cu" "B.Cu")
		(net "GND")
	)
	(via
		(at 1.524 -363.623352)
		(size 0.7112)
		(drill 0.4064)
		(layers "F.Cu" "B.Cu")
		(net "GND")
	)
	(via
		(at 489.926122 -110.23219)
		(size 0.7112)
		(drill 0.4064)
		(layers "F.Cu" "B.Cu")
		(net "GND")
	)
	(via
		(at 419.1 -190.5)
		(size 0.5588)
		(drill 0.3048)
		(layers "F.Cu" "B.Cu")
		(net "GND")
	)
	(via
		(at 12.7 -330.2)
		(size 0.5588)
		(drill 0.3048)
		(layers "F.Cu" "B.Cu")
		(net "GND")
	)
	(via
		(at 403.801072 -101.759004)
		(size 0.5588)
		(drill 0.3048)
		(layers "F.Cu" "B.Cu")
		(net "GND")
	)
	(via
		(at 174.752 -125.984)
		(size 0.5588)
		(drill 0.3048)
		(layers "F.Cu" "B.Cu")
		(net "GND")
	)
	(via
		(at 460.883 -250.317)
		(size 0.5588)
		(drill 0.3048)
		(layers "F.Cu" "B.Cu")
		(net "GND")
	)
	(via
		(at 1.524 -268.373352)
		(size 0.7112)
		(drill 0.4064)
		(layers "F.Cu" "B.Cu")
		(net "GND")
	)
	(via
		(at 334.264 -106.426)
		(size 0.5588)
		(drill 0.3048)
		(layers "F.Cu" "B.Cu")
		(net "GND")
	)
	(via
		(at 139.7 -279.4)
		(size 0.5588)
		(drill 0.3048)
		(layers "F.Cu" "B.Cu")
		(net "GND")
	)
	(via
		(at 489.926122 -284.22219)
		(size 0.7112)
		(drill 0.4064)
		(layers "F.Cu" "B.Cu")
		(net "GND")
	)
	(via
		(at 363.601 -127.381)
		(size 0.5588)
		(drill 0.3048)
		(layers "F.Cu" "B.Cu")
		(net "GND")
	)
	(via
		(at 82.169 -133.5532)
		(size 0.5588)
		(drill 0.3048)
		(layers "F.Cu" "B.Cu")
		(net "GND")
	)
	(via
		(at 420.304976 -20.655026)
		(size 0.5588)
		(drill 0.3048)
		(layers "F.Cu" "B.Cu")
		(net "GND")
	)
	(via
		(at 428.371 -153.289)
		(size 0.5588)
		(drill 0.3048)
		(layers "F.Cu" "B.Cu")
		(net "GND")
	)
	(via
		(at 8.994648 -1.524)
		(size 0.7112)
		(drill 0.4064)
		(layers "F.Cu" "B.Cu")
		(net "GND")
	)
	(via
		(at 489.926122 -313.43219)
		(size 0.7112)
		(drill 0.4064)
		(layers "F.Cu" "B.Cu")
		(net "GND")
	)
	(via
		(at 45.067982 -384.47599)
		(size 0.7112)
		(drill 0.4064)
		(layers "F.Cu" "B.Cu")
		(net "GND")
	)
	(via
		(at 222.213932 -192.278508)
		(size 0.5588)
		(drill 0.3048)
		(layers "F.Cu" "B.Cu")
		(net "GND")
	)
	(via
		(at 1.524 -262.023352)
		(size 0.7112)
		(drill 0.4064)
		(layers "F.Cu" "B.Cu")
		(net "GND")
	)
	(via
		(at 489.926122 -181.35219)
		(size 0.7112)
		(drill 0.4064)
		(layers "F.Cu" "B.Cu")
		(net "GND")
	)
	(via
		(at 143.493998 -384.47599)
		(size 0.7112)
		(drill 0.4064)
		(layers "F.Cu" "B.Cu")
		(net "GND")
	)
	(via
		(at 183.4388 -375.1326)
		(size 0.5588)
		(drill 0.3048)
		(layers "F.Cu" "B.Cu")
		(net "GND")
	)
	(via
		(at 489.926122 -48.00219)
		(size 0.7112)
		(drill 0.4064)
		(layers "F.Cu" "B.Cu")
		(net "GND")
	)
	(via
		(at 455.636376 -1.524)
		(size 0.7112)
		(drill 0.4064)
		(layers "F.Cu" "B.Cu")
		(net "GND")
	)
	(via
		(at 210.007962 -378.476002)
		(size 0.7112)
		(drill 0.4064)
		(layers "F.Cu" "B.Cu")
		(net "GND")
	)
	(via
		(at 365.466376 -1.524)
		(size 0.7112)
		(drill 0.4064)
		(layers "F.Cu" "B.Cu")
		(net "GND")
	)
	(via
		(at 160.003998 -384.47599)
		(size 0.7112)
		(drill 0.4064)
		(layers "F.Cu" "B.Cu")
		(net "GND")
	)
	(via
		(at 118.872 -47.244)
		(size 0.5588)
		(drill 0.3048)
		(layers "F.Cu" "B.Cu")
		(net "GND")
	)
	(via
		(at 116.84 -118.872)
		(size 0.5588)
		(drill 0.3048)
		(layers "F.Cu" "B.Cu")
		(net "GND")
	)
	(via
		(at 108.712 -109.22)
		(size 0.5588)
		(drill 0.3048)
		(layers "F.Cu" "B.Cu")
		(net "GND")
	)
	(via
		(at 289.000692 -384.47599)
		(size 0.7112)
		(drill 0.4064)
		(layers "F.Cu" "B.Cu")
		(net "GND")
	)
	(via
		(at 81.047844 -333.554832)
		(size 0.5588)
		(drill 0.3048)
		(layers "F.Cu" "B.Cu")
		(net "GND")
	)
	(via
		(at 489.926122 -268.98219)
		(size 0.7112)
		(drill 0.4064)
		(layers "F.Cu" "B.Cu")
		(net "GND")
	)
	(via
		(at 459.1558 -129.921)
		(size 0.5588)
		(drill 0.3048)
		(layers "F.Cu" "B.Cu")
		(net "GND")
	)
	(via
		(at 456.946 -268.605)
		(size 0.5588)
		(drill 0.3048)
		(layers "F.Cu" "B.Cu")
		(net "GND")
	)
	(via
		(at 10.622026 -384.47599)
		(size 0.7112)
		(drill 0.4064)
		(layers "F.Cu" "B.Cu")
		(net "GND")
	)
	(via
		(at 197.47611 -45.452538)
		(size 0.7112)
		(drill 0.4064)
		(layers "F.Cu" "B.Cu")
		(net "GND")
	)
	(via
		(at 87.296752 -341.054944)
		(size 0.5588)
		(drill 0.3048)
		(layers "F.Cu" "B.Cu")
		(net "GND")
	)
	(via
		(at 184.912 -138.83005)
		(size 0.5588)
		(drill 0.3048)
		(layers "F.Cu" "B.Cu")
		(net "GND")
	)
	(via
		(at 312.523886 -46.37151)
		(size 0.7112)
		(drill 0.4064)
		(layers "F.Cu" "B.Cu")
		(net "GND")
	)
	(via
		(at 148.2598 -250.4948)
		(size 0.5588)
		(drill 0.3048)
		(layers "F.Cu" "B.Cu")
		(net "GND")
	)
	(via
		(at 362.966 -277.114)
		(size 0.5588)
		(drill 0.3048)
		(layers "F.Cu" "B.Cu")
		(net "GND")
	)
	(via
		(at 436.586376 -1.524)
		(size 0.7112)
		(drill 0.4064)
		(layers "F.Cu" "B.Cu")
		(net "GND")
	)
	(via
		(at 252.2474 -369.9637)
		(size 0.5588)
		(drill 0.3048)
		(layers "F.Cu" "B.Cu")
		(net "GND")
	)
	(via
		(at 482.261926 -21.42998)
		(size 0.5588)
		(drill 0.3048)
		(layers "F.Cu" "B.Cu")
		(net "GND")
	)
	(via
		(at 1.524 -21.993352)
		(size 0.7112)
		(drill 0.4064)
		(layers "F.Cu" "B.Cu")
		(net "GND")
	)
	(via
		(at 341.884 -178.816)
		(size 0.5588)
		(drill 0.3048)
		(layers "F.Cu" "B.Cu")
		(net "GND")
	)
	(via
		(at 406.146 -239.014)
		(size 0.5588)
		(drill 0.3048)
		(layers "F.Cu" "B.Cu")
		(net "GND")
	)
	(via
		(at 115.316 -174.244)
		(size 0.5588)
		(drill 0.3048)
		(layers "F.Cu" "B.Cu")
		(net "GND")
	)
	(via
		(at 25.146 -381.254)
		(size 0.7112)
		(drill 0.4064)
		(layers "F.Cu" "B.Cu")
		(net "GND")
	)
	(via
		(at 197.47611 -12.432538)
		(size 0.7112)
		(drill 0.4064)
		(layers "F.Cu" "B.Cu")
		(net "GND")
	)
	(via
		(at 161.273998 -384.47599)
		(size 0.7112)
		(drill 0.4064)
		(layers "F.Cu" "B.Cu")
		(net "GND")
	)
	(via
		(at 12.7 -304.8)
		(size 0.5588)
		(drill 0.3048)
		(layers "F.Cu" "B.Cu")
		(net "GND")
	)
	(via
		(at 180.848 -15.98676)
		(size 0.5588)
		(drill 0.3048)
		(layers "F.Cu" "B.Cu")
		(net "GND")
	)
	(via
		(at 381 -368.3)
		(size 0.5588)
		(drill 0.3048)
		(layers "F.Cu" "B.Cu")
		(net "GND")
	)
	(via
		(at 180.34 -241.427)
		(size 0.5588)
		(drill 0.3048)
		(layers "F.Cu" "B.Cu")
		(net "GND")
	)
	(via
		(at 489.926122 -64.51219)
		(size 0.7112)
		(drill 0.4064)
		(layers "F.Cu" "B.Cu")
		(net "GND")
	)
	(via
		(at 401.066 -238.76)
		(size 0.5588)
		(drill 0.3048)
		(layers "F.Cu" "B.Cu")
		(net "GND")
	)
	(via
		(at 27.161998 -136.430004)
		(size 0.5588)
		(drill 0.3048)
		(layers "F.Cu" "B.Cu")
		(net "GND")
	)
	(via
		(at 184.912 -141.230096)
		(size 0.5588)
		(drill 0.3048)
		(layers "F.Cu" "B.Cu")
		(net "GND")
	)
	(via
		(at 459.627986 -122.556778)
		(size 0.5588)
		(drill 0.3048)
		(layers "F.Cu" "B.Cu")
		(net "GND")
	)
	(via
		(at 489.926122 -125.47219)
		(size 0.7112)
		(drill 0.4064)
		(layers "F.Cu" "B.Cu")
		(net "GND")
	)
	(via
		(at 1.524 -72.793352)
		(size 0.7112)
		(drill 0.4064)
		(layers "F.Cu" "B.Cu")
		(net "GND")
	)
	(via
		(at 340.066376 -1.524)
		(size 0.7112)
		(drill 0.4064)
		(layers "F.Cu" "B.Cu")
		(net "GND")
	)
	(via
		(at 26.774648 -1.524)
		(size 0.7112)
		(drill 0.4064)
		(layers "F.Cu" "B.Cu")
		(net "GND")
	)
	(via
		(at 134.724648 -1.524)
		(size 0.7112)
		(drill 0.4064)
		(layers "F.Cu" "B.Cu")
		(net "GND")
	)
	(via
		(at 362.331 -153.67)
		(size 0.5588)
		(drill 0.3048)
		(layers "F.Cu" "B.Cu")
		(net "GND")
	)
	(via
		(at 392.684 -28.448)
		(size 0.5588)
		(drill 0.3048)
		(layers "F.Cu" "B.Cu")
		(net "GND")
	)
	(via
		(at 368.3 -88.9)
		(size 0.5588)
		(drill 0.3048)
		(layers "F.Cu" "B.Cu")
		(net "GND")
	)
	(via
		(at 122.812302 -136.121648)
		(size 0.5588)
		(drill 0.3048)
		(layers "F.Cu" "B.Cu")
		(net "GND")
	)
	(via
		(at 93.182948 -122.035062)
		(size 0.5588)
		(drill 0.3048)
		(layers "F.Cu" "B.Cu")
		(net "GND")
	)
	(via
		(at 142.5575 -25.019)
		(size 0.5588)
		(drill 0.3048)
		(layers "F.Cu" "B.Cu")
		(net "GND")
	)
	(via
		(at 116.6368 -250.4948)
		(size 0.5588)
		(drill 0.3048)
		(layers "F.Cu" "B.Cu")
		(net "GND")
	)
	(via
		(at 375.626376 -1.524)
		(size 0.7112)
		(drill 0.4064)
		(layers "F.Cu" "B.Cu")
		(net "GND")
	)
	(via
		(at 165.1 -195.58)
		(size 0.5588)
		(drill 0.3048)
		(layers "F.Cu" "B.Cu")
		(net "GND")
	)
	(via
		(at 154.504898 -16.845026)
		(size 0.5588)
		(drill 0.3048)
		(layers "F.Cu" "B.Cu")
		(net "GND")
	)
	(via
		(at 489.926122 -103.88219)
		(size 0.7112)
		(drill 0.4064)
		(layers "F.Cu" "B.Cu")
		(net "GND")
	)
	(via
		(at 3.937 -370.459)
		(size 0.7112)
		(drill 0.4064)
		(layers "F.Cu" "B.Cu")
		(net "GND")
	)
	(via
		(at 73.152 -61.468)
		(size 0.5588)
		(drill 0.3048)
		(layers "F.Cu" "B.Cu")
		(net "GND")
	)
	(via
		(at 489.926122 -26.41219)
		(size 0.7112)
		(drill 0.4064)
		(layers "F.Cu" "B.Cu")
		(net "GND")
	)
	(via
		(at 310.82742 -326.593962)
		(size 0.5588)
		(drill 0.3048)
		(layers "F.Cu" "B.Cu")
		(net "GND")
	)
	(via
		(at 87.296752 -339.784944)
		(size 0.5588)
		(drill 0.3048)
		(layers "F.Cu" "B.Cu")
		(net "GND")
	)
	(via
		(at 446.9765 -146.304)
		(size 0.5588)
		(drill 0.3048)
		(layers "F.Cu" "B.Cu")
		(net "GND")
	)
	(via
		(at 312.523886 -42.56151)
		(size 0.7112)
		(drill 0.4064)
		(layers "F.Cu" "B.Cu")
		(net "GND")
	)
	(via
		(at 1.524 -152.803352)
		(size 0.7112)
		(drill 0.4064)
		(layers "F.Cu" "B.Cu")
		(net "GND")
	)
	(via
		(at 98.827844 -333.554832)
		(size 0.5588)
		(drill 0.3048)
		(layers "F.Cu" "B.Cu")
		(net "GND")
	)
	(via
		(at 178.565048 -380.775972)
		(size 0.7112)
		(drill 0.4064)
		(layers "F.Cu" "B.Cu")
		(net "GND")
	)
	(via
		(at 489.926122 -312.16219)
		(size 0.7112)
		(drill 0.4064)
		(layers "F.Cu" "B.Cu")
		(net "GND")
	)
	(via
		(at 489.926122 -87.37219)
		(size 0.7112)
		(drill 0.4064)
		(layers "F.Cu" "B.Cu")
		(net "GND")
	)
	(via
		(at 34.544 -231.648)
		(size 0.5588)
		(drill 0.3048)
		(layers "F.Cu" "B.Cu")
		(net "GND")
	)
	(via
		(at 270.52397 -58.90133)
		(size 0.7112)
		(drill 0.4064)
		(layers "F.Cu" "B.Cu")
		(net "GND")
	)
	(via
		(at 446.024 -173.736)
		(size 0.5588)
		(drill 0.3048)
		(layers "F.Cu" "B.Cu")
		(net "GND")
	)
	(via
		(at 92.37599 -378.476002)
		(size 0.7112)
		(drill 0.4064)
		(layers "F.Cu" "B.Cu")
		(net "GND")
	)
	(via
		(at 1.524 -91.843352)
		(size 0.7112)
		(drill 0.4064)
		(layers "F.Cu" "B.Cu")
		(net "GND")
	)
	(via
		(at 366.395 -135.128)
		(size 0.5588)
		(drill 0.3048)
		(layers "F.Cu" "B.Cu")
		(net "GND")
	)
	(via
		(at 217.1954 -65.666874)
		(size 0.6604)
		(drill 0.3556)
		(layers "F.Cu" "B.Cu")
		(net "GND")
	)
	(via
		(at 205.3082 -304.1142)
		(size 0.7112)
		(drill 0.4064)
		(layers "F.Cu" "B.Cu")
		(net "GND")
	)
	(via
		(at 127.762 -380.746)
		(size 0.7112)
		(drill 0.4064)
		(layers "F.Cu" "B.Cu")
		(net "GND")
	)
	(via
		(at 330.835 -268.605)
		(size 0.5588)
		(drill 0.3048)
		(layers "F.Cu" "B.Cu")
		(net "GND")
	)
	(via
		(at 443.475872 -384.47599)
		(size 0.7112)
		(drill 0.4064)
		(layers "F.Cu" "B.Cu")
		(net "GND")
	)
	(via
		(at 482.261926 -26.230072)
		(size 0.5588)
		(drill 0.3048)
		(layers "F.Cu" "B.Cu")
		(net "GND")
	)
	(via
		(at 253.524004 -381.917956)
		(size 0.7112)
		(drill 0.4064)
		(layers "F.Cu" "B.Cu")
		(net "GND")
	)
	(via
		(at 1.524 -326.793352)
		(size 0.7112)
		(drill 0.4064)
		(layers "F.Cu" "B.Cu")
		(net "GND")
	)
	(via
		(at 278.274018 -373.648478)
		(size 0.7112)
		(drill 0.4064)
		(layers "F.Cu" "B.Cu")
		(net "GND")
	)
	(via
		(at 474.091 -128.8415)
		(size 0.5588)
		(drill 0.3048)
		(layers "F.Cu" "B.Cu")
		(net "GND")
	)
	(via
		(at 240.867692 -308.737)
		(size 0.5588)
		(drill 0.3048)
		(layers "F.Cu" "B.Cu")
		(net "GND")
	)
	(via
		(at 474.843602 -233.94035)
		(size 0.5588)
		(drill 0.3048)
		(layers "F.Cu" "B.Cu")
		(net "GND")
	)
	(via
		(at 469.9 -330.2)
		(size 0.5588)
		(drill 0.3048)
		(layers "F.Cu" "B.Cu")
		(net "GND")
	)
	(via
		(at 1.524 -319.173352)
		(size 0.7112)
		(drill 0.4064)
		(layers "F.Cu" "B.Cu")
		(net "GND")
	)
	(via
		(at 424.021504 -363.0168)
		(size 0.5588)
		(drill 0.3048)
		(layers "F.Cu" "B.Cu")
		(net "GND")
	)
	(via
		(at 1.524 -18.183352)
		(size 0.7112)
		(drill 0.4064)
		(layers "F.Cu" "B.Cu")
		(net "GND")
	)
	(via
		(at 307.848 -346.964)
		(size 0.5588)
		(drill 0.3048)
		(layers "F.Cu" "B.Cu")
		(net "GND")
	)
	(via
		(at 9.652 -21.844)
		(size 0.5588)
		(drill 0.3048)
		(layers "F.Cu" "B.Cu")
		(net "GND")
	)
	(via
		(at 431.8 -177.8)
		(size 0.5588)
		(drill 0.3048)
		(layers "F.Cu" "B.Cu")
		(net "GND")
	)
	(via
		(at 351.028 -174.752)
		(size 0.5588)
		(drill 0.3048)
		(layers "F.Cu" "B.Cu")
		(net "GND")
	)
	(via
		(at 1.524 -188.363352)
		(size 0.7112)
		(drill 0.4064)
		(layers "F.Cu" "B.Cu")
		(net "GND")
	)
	(via
		(at 1.524 -193.443352)
		(size 0.7112)
		(drill 0.4064)
		(layers "F.Cu" "B.Cu")
		(net "GND")
	)
	(via
		(at 1.524 -30.883352)
		(size 0.7112)
		(drill 0.4064)
		(layers "F.Cu" "B.Cu")
		(net "GND")
	)
	(via
		(at 85.725 -41.3258)
		(size 0.5588)
		(drill 0.3048)
		(layers "F.Cu" "B.Cu")
		(net "GND")
	)
	(via
		(at 302.26 -118.364)
		(size 0.5588)
		(drill 0.3048)
		(layers "F.Cu" "B.Cu")
		(net "GND")
	)
	(via
		(at 12.7 -279.4)
		(size 0.5588)
		(drill 0.3048)
		(layers "F.Cu" "B.Cu")
		(net "GND")
	)
	(via
		(at 387.611874 -23.830026)
		(size 0.5588)
		(drill 0.3048)
		(layers "F.Cu" "B.Cu")
		(net "GND")
	)
	(via
		(at 73.764648 -1.524)
		(size 0.7112)
		(drill 0.4064)
		(layers "F.Cu" "B.Cu")
		(net "GND")
	)
	(via
		(at 177.292 -279.908)
		(size 0.5588)
		(drill 0.3048)
		(layers "F.Cu" "B.Cu")
		(net "GND")
	)
	(via
		(at 207.6704 -144.0434)
		(size 0.7112)
		(drill 0.4064)
		(layers "F.Cu" "B.Cu")
		(net "GND")
	)
	(via
		(at 469.9 -101.6)
		(size 0.5588)
		(drill 0.3048)
		(layers "F.Cu" "B.Cu")
		(net "GND")
	)
	(via
		(at 27.161998 -23.830026)
		(size 0.5588)
		(drill 0.3048)
		(layers "F.Cu" "B.Cu")
		(net "GND")
	)
	(via
		(at 39.624 -195.072)
		(size 0.5588)
		(drill 0.3048)
		(layers "F.Cu" "B.Cu")
		(net "GND")
	)
	(via
		(at 142.344648 -1.524)
		(size 0.7112)
		(drill 0.4064)
		(layers "F.Cu" "B.Cu")
		(net "GND")
	)
	(via
		(at 167.95115 -101.787452)
		(size 0.5588)
		(drill 0.3048)
		(layers "F.Cu" "B.Cu")
		(net "GND")
	)
	(via
		(at 156.282898 -237.035086)
		(size 0.5588)
		(drill 0.3048)
		(layers "F.Cu" "B.Cu")
		(net "GND")
	)
	(via
		(at 332.74 -218.44)
		(size 0.5588)
		(drill 0.3048)
		(layers "F.Cu" "B.Cu")
		(net "GND")
	)
	(via
		(at 11.877802 -226.44735)
		(size 0.5588)
		(drill 0.3048)
		(layers "F.Cu" "B.Cu")
		(net "GND")
	)
	(via
		(at 163.576 -141.732)
		(size 0.5588)
		(drill 0.3048)
		(layers "F.Cu" "B.Cu")
		(net "GND")
	)
	(via
		(at 75.692 -265.684)
		(size 0.5588)
		(drill 0.3048)
		(layers "F.Cu" "B.Cu")
		(net "GND")
	)
	(via
		(at 451.854824 -270.975074)
		(size 0.5588)
		(drill 0.3048)
		(layers "F.Cu" "B.Cu")
		(net "GND")
	)
	(via
		(at 186.829954 -384.47599)
		(size 0.7112)
		(drill 0.4064)
		(layers "F.Cu" "B.Cu")
		(net "GND")
	)
	(via
		(at 105.471468 -211.298028)
		(size 0.5588)
		(drill 0.3048)
		(layers "F.Cu" "B.Cu")
		(net "GND")
	)
	(via
		(at 28.304998 -33.355026)
		(size 0.5588)
		(drill 0.3048)
		(layers "F.Cu" "B.Cu")
		(net "GND")
	)
	(via
		(at 461.645 -8.3058)
		(size 0.5588)
		(drill 0.3048)
		(layers "F.Cu" "B.Cu")
		(net "GND")
	)
	(via
		(at 121.811796 -251.430028)
		(size 0.5588)
		(drill 0.3048)
		(layers "F.Cu" "B.Cu")
		(net "GND")
	)
	(via
		(at 437.856376 -1.524)
		(size 0.7112)
		(drill 0.4064)
		(layers "F.Cu" "B.Cu")
		(net "GND")
	)
	(via
		(at 478.450402 -233.94035)
		(size 0.5588)
		(drill 0.3048)
		(layers "F.Cu" "B.Cu")
		(net "GND")
	)
	(via
		(at 71.224648 -1.524)
		(size 0.7112)
		(drill 0.4064)
		(layers "F.Cu" "B.Cu")
		(net "GND")
	)
	(via
		(at 482.6 -177.8)
		(size 0.5588)
		(drill 0.3048)
		(layers "F.Cu" "B.Cu")
		(net "GND")
	)
	(via
		(at 147.103592 -211.432394)
		(size 0.5588)
		(drill 0.3048)
		(layers "F.Cu" "B.Cu")
		(net "GND")
	)
	(via
		(at 202.387962 -378.476002)
		(size 0.7112)
		(drill 0.4064)
		(layers "F.Cu" "B.Cu")
		(net "GND")
	)
	(via
		(at 1.524 -278.533352)
		(size 0.7112)
		(drill 0.4064)
		(layers "F.Cu" "B.Cu")
		(net "GND")
	)
	(via
		(at 20.424648 -1.524)
		(size 0.7112)
		(drill 0.4064)
		(layers "F.Cu" "B.Cu")
		(net "GND")
	)
	(via
		(at 489.926122 -249.93219)
		(size 0.7112)
		(drill 0.4064)
		(layers "F.Cu" "B.Cu")
		(net "GND")
	)
	(via
		(at 329.819 -47.117)
		(size 0.5588)
		(drill 0.3048)
		(layers "F.Cu" "B.Cu")
		(net "GND")
	)
	(via
		(at 78.406752 -344.864944)
		(size 0.5588)
		(drill 0.3048)
		(layers "F.Cu" "B.Cu")
		(net "GND")
	)
	(via
		(at 375.099326 -216.497154)
		(size 0.5588)
		(drill 0.3048)
		(layers "F.Cu" "B.Cu")
		(net "GND")
	)
	(via
		(at 282.523692 -157.098492)
		(size 0.5588)
		(drill 0.3048)
		(layers "F.Cu" "B.Cu")
		(net "GND")
	)
	(via
		(at 482.261926 -141.230096)
		(size 0.5588)
		(drill 0.3048)
		(layers "F.Cu" "B.Cu")
		(net "GND")
	)
	(via
		(at 1.524 -122.323352)
		(size 0.7112)
		(drill 0.4064)
		(layers "F.Cu" "B.Cu")
		(net "GND")
	)
	(via
		(at 451.854824 -268.435074)
		(size 0.5588)
		(drill 0.3048)
		(layers "F.Cu" "B.Cu")
		(net "GND")
	)
	(via
		(at 448.461384 -359.315258)
		(size 0.6604)
		(drill 0.3302)
		(layers "F.Cu" "B.Cu")
		(net "GND")
	)
	(via
		(at 489.926122 -116.58219)
		(size 0.7112)
		(drill 0.4064)
		(layers "F.Cu" "B.Cu")
		(net "GND")
	)
	(via
		(at 205.3082 -306.5526)
		(size 0.7112)
		(drill 0.4064)
		(layers "F.Cu" "B.Cu")
		(net "GND")
	)
	(via
		(at 424.434762 -48.42129)
		(size 0.5588)
		(drill 0.3048)
		(layers "F.Cu" "B.Cu")
		(net "GND")
	)
	(via
		(at 86.868 -192.532)
		(size 0.5588)
		(drill 0.3048)
		(layers "F.Cu" "B.Cu")
		(net "GND")
	)
	(via
		(at 1.524 -270.913352)
		(size 0.7112)
		(drill 0.4064)
		(layers "F.Cu" "B.Cu")
		(net "GND")
	)
	(via
		(at 30.082998 -7.035038)
		(size 0.5588)
		(drill 0.3048)
		(layers "F.Cu" "B.Cu")
		(net "GND")
	)
	(via
		(at 201.7014 -306.5526)
		(size 0.7112)
		(drill 0.4064)
		(layers "F.Cu" "B.Cu")
		(net "GND")
	)
	(via
		(at 39.303198 -217.13063)
		(size 0.5588)
		(drill 0.3048)
		(layers "F.Cu" "B.Cu")
		(net "GND")
	)
	(via
		(at 96.287844 -333.554832)
		(size 0.5588)
		(drill 0.3048)
		(layers "F.Cu" "B.Cu")
		(net "GND")
	)
	(via
		(at 174.755048 -380.775972)
		(size 0.7112)
		(drill 0.4064)
		(layers "F.Cu" "B.Cu")
		(net "GND")
	)
	(via
		(at 19.694906 -380.775972)
		(size 0.7112)
		(drill 0.4064)
		(layers "F.Cu" "B.Cu")
		(net "GND")
	)
	(via
		(at 483.404926 -243.035074)
		(size 0.5588)
		(drill 0.3048)
		(layers "F.Cu" "B.Cu")
		(net "GND")
	)
	(via
		(at 340.868 -247.904)
		(size 0.5588)
		(drill 0.3048)
		(layers "F.Cu" "B.Cu")
		(net "GND")
	)
	(via
		(at 381 -342.9)
		(size 0.5588)
		(drill 0.3048)
		(layers "F.Cu" "B.Cu")
		(net "GND")
	)
	(via
		(at 460.847186 -120.194578)
		(size 0.5588)
		(drill 0.3048)
		(layers "F.Cu" "B.Cu")
		(net "GND")
	)
	(via
		(at 380.927864 -378.476002)
		(size 0.7112)
		(drill 0.4064)
		(layers "F.Cu" "B.Cu")
		(net "GND")
	)
	(via
		(at 10.480802 -225.30435)
		(size 0.5588)
		(drill 0.3048)
		(layers "F.Cu" "B.Cu")
		(net "GND")
	)
	(via
		(at 150.495 -277.241)
		(size 0.5588)
		(drill 0.3048)
		(layers "F.Cu" "B.Cu")
		(net "GND")
	)
	(via
		(at 489.926122 -251.20219)
		(size 0.7112)
		(drill 0.4064)
		(layers "F.Cu" "B.Cu")
		(net "GND")
	)
	(via
		(at 376.896376 -1.524)
		(size 0.7112)
		(drill 0.4064)
		(layers "F.Cu" "B.Cu")
		(net "GND")
	)
	(via
		(at 233.2736 -193.2305)
		(size 0.508)
		(drill 0.254)
		(layers "F.Cu" "B.Cu")
		(net "GND")
	)
	(via
		(at 91.404948 -148.35505)
		(size 0.5588)
		(drill 0.3048)
		(layers "F.Cu" "B.Cu")
		(net "GND")
	)
	(via
		(at 152.383998 -384.47599)
		(size 0.7112)
		(drill 0.4064)
		(layers "F.Cu" "B.Cu")
		(net "GND")
	)
	(via
		(at 328.262996 -368.935)
		(size 0.5588)
		(drill 0.3048)
		(layers "F.Cu" "B.Cu")
		(net "GND")
	)
	(via
		(at 160.401 -282.575)
		(size 0.5588)
		(drill 0.3048)
		(layers "F.Cu" "B.Cu")
		(net "GND")
	)
	(via
		(at 476.13316 -215.219788)
		(size 0.5588)
		(drill 0.3048)
		(layers "F.Cu" "B.Cu")
		(net "GND")
	)
	(via
		(at 483.404926 -260.815074)
		(size 0.5588)
		(drill 0.3048)
		(layers "F.Cu" "B.Cu")
		(net "GND")
	)
	(via
		(at 424.434 -277.114)
		(size 0.5588)
		(drill 0.3048)
		(layers "F.Cu" "B.Cu")
		(net "GND")
	)
	(via
		(at 304.8 -279.4)
		(size 0.5588)
		(drill 0.3048)
		(layers "F.Cu" "B.Cu")
		(net "GND")
	)
	(via
		(at 253.238 -379.984)
		(size 0.7112)
		(drill 0.4064)
		(layers "F.Cu" "B.Cu")
		(net "GND")
	)
	(via
		(at 487.386376 -1.524)
		(size 0.7112)
		(drill 0.4064)
		(layers "F.Cu" "B.Cu")
		(net "GND")
	)
	(via
		(at 77.66685 -216.308686)
		(size 0.5588)
		(drill 0.3048)
		(layers "F.Cu" "B.Cu")
		(net "GND")
	)
	(via
		(at 171.958 -261.239)
		(size 0.5588)
		(drill 0.3048)
		(layers "F.Cu" "B.Cu")
		(net "GND")
	)
	(via
		(at 350.129856 -384.47599)
		(size 0.7112)
		(drill 0.4064)
		(layers "F.Cu" "B.Cu")
		(net "GND")
	)
	(via
		(at 489.926122 -295.65219)
		(size 0.7112)
		(drill 0.4064)
		(layers "F.Cu" "B.Cu")
		(net "GND")
	)
	(via
		(at 186.055 -145.81505)
		(size 0.5588)
		(drill 0.3048)
		(layers "F.Cu" "B.Cu")
		(net "GND")
	)
	(via
		(at 489.926122 -265.17219)
		(size 0.7112)
		(drill 0.4064)
		(layers "F.Cu" "B.Cu")
		(net "GND")
	)
	(via
		(at 1.524 -93.113352)
		(size 0.7112)
		(drill 0.4064)
		(layers "F.Cu" "B.Cu")
		(net "GND")
	)
	(via
		(at 197.47611 -25.132538)
		(size 0.7112)
		(drill 0.4064)
		(layers "F.Cu" "B.Cu")
		(net "GND")
	)
	(via
		(at 98.552 -49.784)
		(size 0.5588)
		(drill 0.3048)
		(layers "F.Cu" "B.Cu")
		(net "GND")
	)
	(via
		(at 331.079856 -384.47599)
		(size 0.7112)
		(drill 0.4064)
		(layers "F.Cu" "B.Cu")
		(net "GND")
	)
	(via
		(at 59.037982 -384.47599)
		(size 0.7112)
		(drill 0.4064)
		(layers "F.Cu" "B.Cu")
		(net "GND")
	)
	(via
		(at 472.2622 -133.223)
		(size 0.5588)
		(drill 0.3048)
		(layers "F.Cu" "B.Cu")
		(net "GND")
	)
	(via
		(at 489.926122 -59.43219)
		(size 0.7112)
		(drill 0.4064)
		(layers "F.Cu" "B.Cu")
		(net "GND")
	)
	(via
		(at 128.8415 -375.412)
		(size 0.5588)
		(drill 0.3048)
		(layers "F.Cu" "B.Cu")
		(net "GND")
	)
	(via
		(at 145.288 -248.6152)
		(size 0.5588)
		(drill 0.3048)
		(layers "F.Cu" "B.Cu")
		(net "GND")
	)
	(via
		(at 180.4162 -271.3228)
		(size 0.5588)
		(drill 0.3048)
		(layers "F.Cu" "B.Cu")
		(net "GND")
	)
	(via
		(at 423.672 -255.016)
		(size 0.5588)
		(drill 0.3048)
		(layers "F.Cu" "B.Cu")
		(net "GND")
	)
	(via
		(at 270.926052 -372.721632)
		(size 0.7112)
		(drill 0.4064)
		(layers "F.Cu" "B.Cu")
		(net "GND")
	)
	(via
		(at 288.911284 -181.094634)
		(size 0.6604)
		(drill 0.3556)
		(layers "F.Cu" "B.Cu")
		(net "GND")
	)
	(via
		(at 278.393906 -382.488694)
		(size 0.7112)
		(drill 0.4064)
		(layers "F.Cu" "B.Cu")
		(net "GND")
	)
	(via
		(at 1.524 -164.233352)
		(size 0.7112)
		(drill 0.4064)
		(layers "F.Cu" "B.Cu")
		(net "GND")
	)
	(via
		(at 378.387864 -378.476002)
		(size 0.7112)
		(drill 0.4064)
		(layers "F.Cu" "B.Cu")
		(net "GND")
	)
	(via
		(at 448.016376 -1.524)
		(size 0.7112)
		(drill 0.4064)
		(layers "F.Cu" "B.Cu")
		(net "GND")
	)
	(via
		(at 419.345872 -384.47599)
		(size 0.7112)
		(drill 0.4064)
		(layers "F.Cu" "B.Cu")
		(net "GND")
	)
	(via
		(at 84.857844 -333.554832)
		(size 0.5588)
		(drill 0.3048)
		(layers "F.Cu" "B.Cu")
		(net "GND")
	)
	(via
		(at 266.224004 -384.457956)
		(size 0.7112)
		(drill 0.4064)
		(layers "F.Cu" "B.Cu")
		(net "GND")
	)
	(via
		(at 398.272 -51.816)
		(size 0.5588)
		(drill 0.3048)
		(layers "F.Cu" "B.Cu")
		(net "GND")
	)
	(via
		(at 50.8 -304.8)
		(size 0.5588)
		(drill 0.3048)
		(layers "F.Cu" "B.Cu")
		(net "GND")
	)
	(via
		(at 489.926122 -227.07219)
		(size 0.7112)
		(drill 0.4064)
		(layers "F.Cu" "B.Cu")
		(net "GND")
	)
	(via
		(at 362.331 -268.605)
		(size 0.5588)
		(drill 0.3048)
		(layers "F.Cu" "B.Cu")
		(net "GND")
	)
	(via
		(at 321.056 -274.828)
		(size 0.5588)
		(drill 0.3048)
		(layers "F.Cu" "B.Cu")
		(net "GND")
	)
	(via
		(at 46.438058 -115.764056)
		(size 0.5588)
		(drill 0.3048)
		(layers "F.Cu" "B.Cu")
		(net "GND")
	)
	(via
		(at 438.301384 -116.632228)
		(size 0.5588)
		(drill 0.3048)
		(layers "F.Cu" "B.Cu")
		(net "GND")
	)
	(via
		(at 270.926052 -368.911632)
		(size 0.7112)
		(drill 0.4064)
		(layers "F.Cu" "B.Cu")
		(net "GND")
	)
	(via
		(at 458.089 -20.8788)
		(size 0.5588)
		(drill 0.3048)
		(layers "F.Cu" "B.Cu")
		(net "GND")
	)
	(via
		(at 296.926 -129.921)
		(size 0.5588)
		(drill 0.3048)
		(layers "F.Cu" "B.Cu")
		(net "GND")
	)
	(via
		(at 259.383276 -196.007482)
		(size 0.7112)
		(drill 0.4064)
		(layers "F.Cu" "B.Cu")
		(net "GND")
	)
	(via
		(at 347.686376 -1.524)
		(size 0.7112)
		(drill 0.4064)
		(layers "F.Cu" "B.Cu")
		(net "GND")
	)
	(via
		(at 477.012 -376.936)
		(size 0.5588)
		(drill 0.3048)
		(layers "F.Cu" "B.Cu")
		(net "GND")
	)
	(via
		(at 324.511924 -253.830074)
		(size 0.5588)
		(drill 0.3048)
		(layers "F.Cu" "B.Cu")
		(net "GND")
	)
	(via
		(at 457.455016 -384.429)
		(size 0.7112)
		(drill 0.4064)
		(layers "F.Cu" "B.Cu")
		(net "GND")
	)
	(via
		(at 1.524 -133.753352)
		(size 0.7112)
		(drill 0.4064)
		(layers "F.Cu" "B.Cu")
		(net "GND")
	)
	(via
		(at 64.151256 -106.047286)
		(size 0.5588)
		(drill 0.3048)
		(layers "F.Cu" "B.Cu")
		(net "GND")
	)
	(via
		(at 283.920692 -384.47599)
		(size 0.7112)
		(drill 0.4064)
		(layers "F.Cu" "B.Cu")
		(net "GND")
	)
	(via
		(at 1.524 -148.993352)
		(size 0.7112)
		(drill 0.4064)
		(layers "F.Cu" "B.Cu")
		(net "GND")
	)
	(via
		(at 1.524 -150.263352)
		(size 0.7112)
		(drill 0.4064)
		(layers "F.Cu" "B.Cu")
		(net "GND")
	)
	(via
		(at 54.6354 -15.98676)
		(size 0.5588)
		(drill 0.3048)
		(layers "F.Cu" "B.Cu")
		(net "GND")
	)
	(via
		(at 1.524 -47.393352)
		(size 0.7112)
		(drill 0.4064)
		(layers "F.Cu" "B.Cu")
		(net "GND")
	)
	(via
		(at 36.924996 -368.935)
		(size 0.5588)
		(drill 0.3048)
		(layers "F.Cu" "B.Cu")
		(net "GND")
	)
	(via
		(at 180.4162 -156.2608)
		(size 0.5588)
		(drill 0.3048)
		(layers "F.Cu" "B.Cu")
		(net "GND")
	)
	(via
		(at 312.523886 -37.48151)
		(size 0.7112)
		(drill 0.4064)
		(layers "F.Cu" "B.Cu")
		(net "GND")
	)
	(via
		(at 161.9885 -146.177)
		(size 0.5588)
		(drill 0.3048)
		(layers "F.Cu" "B.Cu")
		(net "GND")
	)
	(via
		(at 279.174448 -352.367342)
		(size 0.5588)
		(drill 0.3048)
		(layers "F.Cu" "B.Cu")
		(net "GND")
	)
	(via
		(at 392.176 -255.143)
		(size 0.5588)
		(drill 0.3048)
		(layers "F.Cu" "B.Cu")
		(net "GND")
	)
	(via
		(at 1.524 -338.223352)
		(size 0.7112)
		(drill 0.4064)
		(layers "F.Cu" "B.Cu")
		(net "GND")
	)
	(via
		(at 224.550224 -326.131174)
		(size 0.5588)
		(drill 0.3048)
		(layers "F.Cu" "B.Cu")
		(net "GND")
	)
	(via
		(at 162.306 -90.043)
		(size 0.5588)
		(drill 0.3048)
		(layers "F.Cu" "B.Cu")
		(net "GND")
	)
	(via
		(at 22.606 -224.917)
		(size 0.5588)
		(drill 0.3048)
		(layers "F.Cu" "B.Cu")
		(net "GND")
	)
	(via
		(at 482.6 -190.5)
		(size 0.5588)
		(drill 0.3048)
		(layers "F.Cu" "B.Cu")
		(net "GND")
	)
	(via
		(at 324.729856 -384.47599)
		(size 0.7112)
		(drill 0.4064)
		(layers "F.Cu" "B.Cu")
		(net "GND")
	)
	(via
		(at 489.926122 -86.10219)
		(size 0.7112)
		(drill 0.4064)
		(layers "F.Cu" "B.Cu")
		(net "GND")
	)
	(via
		(at 307.294026 -360.013758)
		(size 0.5588)
		(drill 0.3048)
		(layers "F.Cu" "B.Cu")
		(net "GND")
	)
	(via
		(at 325.654924 -153.43505)
		(size 0.5588)
		(drill 0.3048)
		(layers "F.Cu" "B.Cu")
		(net "GND")
	)
	(via
		(at 270.52397 -56.36133)
		(size 0.7112)
		(drill 0.4064)
		(layers "F.Cu" "B.Cu")
		(net "GND")
	)
	(via
		(at 327.432924 -7.035038)
		(size 0.5588)
		(drill 0.3048)
		(layers "F.Cu" "B.Cu")
		(net "GND")
	)
	(via
		(at 287.02 -252.476)
		(size 0.5588)
		(drill 0.3048)
		(layers "F.Cu" "B.Cu")
		(net "GND")
	)
	(via
		(at 387.813042 -40.972232)
		(size 0.5588)
		(drill 0.3048)
		(layers "F.Cu" "B.Cu")
		(net "GND")
	)
	(via
		(at 21.59 -223.901)
		(size 0.5588)
		(drill 0.3048)
		(layers "F.Cu" "B.Cu")
		(net "GND")
	)
	(via
		(at 101.6 -203.2)
		(size 0.5588)
		(drill 0.3048)
		(layers "F.Cu" "B.Cu")
		(net "GND")
	)
	(via
		(at 100.097844 -333.554832)
		(size 0.5588)
		(drill 0.3048)
		(layers "F.Cu" "B.Cu")
		(net "GND")
	)
	(via
		(at 380.492 -148.844)
		(size 0.5588)
		(drill 0.3048)
		(layers "F.Cu" "B.Cu")
		(net "GND")
	)
	(via
		(at 103.378 -249.936)
		(size 0.5588)
		(drill 0.3048)
		(layers "F.Cu" "B.Cu")
		(net "GND")
	)
	(via
		(at 190.720218 -365.252254)
		(size 0.5588)
		(drill 0.3048)
		(layers "F.Cu" "B.Cu")
		(net "GND")
	)
	(via
		(at 1.524 -79.143352)
		(size 0.7112)
		(drill 0.4064)
		(layers "F.Cu" "B.Cu")
		(net "GND")
	)
	(via
		(at 263.040876 -197.252082)
		(size 0.7112)
		(drill 0.4064)
		(layers "F.Cu" "B.Cu")
		(net "GND")
	)
	(via
		(at 113.284 -260.604)
		(size 0.5588)
		(drill 0.3048)
		(layers "F.Cu" "B.Cu")
		(net "GND")
	)
	(via
		(at 1.524 -339.493352)
		(size 0.7112)
		(drill 0.4064)
		(layers "F.Cu" "B.Cu")
		(net "GND")
	)
	(via
		(at 1.524 -272.183352)
		(size 0.7112)
		(drill 0.4064)
		(layers "F.Cu" "B.Cu")
		(net "GND")
	)
	(via
		(at 365.633 -20.574)
		(size 0.5588)
		(drill 0.3048)
		(layers "F.Cu" "B.Cu")
		(net "GND")
	)
	(via
		(at 170.284648 -1.524)
		(size 0.7112)
		(drill 0.4064)
		(layers "F.Cu" "B.Cu")
		(net "GND")
	)
	(via
		(at 489.926122 -235.96219)
		(size 0.7112)
		(drill 0.4064)
		(layers "F.Cu" "B.Cu")
		(net "GND")
	)
	(via
		(at 419.223952 -382.05791)
		(size 0.7112)
		(drill 0.4064)
		(layers "F.Cu" "B.Cu")
		(net "GND")
	)
	(via
		(at 50.904648 -1.524)
		(size 0.7112)
		(drill 0.4064)
		(layers "F.Cu" "B.Cu")
		(net "GND")
	)
	(via
		(at 434.046376 -1.524)
		(size 0.7112)
		(drill 0.4064)
		(layers "F.Cu" "B.Cu")
		(net "GND")
	)
	(via
		(at 179.174648 -1.524)
		(size 0.7112)
		(drill 0.4064)
		(layers "F.Cu" "B.Cu")
		(net "GND")
	)
	(via
		(at 31.097982 -384.47599)
		(size 0.7112)
		(drill 0.4064)
		(layers "F.Cu" "B.Cu")
		(net "GND")
	)
	(via
		(at 1.524 -62.633352)
		(size 0.7112)
		(drill 0.4064)
		(layers "F.Cu" "B.Cu")
		(net "GND")
	)
	(via
		(at 94.866968 -340.980014)
		(size 0.5588)
		(drill 0.3048)
		(layers "F.Cu" "B.Cu")
		(net "GND")
	)
	(via
		(at 489.926122 -27.68219)
		(size 0.7112)
		(drill 0.4064)
		(layers "F.Cu" "B.Cu")
		(net "GND")
	)
	(via
		(at 375.92 -138.684)
		(size 0.5588)
		(drill 0.3048)
		(layers "F.Cu" "B.Cu")
		(net "GND")
	)
	(via
		(at 38.717982 -384.47599)
		(size 0.7112)
		(drill 0.4064)
		(layers "F.Cu" "B.Cu")
		(net "GND")
	)
	(via
		(at 44.196 -59.944)
		(size 0.5588)
		(drill 0.3048)
		(layers "F.Cu" "B.Cu")
		(net "GND")
	)
	(via
		(at 450.711824 -26.230072)
		(size 0.5588)
		(drill 0.3048)
		(layers "F.Cu" "B.Cu")
		(net "GND")
	)
	(via
		(at 146.812 -256.667)
		(size 0.5588)
		(drill 0.3048)
		(layers "F.Cu" "B.Cu")
		(net "GND")
	)
	(via
		(at 28.304998 -246.845074)
		(size 0.5588)
		(drill 0.3048)
		(layers "F.Cu" "B.Cu")
		(net "GND")
	)
	(via
		(at 1.524 -65.173352)
		(size 0.7112)
		(drill 0.4064)
		(layers "F.Cu" "B.Cu")
		(net "GND")
	)
	(via
		(at 1.524 -94.383352)
		(size 0.7112)
		(drill 0.4064)
		(layers "F.Cu" "B.Cu")
		(net "GND")
	)
	(via
		(at 76.304648 -1.524)
		(size 0.7112)
		(drill 0.4064)
		(layers "F.Cu" "B.Cu")
		(net "GND")
	)
	(via
		(at 286.6898 -306.451)
		(size 0.7112)
		(drill 0.4064)
		(layers "F.Cu" "B.Cu")
		(net "GND")
	)
	(via
		(at 16.614648 -1.524)
		(size 0.7112)
		(drill 0.4064)
		(layers "F.Cu" "B.Cu")
		(net "GND")
	)
	(via
		(at 352.806 -37.719)
		(size 0.5588)
		(drill 0.3048)
		(layers "F.Cu" "B.Cu")
		(net "GND")
	)
	(via
		(at 489.926122 -211.83219)
		(size 0.7112)
		(drill 0.4064)
		(layers "F.Cu" "B.Cu")
		(net "GND")
	)
	(via
		(at 489.926122 -119.12219)
		(size 0.7112)
		(drill 0.4064)
		(layers "F.Cu" "B.Cu")
		(net "GND")
	)
	(via
		(at 407.416 -259.588)
		(size 0.5588)
		(drill 0.3048)
		(layers "F.Cu" "B.Cu")
		(net "GND")
	)
	(via
		(at 1.524 -165.503352)
		(size 0.7112)
		(drill 0.4064)
		(layers "F.Cu" "B.Cu")
		(net "GND")
	)
	(via
		(at 158.166562 -153.442162)
		(size 0.5588)
		(drill 0.3048)
		(layers "F.Cu" "B.Cu")
		(net "GND")
	)
	(via
		(at 317.5 -279.4)
		(size 0.5588)
		(drill 0.3048)
		(layers "F.Cu" "B.Cu")
		(net "GND")
	)
	(via
		(at 54.714648 -1.524)
		(size 0.7112)
		(drill 0.4064)
		(layers "F.Cu" "B.Cu")
		(net "GND")
	)
	(via
		(at 371.357144 -96.310704)
		(size 0.5588)
		(drill 0.3048)
		(layers "F.Cu" "B.Cu")
		(net "GND")
	)
	(via
		(at 489.926122 -243.58219)
		(size 0.7112)
		(drill 0.4064)
		(layers "F.Cu" "B.Cu")
		(net "GND")
	)
	(via
		(at 40.60444 -234.835192)
		(size 0.5588)
		(drill 0.3048)
		(layers "F.Cu" "B.Cu")
		(net "GND")
	)
	(via
		(at 455.803 -255.778)
		(size 0.5588)
		(drill 0.3048)
		(layers "F.Cu" "B.Cu")
		(net "GND")
	)
	(via
		(at 323.215 -54.102)
		(size 0.5588)
		(drill 0.3048)
		(layers "F.Cu" "B.Cu")
		(net "GND")
	)
	(via
		(at 80.946752 -344.864944)
		(size 0.5588)
		(drill 0.3048)
		(layers "F.Cu" "B.Cu")
		(net "GND")
	)
	(via
		(at 1.524 -119.783352)
		(size 0.7112)
		(drill 0.4064)
		(layers "F.Cu" "B.Cu")
		(net "GND")
	)
	(via
		(at 1.524 -236.623352)
		(size 0.7112)
		(drill 0.4064)
		(layers "F.Cu" "B.Cu")
		(net "GND")
	)
	(via
		(at 96.71812 -361.340146)
		(size 0.7112)
		(drill 0.4064)
		(layers "F.Cu" "B.Cu")
		(net "GND")
	)
	(via
		(at 482.6 -304.8)
		(size 0.5588)
		(drill 0.3048)
		(layers "F.Cu" "B.Cu")
		(net "GND")
	)
	(via
		(at 89.836752 -344.864944)
		(size 0.5588)
		(drill 0.3048)
		(layers "F.Cu" "B.Cu")
		(net "GND")
	)
	(via
		(at 154.504898 -40.975026)
		(size 0.5588)
		(drill 0.3048)
		(layers "F.Cu" "B.Cu")
		(net "GND")
	)
	(via
		(at 49.215802 -230.51135)
		(size 0.5588)
		(drill 0.3048)
		(layers "F.Cu" "B.Cu")
		(net "GND")
	)
	(via
		(at 489.926122 -204.21219)
		(size 0.7112)
		(drill 0.4064)
		(layers "F.Cu" "B.Cu")
		(net "GND")
	)
	(via
		(at 1.524 -56.283352)
		(size 0.7112)
		(drill 0.4064)
		(layers "F.Cu" "B.Cu")
		(net "GND")
	)
	(via
		(at 172.974 -43.561)
		(size 0.5588)
		(drill 0.3048)
		(layers "F.Cu" "B.Cu")
		(net "GND")
	)
	(via
		(at 325.654924 -20.655026)
		(size 0.5588)
		(drill 0.3048)
		(layers "F.Cu" "B.Cu")
		(net "GND")
	)
	(via
		(at 196.85 -379.857)
		(size 0.7112)
		(drill 0.4064)
		(layers "F.Cu" "B.Cu")
		(net "GND")
	)
	(via
		(at 451.854824 -128.03505)
		(size 0.5588)
		(drill 0.3048)
		(layers "F.Cu" "B.Cu")
		(net "GND")
	)
	(via
		(at 1.524 -226.463352)
		(size 0.7112)
		(drill 0.4064)
		(layers "F.Cu" "B.Cu")
		(net "GND")
	)
	(via
		(at 77.136752 -344.864944)
		(size 0.5588)
		(drill 0.3048)
		(layers "F.Cu" "B.Cu")
		(net "GND")
	)
	(via
		(at 259.874004 -384.457956)
		(size 0.7112)
		(drill 0.4064)
		(layers "F.Cu" "B.Cu")
		(net "GND")
	)
	(via
		(at 296.620692 -384.47599)
		(size 0.7112)
		(drill 0.4064)
		(layers "F.Cu" "B.Cu")
		(net "GND")
	)
	(via
		(at 19.154648 -1.524)
		(size 0.7112)
		(drill 0.4064)
		(layers "F.Cu" "B.Cu")
		(net "GND")
	)
	(via
		(at 33.310322 -362.625894)
		(size 0.5588)
		(drill 0.3048)
		(layers "F.Cu" "B.Cu")
		(net "GND")
	)
	(via
		(at 489.926122 -63.24219)
		(size 0.7112)
		(drill 0.4064)
		(layers "F.Cu" "B.Cu")
		(net "GND")
	)
	(via
		(at 419.161976 -256.23012)
		(size 0.5588)
		(drill 0.3048)
		(layers "F.Cu" "B.Cu")
		(net "GND")
	)
	(via
		(at 70.776084 -382.117092)
		(size 0.7112)
		(drill 0.4064)
		(layers "F.Cu" "B.Cu")
		(net "GND")
	)
	(via
		(at 447.487802 -226.44735)
		(size 0.5588)
		(drill 0.3048)
		(layers "F.Cu" "B.Cu")
		(net "GND")
	)
	(via
		(at 353.939856 -384.47599)
		(size 0.7112)
		(drill 0.4064)
		(layers "F.Cu" "B.Cu")
		(net "GND")
	)
	(via
		(at 1.524 -100.733352)
		(size 0.7112)
		(drill 0.4064)
		(layers "F.Cu" "B.Cu")
		(net "GND")
	)
	(via
		(at 451.854824 -260.815074)
		(size 0.5588)
		(drill 0.3048)
		(layers "F.Cu" "B.Cu")
		(net "GND")
	)
	(via
		(at 312.523886 -28.59151)
		(size 0.7112)
		(drill 0.4064)
		(layers "F.Cu" "B.Cu")
		(net "GND")
	)
	(via
		(at 154.504898 -145.81505)
		(size 0.5588)
		(drill 0.3048)
		(layers "F.Cu" "B.Cu")
		(net "GND")
	)
	(via
		(at 61.632846 -165.785038)
		(size 0.5588)
		(drill 0.3048)
		(layers "F.Cu" "B.Cu")
		(net "GND")
	)
	(via
		(at 98.552 -139.192)
		(size 0.5588)
		(drill 0.3048)
		(layers "F.Cu" "B.Cu")
		(net "GND")
	)
	(via
		(at 236.978444 -191.181228)
		(size 0.5588)
		(drill 0.3048)
		(layers "F.Cu" "B.Cu")
		(net "GND")
	)
	(via
		(at 346.964 -352.552)
		(size 0.5588)
		(drill 0.3048)
		(layers "F.Cu" "B.Cu")
		(net "GND")
	)
	(via
		(at 1.524 -240.433352)
		(size 0.7112)
		(drill 0.4064)
		(layers "F.Cu" "B.Cu")
		(net "GND")
	)
	(via
		(at 311.15 -49.276)
		(size 0.7112)
		(drill 0.4064)
		(layers "F.Cu" "B.Cu")
		(net "GND")
	)
	(via
		(at 393.3444 -135.8646)
		(size 0.5588)
		(drill 0.3048)
		(layers "F.Cu" "B.Cu")
		(net "GND")
	)
	(via
		(at 253.259082 -227.56749)
		(size 0.5588)
		(drill 0.3048)
		(layers "F.Cu" "B.Cu")
		(net "GND")
	)
	(via
		(at 312.523886 -38.75151)
		(size 0.7112)
		(drill 0.4064)
		(layers "F.Cu" "B.Cu")
		(net "GND")
	)
	(via
		(at 1.524 -254.403352)
		(size 0.7112)
		(drill 0.4064)
		(layers "F.Cu" "B.Cu")
		(net "GND")
	)
	(via
		(at 416.266376 -1.524)
		(size 0.7112)
		(drill 0.4064)
		(layers "F.Cu" "B.Cu")
		(net "GND")
	)
	(via
		(at 229.057962 -378.476002)
		(size 0.7112)
		(drill 0.4064)
		(layers "F.Cu" "B.Cu")
		(net "GND")
	)
	(via
		(at 393.5222 -14.224)
		(size 0.5588)
		(drill 0.3048)
		(layers "F.Cu" "B.Cu")
		(net "GND")
	)
	(via
		(at 489.926122 -225.80219)
		(size 0.7112)
		(drill 0.4064)
		(layers "F.Cu" "B.Cu")
		(net "GND")
	)
	(via
		(at 235.407962 -378.476002)
		(size 0.7112)
		(drill 0.4064)
		(layers "F.Cu" "B.Cu")
		(net "GND")
	)
	(via
		(at 90.261948 -136.430004)
		(size 0.5588)
		(drill 0.3048)
		(layers "F.Cu" "B.Cu")
		(net "GND")
	)
	(via
		(at 329.819 -277.114)
		(size 0.5588)
		(drill 0.3048)
		(layers "F.Cu" "B.Cu")
		(net "GND")
	)
	(via
		(at 396.875 -153.289)
		(size 0.5588)
		(drill 0.3048)
		(layers "F.Cu" "B.Cu")
		(net "GND")
	)
	(via
		(at 137.983468 -101.773228)
		(size 0.5588)
		(drill 0.3048)
		(layers "F.Cu" "B.Cu")
		(net "GND")
	)
	(via
		(at 1.524 -237.893352)
		(size 0.7112)
		(drill 0.4064)
		(layers "F.Cu" "B.Cu")
		(net "GND")
	)
	(via
		(at 35.741864 -115.087654)
		(size 0.6096)
		(drill 0.3048)
		(layers "F.Cu" "B.Cu")
		(net "GND")
	)
	(via
		(at 428.806864 -117.215412)
		(size 0.6096)
		(drill 0.3048)
		(layers "F.Cu" "B.Cu")
		(net "GND")
	)
	(via
		(at 225.330258 -64.523874)
		(size 0.7112)
		(drill 0.4064)
		(layers "F.Cu" "B.Cu")
		(net "GND")
	)
	(via
		(at 1.524 -33.423352)
		(size 0.7112)
		(drill 0.4064)
		(layers "F.Cu" "B.Cu")
		(net "GND")
	)
	(via
		(at 418.806376 -1.524)
		(size 0.7112)
		(drill 0.4064)
		(layers "F.Cu" "B.Cu")
		(net "GND")
	)
	(via
		(at 361.315 -162.179)
		(size 0.5588)
		(drill 0.3048)
		(layers "F.Cu" "B.Cu")
		(net "GND")
	)
	(via
		(at 459.613 -277.114)
		(size 0.5588)
		(drill 0.3048)
		(layers "F.Cu" "B.Cu")
		(net "GND")
	)
	(via
		(at 251.038614 -143.207994)
		(size 0.5588)
		(drill 0.3048)
		(layers "F.Cu" "B.Cu")
		(net "GND")
	)
	(via
		(at 259.08 -312.42)
		(size 0.5588)
		(drill 0.3048)
		(layers "F.Cu" "B.Cu")
		(net "GND")
	)
	(via
		(at 419.161976 -141.230096)
		(size 0.5588)
		(drill 0.3048)
		(layers "F.Cu" "B.Cu")
		(net "GND")
	)
	(via
		(at 281.8384 -304.0634)
		(size 0.7112)
		(drill 0.4064)
		(layers "F.Cu" "B.Cu")
		(net "GND")
	)
	(via
		(at 355.6 -292.1)
		(size 0.5588)
		(drill 0.3048)
		(layers "F.Cu" "B.Cu")
		(net "GND")
	)
	(via
		(at 106.784648 -1.524)
		(size 0.7112)
		(drill 0.4064)
		(layers "F.Cu" "B.Cu")
		(net "GND")
	)
	(via
		(at 259.795772 -353.946206)
		(size 0.5588)
		(drill 0.3048)
		(layers "F.Cu" "B.Cu")
		(net "GND")
	)
	(via
		(at 489.926122 -7.36219)
		(size 0.7112)
		(drill 0.4064)
		(layers "F.Cu" "B.Cu")
		(net "GND")
	)
	(via
		(at 205.476094 -51.226212)
		(size 0.7112)
		(drill 0.4064)
		(layers "F.Cu" "B.Cu")
		(net "GND")
	)
	(via
		(at 244.0686 -307.6956)
		(size 0.5588)
		(drill 0.3048)
		(layers "F.Cu" "B.Cu")
		(net "GND")
	)
	(via
		(at 282.070048 -356.431342)
		(size 0.5588)
		(drill 0.3048)
		(layers "F.Cu" "B.Cu")
		(net "GND")
	)
	(via
		(at 313.563 -1.524)
		(size 0.7112)
		(drill 0.4064)
		(layers "F.Cu" "B.Cu")
		(net "GND")
	)
	(via
		(at 489.926122 -81.02219)
		(size 0.7112)
		(drill 0.4064)
		(layers "F.Cu" "B.Cu")
		(net "GND")
	)
	(via
		(at 330.3524 -250.6472)
		(size 0.5588)
		(drill 0.3048)
		(layers "F.Cu" "B.Cu")
		(net "GND")
	)
	(via
		(at 439.42 -34.544)
		(size 0.5588)
		(drill 0.3048)
		(layers "F.Cu" "B.Cu")
		(net "GND")
	)
	(via
		(at 223.977962 -378.476002)
		(size 0.7112)
		(drill 0.4064)
		(layers "F.Cu" "B.Cu")
		(net "GND")
	)
	(via
		(at 489.926122 -136.90219)
		(size 0.7112)
		(drill 0.4064)
		(layers "F.Cu" "B.Cu")
		(net "GND")
	)
	(via
		(at 1.524 -329.333352)
		(size 0.7112)
		(drill 0.4064)
		(layers "F.Cu" "B.Cu")
		(net "GND")
	)
	(via
		(at 283.0576 -305.2826)
		(size 0.7112)
		(drill 0.4064)
		(layers "F.Cu" "B.Cu")
		(net "GND")
	)
	(via
		(at 72.494648 -1.524)
		(size 0.7112)
		(drill 0.4064)
		(layers "F.Cu" "B.Cu")
		(net "GND")
	)
	(via
		(at 321.564 -286.512)
		(size 0.5588)
		(drill 0.3048)
		(layers "F.Cu" "B.Cu")
		(net "GND")
	)
	(via
		(at 269.66545 -383.629408)
		(size 0.7112)
		(drill 0.4064)
		(layers "F.Cu" "B.Cu")
		(net "GND")
	)
	(via
		(at 356.062026 -256.23012)
		(size 0.5588)
		(drill 0.3048)
		(layers "F.Cu" "B.Cu")
		(net "GND")
	)
	(via
		(at 1.524 -63.903352)
		(size 0.7112)
		(drill 0.4064)
		(layers "F.Cu" "B.Cu")
		(net "GND")
	)
	(via
		(at 121.811796 -253.830074)
		(size 0.5588)
		(drill 0.3048)
		(layers "F.Cu" "B.Cu")
		(net "GND")
	)
	(via
		(at 87.734648 -1.524)
		(size 0.7112)
		(drill 0.4064)
		(layers "F.Cu" "B.Cu")
		(net "GND")
	)
	(via
		(at 374.019318 -216.8144)
		(size 0.5588)
		(drill 0.3048)
		(layers "F.Cu" "B.Cu")
		(net "GND")
	)
	(via
		(at 47.454058 -115.764056)
		(size 0.5588)
		(drill 0.3048)
		(layers "F.Cu" "B.Cu")
		(net "GND")
	)
	(via
		(at 467.614 -35.56)
		(size 0.5588)
		(drill 0.3048)
		(layers "F.Cu" "B.Cu")
		(net "GND")
	)
	(via
		(at 476.25 -141.732)
		(size 0.5588)
		(drill 0.3048)
		(layers "F.Cu" "B.Cu")
		(net "GND")
	)
	(via
		(at 450.711824 -21.42998)
		(size 0.5588)
		(drill 0.3048)
		(layers "F.Cu" "B.Cu")
		(net "GND")
	)
	(via
		(at 323.596 -348.996)
		(size 0.5588)
		(drill 0.3048)
		(layers "F.Cu" "B.Cu")
		(net "GND")
	)
	(via
		(at 116.944648 -1.524)
		(size 0.7112)
		(drill 0.4064)
		(layers "F.Cu" "B.Cu")
		(net "GND")
	)
	(via
		(at 262.362696 -95.246952)
		(size 0.5588)
		(drill 0.3048)
		(layers "F.Cu" "B.Cu")
		(net "GND")
	)
	(via
		(at 259.58038 -278.5999)
		(size 0.5588)
		(drill 0.3048)
		(layers "F.Cu" "B.Cu")
		(net "GND")
	)
	(via
		(at 278.892 -96.012)
		(size 0.5588)
		(drill 0.3048)
		(layers "F.Cu" "B.Cu")
		(net "GND")
	)
	(via
		(at 444.5 -50.8)
		(size 0.5588)
		(drill 0.3048)
		(layers "F.Cu" "B.Cu")
		(net "GND")
	)
	(via
		(at 388.754874 -268.435074)
		(size 0.5588)
		(drill 0.3048)
		(layers "F.Cu" "B.Cu")
		(net "GND")
	)
	(via
		(at 209.001614 -168.209468)
		(size 0.5588)
		(drill 0.3048)
		(layers "F.Cu" "B.Cu")
		(net "GND")
	)
	(via
		(at 197.47611 -42.912538)
		(size 0.7112)
		(drill 0.4064)
		(layers "F.Cu" "B.Cu")
		(net "GND")
	)
	(via
		(at 59.854846 -20.655026)
		(size 0.5588)
		(drill 0.3048)
		(layers "F.Cu" "B.Cu")
		(net "GND")
	)
	(via
		(at 483.404926 -131.84505)
		(size 0.5588)
		(drill 0.3048)
		(layers "F.Cu" "B.Cu")
		(net "GND")
	)
	(via
		(at 489.926122 -107.69219)
		(size 0.7112)
		(drill 0.4064)
		(layers "F.Cu" "B.Cu")
		(net "GND")
	)
	(via
		(at 76.2 -292.1)
		(size 0.5588)
		(drill 0.3048)
		(layers "F.Cu" "B.Cu")
		(net "GND")
	)
	(via
		(at 289.080448 -346.271342)
		(size 0.5588)
		(drill 0.3048)
		(layers "F.Cu" "B.Cu")
		(net "GND")
	)
	(via
		(at 38.1 -203.2)
		(size 0.5588)
		(drill 0.3048)
		(layers "F.Cu" "B.Cu")
		(net "GND")
	)
	(via
		(at 1.524 -66.443352)
		(size 0.7112)
		(drill 0.4064)
		(layers "F.Cu" "B.Cu")
		(net "GND")
	)
	(via
		(at 54.229 -271.3228)
		(size 0.5588)
		(drill 0.3048)
		(layers "F.Cu" "B.Cu")
		(net "GND")
	)
	(via
		(at 384.516376 -1.524)
		(size 0.7112)
		(drill 0.4064)
		(layers "F.Cu" "B.Cu")
		(net "GND")
	)
	(via
		(at 1.524 -197.253352)
		(size 0.7112)
		(drill 0.4064)
		(layers "F.Cu" "B.Cu")
		(net "GND")
	)
	(via
		(at 478.282 -46.101)
		(size 0.5588)
		(drill 0.3048)
		(layers "F.Cu" "B.Cu")
		(net "GND")
	)
	(via
		(at 106.441494 -101.697028)
		(size 0.5588)
		(drill 0.3048)
		(layers "F.Cu" "B.Cu")
		(net "GND")
	)
	(via
		(at 394.897864 -378.476002)
		(size 0.7112)
		(drill 0.4064)
		(layers "F.Cu" "B.Cu")
		(net "GND")
	)
	(via
		(at 79.676752 -338.514944)
		(size 0.5588)
		(drill 0.3048)
		(layers "F.Cu" "B.Cu")
		(net "GND")
	)
	(via
		(at 357.205026 -268.435074)
		(size 0.5588)
		(drill 0.3048)
		(layers "F.Cu" "B.Cu")
		(net "GND")
	)
	(via
		(at 104.244648 -1.524)
		(size 0.7112)
		(drill 0.4064)
		(layers "F.Cu" "B.Cu")
		(net "GND")
	)
	(via
		(at 237.881922 -193.679572)
		(size 0.5588)
		(drill 0.3048)
		(layers "F.Cu" "B.Cu")
		(net "GND")
	)
	(via
		(at 489.926122 -233.42219)
		(size 0.7112)
		(drill 0.4064)
		(layers "F.Cu" "B.Cu")
		(net "GND")
	)
	(via
		(at 121.811796 -26.230072)
		(size 0.5588)
		(drill 0.3048)
		(layers "F.Cu" "B.Cu")
		(net "GND")
	)
	(via
		(at 79.676752 -334.704944)
		(size 0.5588)
		(drill 0.3048)
		(layers "F.Cu" "B.Cu")
		(net "GND")
	)
	(via
		(at 414.996376 -1.524)
		(size 0.7112)
		(drill 0.4064)
		(layers "F.Cu" "B.Cu")
		(net "GND")
	)
	(via
		(at 489.926122 -8.63219)
		(size 0.7112)
		(drill 0.4064)
		(layers "F.Cu" "B.Cu")
		(net "GND")
	)
	(via
		(at 118.872 -162.179)
		(size 0.5588)
		(drill 0.3048)
		(layers "F.Cu" "B.Cu")
		(net "GND")
	)
	(via
		(at 1.524 -302.663352)
		(size 0.7112)
		(drill 0.4064)
		(layers "F.Cu" "B.Cu")
		(net "GND")
	)
	(via
		(at 241.757962 -378.476002)
		(size 0.7112)
		(drill 0.4064)
		(layers "F.Cu" "B.Cu")
		(net "GND")
	)
	(via
		(at 132.588 -328.676)
		(size 0.5588)
		(drill 0.3048)
		(layers "F.Cu" "B.Cu")
		(net "GND")
	)
	(via
		(at 122.954796 -128.03505)
		(size 0.5588)
		(drill 0.3048)
		(layers "F.Cu" "B.Cu")
		(net "GND")
	)
	(via
		(at 30.117796 -372.3386)
		(size 0.5588)
		(drill 0.3048)
		(layers "F.Cu" "B.Cu")
		(net "GND")
	)
	(via
		(at 420.076376 -1.524)
		(size 0.7112)
		(drill 0.4064)
		(layers "F.Cu" "B.Cu")
		(net "GND")
	)
	(via
		(at 45.464222 -115.574572)
		(size 0.5588)
		(drill 0.3048)
		(layers "F.Cu" "B.Cu")
		(net "GND")
	)
	(via
		(at 411.186376 -1.524)
		(size 0.7112)
		(drill 0.4064)
		(layers "F.Cu" "B.Cu")
		(net "GND")
	)
	(via
		(at 229.8954 -197.358)
		(size 0.5588)
		(drill 0.3048)
		(layers "F.Cu" "B.Cu")
		(net "GND")
	)
	(via
		(at 346.456 -124.968)
		(size 0.5588)
		(drill 0.3048)
		(layers "F.Cu" "B.Cu")
		(net "GND")
	)
	(via
		(at 401.026376 -1.524)
		(size 0.7112)
		(drill 0.4064)
		(layers "F.Cu" "B.Cu")
		(net "GND")
	)
	(via
		(at 148.694648 -1.524)
		(size 0.7112)
		(drill 0.4064)
		(layers "F.Cu" "B.Cu")
		(net "GND")
	)
	(via
		(at 202.260454 -243.78793)
		(size 0.5588)
		(drill 0.3048)
		(layers "F.Cu" "B.Cu")
		(net "GND")
	)
	(via
		(at 185.547 -368.681)
		(size 0.5588)
		(drill 0.3048)
		(layers "F.Cu" "B.Cu")
		(net "GND")
	)
	(via
		(at 373.086376 -1.524)
		(size 0.7112)
		(drill 0.4064)
		(layers "F.Cu" "B.Cu")
		(net "GND")
	)
	(via
		(at 257.360674 -276.6822)
		(size 0.5588)
		(drill 0.3048)
		(layers "F.Cu" "B.Cu")
		(net "GND")
	)
	(via
		(at 437.327548 -115.426744)
		(size 0.5588)
		(drill 0.3048)
		(layers "F.Cu" "B.Cu")
		(net "GND")
	)
	(via
		(at 42.891202 -233.78795)
		(size 0.5588)
		(drill 0.3048)
		(layers "F.Cu" "B.Cu")
		(net "GND")
	)
	(via
		(at 12.573 -150.622)
		(size 0.5588)
		(drill 0.3048)
		(layers "F.Cu" "B.Cu")
		(net "GND")
	)
	(via
		(at 156.083 -80.899)
		(size 0.5588)
		(drill 0.3048)
		(layers "F.Cu" "B.Cu")
		(net "GND")
	)
	(via
		(at 426.72 -6.604)
		(size 0.5588)
		(drill 0.3048)
		(layers "F.Cu" "B.Cu")
		(net "GND")
	)
	(via
		(at 450.711824 -23.830026)
		(size 0.5588)
		(drill 0.3048)
		(layers "F.Cu" "B.Cu")
		(net "GND")
	)
	(via
		(at 302.26 -379.476)
		(size 0.5588)
		(drill 0.3048)
		(layers "F.Cu" "B.Cu")
		(net "GND")
	)
	(via
		(at 163.813998 -384.47599)
		(size 0.7112)
		(drill 0.4064)
		(layers "F.Cu" "B.Cu")
		(net "GND")
	)
	(via
		(at 208.8896 -142.8242)
		(size 0.7112)
		(drill 0.4064)
		(layers "F.Cu" "B.Cu")
		(net "GND")
	)
	(via
		(at 142.5575 -139.954)
		(size 0.5588)
		(drill 0.3048)
		(layers "F.Cu" "B.Cu")
		(net "GND")
	)
	(via
		(at 397.216376 -1.524)
		(size 0.7112)
		(drill 0.4064)
		(layers "F.Cu" "B.Cu")
		(net "GND")
	)
	(via
		(at 460.279242 -101.9048)
		(size 0.5588)
		(drill 0.3048)
		(layers "F.Cu" "B.Cu")
		(net "GND")
	)
	(via
		(at 321.7164 -30.353)
		(size 0.5588)
		(drill 0.3048)
		(layers "F.Cu" "B.Cu")
		(net "GND")
	)
	(via
		(at 93.182948 -7.035038)
		(size 0.5588)
		(drill 0.3048)
		(layers "F.Cu" "B.Cu")
		(net "GND")
	)
	(via
		(at 489.926122 -158.49219)
		(size 0.7112)
		(drill 0.4064)
		(layers "F.Cu" "B.Cu")
		(net "GND")
	)
	(via
		(at 98.044 -7.112)
		(size 0.5588)
		(drill 0.3048)
		(layers "F.Cu" "B.Cu")
		(net "GND")
	)
	(via
		(at 289.238436 -49.724056)
		(size 0.7112)
		(drill 0.4064)
		(layers "F.Cu" "B.Cu")
		(net "GND")
	)
	(via
		(at 277.622 -127.508)
		(size 0.5588)
		(drill 0.3048)
		(layers "F.Cu" "B.Cu")
		(net "GND")
	)
	(via
		(at 309.091076 -333.954882)
		(size 0.5588)
		(drill 0.3048)
		(layers "F.Cu" "B.Cu")
		(net "GND")
	)
	(via
		(at 244.9068 -217.3224)
		(size 0.5588)
		(drill 0.3048)
		(layers "F.Cu" "B.Cu")
		(net "GND")
	)
	(via
		(at 23.4315 -135.382)
		(size 0.5588)
		(drill 0.3048)
		(layers "F.Cu" "B.Cu")
		(net "GND")
	)
	(via
		(at 86.5505 -135.382)
		(size 0.5588)
		(drill 0.3048)
		(layers "F.Cu" "B.Cu")
		(net "GND")
	)
	(via
		(at 473.71 -260.604)
		(size 0.5588)
		(drill 0.3048)
		(layers "F.Cu" "B.Cu")
		(net "GND")
	)
	(via
		(at 122.954796 -20.655026)
		(size 0.5588)
		(drill 0.3048)
		(layers "F.Cu" "B.Cu")
		(net "GND")
	)
	(via
		(at 454.717404 -370.4844)
		(size 0.5588)
		(drill 0.3048)
		(layers "F.Cu" "B.Cu")
		(net "GND")
	)
	(via
		(at 42.891202 -232.77195)
		(size 0.5588)
		(drill 0.3048)
		(layers "F.Cu" "B.Cu")
		(net "GND")
	)
	(via
		(at 295.350692 -384.47599)
		(size 0.7112)
		(drill 0.4064)
		(layers "F.Cu" "B.Cu")
		(net "GND")
	)
	(via
		(at 451.854824 -148.35505)
		(size 0.5588)
		(drill 0.3048)
		(layers "F.Cu" "B.Cu")
		(net "GND")
	)
	(via
		(at 211.836 -126.746)
		(size 0.5588)
		(drill 0.3048)
		(layers "F.Cu" "B.Cu")
		(net "GND")
	)
	(via
		(at 121.811796 -23.830026)
		(size 0.5588)
		(drill 0.3048)
		(layers "F.Cu" "B.Cu")
		(net "GND")
	)
	(via
		(at 1.524 -291.233352)
		(size 0.7112)
		(drill 0.4064)
		(layers "F.Cu" "B.Cu")
		(net "GND")
	)
	(via
		(at 1.524 -194.713352)
		(size 0.7112)
		(drill 0.4064)
		(layers "F.Cu" "B.Cu")
		(net "GND")
	)
	(via
		(at 39.284402 -232.77195)
		(size 0.5588)
		(drill 0.3048)
		(layers "F.Cu" "B.Cu")
		(net "GND")
	)
	(via
		(at 94.084648 -1.524)
		(size 0.7112)
		(drill 0.4064)
		(layers "F.Cu" "B.Cu")
		(net "GND")
	)
	(via
		(at 449.286376 -1.524)
		(size 0.7112)
		(drill 0.4064)
		(layers "F.Cu" "B.Cu")
		(net "GND")
	)
	(via
		(at 312.523886 -12.08151)
		(size 0.7112)
		(drill 0.4064)
		(layers "F.Cu" "B.Cu")
		(net "GND")
	)
	(via
		(at 117.3734 -15.98676)
		(size 0.5588)
		(drill 0.3048)
		(layers "F.Cu" "B.Cu")
		(net "GND")
	)
	(via
		(at 428.117 -47.117)
		(size 0.5588)
		(drill 0.3048)
		(layers "F.Cu" "B.Cu")
		(net "GND")
	)
	(via
		(at 462.7499 -8.9916)
		(size 0.5588)
		(drill 0.3048)
		(layers "F.Cu" "B.Cu")
		(net "GND")
	)
	(via
		(at 341.239856 -384.47599)
		(size 0.7112)
		(drill 0.4064)
		(layers "F.Cu" "B.Cu")
		(net "GND")
	)
	(via
		(at 124.732796 -122.035062)
		(size 0.5588)
		(drill 0.3048)
		(layers "F.Cu" "B.Cu")
		(net "GND")
	)
	(via
		(at 139.804648 -1.524)
		(size 0.7112)
		(drill 0.4064)
		(layers "F.Cu" "B.Cu")
		(net "GND")
	)
	(via
		(at 147.955 -67.564)
		(size 0.5588)
		(drill 0.3048)
		(layers "F.Cu" "B.Cu")
		(net "GND")
	)
	(via
		(at 1.524 -113.433352)
		(size 0.7112)
		(drill 0.4064)
		(layers "F.Cu" "B.Cu")
		(net "GND")
	)
	(via
		(at 18.424906 -380.775972)
		(size 0.7112)
		(drill 0.4064)
		(layers "F.Cu" "B.Cu")
		(net "GND")
	)
	(via
		(at 325.654924 -148.35505)
		(size 0.5588)
		(drill 0.3048)
		(layers "F.Cu" "B.Cu")
		(net "GND")
	)
	(via
		(at 1.524 -143.913352)
		(size 0.7112)
		(drill 0.4064)
		(layers "F.Cu" "B.Cu")
		(net "GND")
	)
	(via
		(at 186.055 -30.815026)
		(size 0.5588)
		(drill 0.3048)
		(layers "F.Cu" "B.Cu")
		(net "GND")
	)
	(via
		(at 70.612 -140.716)
		(size 0.5588)
		(drill 0.3048)
		(layers "F.Cu" "B.Cu")
		(net "GND")
	)
	(via
		(at 186.055 -260.815074)
		(size 0.5588)
		(drill 0.3048)
		(layers "F.Cu" "B.Cu")
		(net "GND")
	)
	(via
		(at 153.361898 -256.23012)
		(size 0.5588)
		(drill 0.3048)
		(layers "F.Cu" "B.Cu")
		(net "GND")
	)
	(via
		(at 57.767982 -384.47599)
		(size 0.7112)
		(drill 0.4064)
		(layers "F.Cu" "B.Cu")
		(net "GND")
	)
	(via
		(at 489.926122 -323.59219)
		(size 0.7112)
		(drill 0.4064)
		(layers "F.Cu" "B.Cu")
		(net "GND")
	)
	(via
		(at 489.926122 -194.05219)
		(size 0.7112)
		(drill 0.4064)
		(layers "F.Cu" "B.Cu")
		(net "GND")
	)
	(via
		(at 1.524 -151.533352)
		(size 0.7112)
		(drill 0.4064)
		(layers "F.Cu" "B.Cu")
		(net "GND")
	)
	(via
		(at 346.416376 -1.524)
		(size 0.7112)
		(drill 0.4064)
		(layers "F.Cu" "B.Cu")
		(net "GND")
	)
	(via
		(at 489.926122 -65.78219)
		(size 0.7112)
		(drill 0.4064)
		(layers "F.Cu" "B.Cu")
		(net "GND")
	)
	(via
		(at 1.524 -58.823352)
		(size 0.7112)
		(drill 0.4064)
		(layers "F.Cu" "B.Cu")
		(net "GND")
	)
	(via
		(at 489.926122 -78.48219)
		(size 0.7112)
		(drill 0.4064)
		(layers "F.Cu" "B.Cu")
		(net "GND")
	)
	(via
		(at 489.926122 -357.88219)
		(size 0.7112)
		(drill 0.4064)
		(layers "F.Cu" "B.Cu")
		(net "GND")
	)
	(via
		(at 478.450402 -232.92435)
		(size 0.5588)
		(drill 0.3048)
		(layers "F.Cu" "B.Cu")
		(net "GND")
	)
	(via
		(at 489.926122 -201.67219)
		(size 0.7112)
		(drill 0.4064)
		(layers "F.Cu" "B.Cu")
		(net "GND")
	)
	(via
		(at 420.304976 -250.655074)
		(size 0.5588)
		(drill 0.3048)
		(layers "F.Cu" "B.Cu")
		(net "GND")
	)
	(via
		(at 447.8782 -260.2992)
		(size 0.5588)
		(drill 0.3048)
		(layers "F.Cu" "B.Cu")
		(net "GND")
	)
	(via
		(at 486.925874 -375.700036)
		(size 0.7112)
		(drill 0.4064)
		(layers "F.Cu" "B.Cu")
		(net "GND")
	)
	(via
		(at 451.854824 -250.655074)
		(size 0.5588)
		(drill 0.3048)
		(layers "F.Cu" "B.Cu")
		(net "GND")
	)
	(via
		(at 489.926122 -3.55219)
		(size 0.7112)
		(drill 0.4064)
		(layers "F.Cu" "B.Cu")
		(net "GND")
	)
	(via
		(at 443.484 -26.924)
		(size 0.5588)
		(drill 0.3048)
		(layers "F.Cu" "B.Cu")
		(net "GND")
	)
	(via
		(at 489.926122 -244.85219)
		(size 0.7112)
		(drill 0.4064)
		(layers "F.Cu" "B.Cu")
		(net "GND")
	)
	(via
		(at 176.403 -260.604)
		(size 0.5588)
		(drill 0.3048)
		(layers "F.Cu" "B.Cu")
		(net "GND")
	)
	(via
		(at 357.205026 -20.655026)
		(size 0.5588)
		(drill 0.3048)
		(layers "F.Cu" "B.Cu")
		(net "GND")
	)
	(via
		(at 221.437962 -378.476002)
		(size 0.7112)
		(drill 0.4064)
		(layers "F.Cu" "B.Cu")
		(net "GND")
	)
	(via
		(at 450.711824 -253.830074)
		(size 0.5588)
		(drill 0.3048)
		(layers "F.Cu" "B.Cu")
		(net "GND")
	)
	(via
		(at 489.926122 -30.22219)
		(size 0.7112)
		(drill 0.4064)
		(layers "F.Cu" "B.Cu")
		(net "GND")
	)
	(via
		(at 144.272 -48.26)
		(size 0.5588)
		(drill 0.3048)
		(layers "F.Cu" "B.Cu")
		(net "GND")
	)
	(via
		(at 325.654924 -30.815026)
		(size 0.5588)
		(drill 0.3048)
		(layers "F.Cu" "B.Cu")
		(net "GND")
	)
	(via
		(at 392.357864 -378.476002)
		(size 0.7112)
		(drill 0.4064)
		(layers "F.Cu" "B.Cu")
		(net "GND")
	)
	(via
		(at 70.467982 -384.47599)
		(size 0.7112)
		(drill 0.4064)
		(layers "F.Cu" "B.Cu")
		(net "GND")
	)
	(via
		(at 427.6598 -14.859)
		(size 0.5588)
		(drill 0.3048)
		(layers "F.Cu" "B.Cu")
		(net "GND")
	)
	(via
		(at 186.055 -131.84505)
		(size 0.5588)
		(drill 0.3048)
		(layers "F.Cu" "B.Cu")
		(net "GND")
	)
	(via
		(at 329.692 -257.556)
		(size 0.5588)
		(drill 0.3048)
		(layers "F.Cu" "B.Cu")
		(net "GND")
	)
	(via
		(at 82.296 -49.784)
		(size 0.5588)
		(drill 0.3048)
		(layers "F.Cu" "B.Cu")
		(net "GND")
	)
	(via
		(at 39.624 -138.176)
		(size 0.5588)
		(drill 0.3048)
		(layers "F.Cu" "B.Cu")
		(net "GND")
	)
	(via
		(at 453.632824 -237.035086)
		(size 0.5588)
		(drill 0.3048)
		(layers "F.Cu" "B.Cu")
		(net "GND")
	)
	(via
		(at 388.754874 -38.435026)
		(size 0.5588)
		(drill 0.3048)
		(layers "F.Cu" "B.Cu")
		(net "GND")
	)
	(via
		(at 438.912 -140.716)
		(size 0.5588)
		(drill 0.3048)
		(layers "F.Cu" "B.Cu")
		(net "GND")
	)
	(via
		(at 355.075998 -50.787554)
		(size 0.5588)
		(drill 0.3048)
		(layers "F.Cu" "B.Cu")
		(net "GND")
	)
	(via
		(at 46.167802 -230.51135)
		(size 0.5588)
		(drill 0.3048)
		(layers "F.Cu" "B.Cu")
		(net "GND")
	)
	(via
		(at 467.614 -265.684)
		(size 0.5588)
		(drill 0.3048)
		(layers "F.Cu" "B.Cu")
		(net "GND")
	)
	(via
		(at 197.47611 -20.052538)
		(size 0.7112)
		(drill 0.4064)
		(layers "F.Cu" "B.Cu")
		(net "GND")
	)
	(via
		(at 149.6695 -250.444)
		(size 0.5588)
		(drill 0.3048)
		(layers "F.Cu" "B.Cu")
		(net "GND")
	)
	(via
		(at 1.524 -15.643352)
		(size 0.7112)
		(drill 0.4064)
		(layers "F.Cu" "B.Cu")
		(net "GND")
	)
	(via
		(at 457.581 -277.114)
		(size 0.5588)
		(drill 0.3048)
		(layers "F.Cu" "B.Cu")
		(net "GND")
	)
	(via
		(at 489.926122 -364.23219)
		(size 0.7112)
		(drill 0.4064)
		(layers "F.Cu" "B.Cu")
		(net "GND")
	)
	(via
		(at 353.3648 -30.353)
		(size 0.5588)
		(drill 0.3048)
		(layers "F.Cu" "B.Cu")
		(net "GND")
	)
	(via
		(at 47.8155 -139.941554)
		(size 0.5588)
		(drill 0.3048)
		(layers "F.Cu" "B.Cu")
		(net "GND")
	)
	(via
		(at 408.646376 -1.524)
		(size 0.7112)
		(drill 0.4064)
		(layers "F.Cu" "B.Cu")
		(net "GND")
	)
	(via
		(at 13.56995 -216.8144)
		(size 0.5588)
		(drill 0.3048)
		(layers "F.Cu" "B.Cu")
		(net "GND")
	)
	(via
		(at 486.116376 -1.524)
		(size 0.7112)
		(drill 0.4064)
		(layers "F.Cu" "B.Cu")
		(net "GND")
	)
	(via
		(at 61.577982 -384.47599)
		(size 0.7112)
		(drill 0.4064)
		(layers "F.Cu" "B.Cu")
		(net "GND")
	)
	(via
		(at 111.864648 -1.524)
		(size 0.7112)
		(drill 0.4064)
		(layers "F.Cu" "B.Cu")
		(net "GND")
	)
	(via
		(at 208.28 -367.792)
		(size 0.5588)
		(drill 0.3048)
		(layers "F.Cu" "B.Cu")
		(net "GND")
	)
	(via
		(at 38.1 -88.9)
		(size 0.5588)
		(drill 0.3048)
		(layers "F.Cu" "B.Cu")
		(net "GND")
	)
	(via
		(at 279.571958 -101.186488)
		(size 0.7112)
		(drill 0.4064)
		(layers "F.Cu" "B.Cu")
		(net "GND")
	)
	(via
		(at 406.908 -173.736)
		(size 0.5588)
		(drill 0.3048)
		(layers "F.Cu" "B.Cu")
		(net "GND")
	)
	(via
		(at 220.091 -353.794568)
		(size 0.5588)
		(drill 0.3048)
		(layers "F.Cu" "B.Cu")
		(net "GND")
	)
	(via
		(at 201.7014 -305.3334)
		(size 0.7112)
		(drill 0.4064)
		(layers "F.Cu" "B.Cu")
		(net "GND")
	)
	(via
		(at 122.954796 -30.815026)
		(size 0.5588)
		(drill 0.3048)
		(layers "F.Cu" "B.Cu")
		(net "GND")
	)
	(via
		(at 1.524 -131.213352)
		(size 0.7112)
		(drill 0.4064)
		(layers "F.Cu" "B.Cu")
		(net "GND")
	)
	(via
		(at 375.847864 -378.476002)
		(size 0.7112)
		(drill 0.4064)
		(layers "F.Cu" "B.Cu")
		(net "GND")
	)
	(via
		(at 127 -292.1)
		(size 0.5588)
		(drill 0.3048)
		(layers "F.Cu" "B.Cu")
		(net "GND")
	)
	(via
		(at 489.926122 -298.19219)
		(size 0.7112)
		(drill 0.4064)
		(layers "F.Cu" "B.Cu")
		(net "GND")
	)
	(via
		(at 239.217962 -378.476002)
		(size 0.7112)
		(drill 0.4064)
		(layers "F.Cu" "B.Cu")
		(net "GND")
	)
	(via
		(at 404.876 -14.224)
		(size 0.5588)
		(drill 0.3048)
		(layers "F.Cu" "B.Cu")
		(net "GND")
	)
	(via
		(at 362.17606 -381.028194)
		(size 0.7112)
		(drill 0.4064)
		(layers "F.Cu" "B.Cu")
		(net "GND")
	)
	(via
		(at 1.524 -361.083352)
		(size 0.7112)
		(drill 0.4064)
		(layers "F.Cu" "B.Cu")
		(net "GND")
	)
	(via
		(at 377.117864 -378.476002)
		(size 0.7112)
		(drill 0.4064)
		(layers "F.Cu" "B.Cu")
		(net "GND")
	)
	(via
		(at 388.754874 -128.03505)
		(size 0.5588)
		(drill 0.3048)
		(layers "F.Cu" "B.Cu")
		(net "GND")
	)
	(via
		(at 278.274018 -372.378478)
		(size 0.7112)
		(drill 0.4064)
		(layers "F.Cu" "B.Cu")
		(net "GND")
	)
	(via
		(at 264.260076 -197.252082)
		(size 0.7112)
		(drill 0.4064)
		(layers "F.Cu" "B.Cu")
		(net "GND")
	)
	(via
		(at 259.383276 -197.226682)
		(size 0.7112)
		(drill 0.4064)
		(layers "F.Cu" "B.Cu")
		(net "GND")
	)
	(via
		(at 489.926122 -232.15219)
		(size 0.7112)
		(drill 0.4064)
		(layers "F.Cu" "B.Cu")
		(net "GND")
	)
	(via
		(at 306.324 -109.347)
		(size 0.5588)
		(drill 0.3048)
		(layers "F.Cu" "B.Cu")
		(net "GND")
	)
	(via
		(at 1.524 -275.993352)
		(size 0.7112)
		(drill 0.4064)
		(layers "F.Cu" "B.Cu")
		(net "GND")
	)
	(via
		(at 409.448 -248.92)
		(size 0.5588)
		(drill 0.3048)
		(layers "F.Cu" "B.Cu")
		(net "GND")
	)
	(via
		(at 97.536 -118.872)
		(size 0.5588)
		(drill 0.3048)
		(layers "F.Cu" "B.Cu")
		(net "GND")
	)
	(via
		(at 202.062588 -49.724056)
		(size 0.7112)
		(drill 0.4064)
		(layers "F.Cu" "B.Cu")
		(net "GND")
	)
	(via
		(at 204.0128 -142.7988)
		(size 0.7112)
		(drill 0.4064)
		(layers "F.Cu" "B.Cu")
		(net "GND")
	)
	(via
		(at 317.206376 -1.524)
		(size 0.7112)
		(drill 0.4064)
		(layers "F.Cu" "B.Cu")
		(net "GND")
	)
	(via
		(at 179.7558 -250.4948)
		(size 0.5588)
		(drill 0.3048)
		(layers "F.Cu" "B.Cu")
		(net "GND")
	)
	(via
		(at 91.404948 -20.655026)
		(size 0.5588)
		(drill 0.3048)
		(layers "F.Cu" "B.Cu")
		(net "GND")
	)
	(via
		(at 28.304998 -20.655026)
		(size 0.5588)
		(drill 0.3048)
		(layers "F.Cu" "B.Cu")
		(net "GND")
	)
	(via
		(at 333.502 -47.117)
		(size 0.5588)
		(drill 0.3048)
		(layers "F.Cu" "B.Cu")
		(net "GND")
	)
	(via
		(at 185.217054 -22.17039)
		(size 0.5588)
		(drill 0.3048)
		(layers "F.Cu" "B.Cu")
		(net "GND")
	)
	(via
		(at 451.854824 -40.975026)
		(size 0.5588)
		(drill 0.3048)
		(layers "F.Cu" "B.Cu")
		(net "GND")
	)
	(via
		(at 458.506068 -101.849428)
		(size 0.5588)
		(drill 0.3048)
		(layers "F.Cu" "B.Cu")
		(net "GND")
	)
	(via
		(at 418.973 -380.365)
		(size 0.7112)
		(drill 0.4064)
		(layers "F.Cu" "B.Cu")
		(net "GND")
	)
	(via
		(at 463.804 -263.271)
		(size 0.5588)
		(drill 0.3048)
		(layers "F.Cu" "B.Cu")
		(net "GND")
	)
	(via
		(at 467.425024 -380.775972)
		(size 0.7112)
		(drill 0.4064)
		(layers "F.Cu" "B.Cu")
		(net "GND")
	)
	(via
		(at 28.304998 -128.03505)
		(size 0.5588)
		(drill 0.3048)
		(layers "F.Cu" "B.Cu")
		(net "GND")
	)
	(via
		(at 187.833 -280.785062)
		(size 0.5588)
		(drill 0.3048)
		(layers "F.Cu" "B.Cu")
		(net "GND")
	)
	(via
		(at 145.288 -18.6182)
		(size 0.5588)
		(drill 0.3048)
		(layers "F.Cu" "B.Cu")
		(net "GND")
	)
	(via
		(at 298.128436 -49.724056)
		(size 0.7112)
		(drill 0.4064)
		(layers "F.Cu" "B.Cu")
		(net "GND")
	)
	(via
		(at 33.02 -142.24)
		(size 0.5588)
		(drill 0.3048)
		(layers "F.Cu" "B.Cu")
		(net "GND")
	)
	(via
		(at 197.47611 -18.782538)
		(size 0.7112)
		(drill 0.4064)
		(layers "F.Cu" "B.Cu")
		(net "GND")
	)
	(via
		(at 489.926122 -272.79219)
		(size 0.7112)
		(drill 0.4064)
		(layers "F.Cu" "B.Cu")
		(net "GND")
	)
	(via
		(at 1.524 -248.053352)
		(size 0.7112)
		(drill 0.4064)
		(layers "F.Cu" "B.Cu")
		(net "GND")
	)
	(via
		(at 398.486376 -1.524)
		(size 0.7112)
		(drill 0.4064)
		(layers "F.Cu" "B.Cu")
		(net "GND")
	)
	(via
		(at 390.532874 -237.035086)
		(size 0.5588)
		(drill 0.3048)
		(layers "F.Cu" "B.Cu")
		(net "GND")
	)
	(via
		(at 122.954796 -155.97505)
		(size 0.5588)
		(drill 0.3048)
		(layers "F.Cu" "B.Cu")
		(net "GND")
	)
	(via
		(at 368.3 -342.9)
		(size 0.5588)
		(drill 0.3048)
		(layers "F.Cu" "B.Cu")
		(net "GND")
	)
	(via
		(at 370.767864 -378.476002)
		(size 0.7112)
		(drill 0.4064)
		(layers "F.Cu" "B.Cu")
		(net "GND")
	)
	(via
		(at 209.804 -255.016)
		(size 0.5588)
		(drill 0.3048)
		(layers "F.Cu" "B.Cu")
		(net "GND")
	)
	(via
		(at 270.52397 -51.28133)
		(size 0.7112)
		(drill 0.4064)
		(layers "F.Cu" "B.Cu")
		(net "GND")
	)
	(via
		(at 334.772 -167.64)
		(size 0.5588)
		(drill 0.3048)
		(layers "F.Cu" "B.Cu")
		(net "GND")
	)
	(via
		(at 388.754874 -135.65505)
		(size 0.5588)
		(drill 0.3048)
		(layers "F.Cu" "B.Cu")
		(net "GND")
	)
	(via
		(at 283.0576 -306.5018)
		(size 0.7112)
		(drill 0.4064)
		(layers "F.Cu" "B.Cu")
		(net "GND")
	)
	(via
		(at 425.45 -268.605)
		(size 0.5588)
		(drill 0.3048)
		(layers "F.Cu" "B.Cu")
		(net "GND")
	)
	(via
		(at 396.1638 -244.856)
		(size 0.5588)
		(drill 0.3048)
		(layers "F.Cu" "B.Cu")
		(net "GND")
	)
	(via
		(at 273.812 -296.164)
		(size 0.5588)
		(drill 0.3048)
		(layers "F.Cu" "B.Cu")
		(net "GND")
	)
	(via
		(at 412.456376 -1.524)
		(size 0.7112)
		(drill 0.4064)
		(layers "F.Cu" "B.Cu")
		(net "GND")
	)
	(via
		(at 315.936376 -1.524)
		(size 0.7112)
		(drill 0.4064)
		(layers "F.Cu" "B.Cu")
		(net "GND")
	)
	(via
		(at 430.875186 -114.987578)
		(size 0.5588)
		(drill 0.3048)
		(layers "F.Cu" "B.Cu")
		(net "GND")
	)
	(via
		(at 417.536376 -1.524)
		(size 0.7112)
		(drill 0.4064)
		(layers "F.Cu" "B.Cu")
		(net "GND")
	)
	(via
		(at 28.304998 -131.84505)
		(size 0.5588)
		(drill 0.3048)
		(layers "F.Cu" "B.Cu")
		(net "GND")
	)
	(via
		(at 183.896 -383.413)
		(size 0.7112)
		(drill 0.4064)
		(layers "F.Cu" "B.Cu")
		(net "GND")
	)
	(via
		(at 456.021186 -122.556778)
		(size 0.5588)
		(drill 0.3048)
		(layers "F.Cu" "B.Cu")
		(net "GND")
	)
	(via
		(at 489.926122 -68.32219)
		(size 0.7112)
		(drill 0.4064)
		(layers "F.Cu" "B.Cu")
		(net "GND")
	)
	(via
		(at 387.611874 -256.23012)
		(size 0.5588)
		(drill 0.3048)
		(layers "F.Cu" "B.Cu")
		(net "GND")
	)
	(via
		(at 227.787962 -378.476002)
		(size 0.7112)
		(drill 0.4064)
		(layers "F.Cu" "B.Cu")
		(net "GND")
	)
	(via
		(at 333.495142 -163.354512)
		(size 0.5588)
		(drill 0.3048)
		(layers "F.Cu" "B.Cu")
		(net "GND")
	)
	(via
		(at 392.938 -277.114)
		(size 0.5588)
		(drill 0.3048)
		(layers "F.Cu" "B.Cu")
		(net "GND")
	)
	(via
		(at 486.925874 -373.160036)
		(size 0.7112)
		(drill 0.4064)
		(layers "F.Cu" "B.Cu")
		(net "GND")
	)
	(via
		(at 489.926122 -188.97219)
		(size 0.7112)
		(drill 0.4064)
		(layers "F.Cu" "B.Cu")
		(net "GND")
	)
	(via
		(at 176.3268 -33.782)
		(size 0.5588)
		(drill 0.3048)
		(layers "F.Cu" "B.Cu")
		(net "GND")
	)
	(via
		(at 489.926122 -335.02219)
		(size 0.7112)
		(drill 0.4064)
		(layers "F.Cu" "B.Cu")
		(net "GND")
	)
	(via
		(at 15.344648 -1.524)
		(size 0.7112)
		(drill 0.4064)
		(layers "F.Cu" "B.Cu")
		(net "GND")
	)
	(via
		(at 312.523886 -1.92151)
		(size 0.7112)
		(drill 0.4064)
		(layers "F.Cu" "B.Cu")
		(net "GND")
	)
	(via
		(at 357.205026 -38.435026)
		(size 0.5588)
		(drill 0.3048)
		(layers "F.Cu" "B.Cu")
		(net "GND")
	)
	(via
		(at 125.603 -378.587)
		(size 0.7112)
		(drill 0.4064)
		(layers "F.Cu" "B.Cu")
		(net "GND")
	)
	(via
		(at 280.18994 -384.284728)
		(size 0.7112)
		(drill 0.4064)
		(layers "F.Cu" "B.Cu")
		(net "GND")
	)
	(via
		(at 66.657982 -384.47599)
		(size 0.7112)
		(drill 0.4064)
		(layers "F.Cu" "B.Cu")
		(net "GND")
	)
	(via
		(at 1.524 -192.173352)
		(size 0.7112)
		(drill 0.4064)
		(layers "F.Cu" "B.Cu")
		(net "GND")
	)
	(via
		(at 489.926122 -182.62219)
		(size 0.7112)
		(drill 0.4064)
		(layers "F.Cu" "B.Cu")
		(net "GND")
	)
	(via
		(at 256.064004 -384.457956)
		(size 0.7112)
		(drill 0.4064)
		(layers "F.Cu" "B.Cu")
		(net "GND")
	)
	(via
		(at 223.19996 -166.41826)
		(size 0.5588)
		(drill 0.3048)
		(layers "F.Cu" "B.Cu")
		(net "GND")
	)
	(via
		(at 286.6898 -304.0126)
		(size 0.7112)
		(drill 0.4064)
		(layers "F.Cu" "B.Cu")
		(net "GND")
	)
	(via
		(at 332.105 -242.316)
		(size 0.5588)
		(drill 0.3048)
		(layers "F.Cu" "B.Cu")
		(net "GND")
	)
	(via
		(at 418.592 -118.872)
		(size 0.5588)
		(drill 0.3048)
		(layers "F.Cu" "B.Cu")
		(net "GND")
	)
	(via
		(at 369.276376 -1.524)
		(size 0.7112)
		(drill 0.4064)
		(layers "F.Cu" "B.Cu")
		(net "GND")
	)
	(via
		(at 177.8 -50.8)
		(size 0.5588)
		(drill 0.3048)
		(layers "F.Cu" "B.Cu")
		(net "GND")
	)
	(via
		(at 270.926052 -367.641632)
		(size 0.7112)
		(drill 0.4064)
		(layers "F.Cu" "B.Cu")
		(net "GND")
	)
	(via
		(at 262.219694 -282.965906)
		(size 0.5588)
		(drill 0.3048)
		(layers "F.Cu" "B.Cu")
		(net "GND")
	)
	(via
		(at 210.058 -250.317)
		(size 0.5588)
		(drill 0.3048)
		(layers "F.Cu" "B.Cu")
		(net "GND")
	)
	(via
		(at 489.926122 -366.77219)
		(size 0.7112)
		(drill 0.4064)
		(layers "F.Cu" "B.Cu")
		(net "GND")
	)
	(via
		(at 8.636 -201.168)
		(size 0.5588)
		(drill 0.3048)
		(layers "F.Cu" "B.Cu")
		(net "GND")
	)
	(via
		(at 105.514648 -1.524)
		(size 0.7112)
		(drill 0.4064)
		(layers "F.Cu" "B.Cu")
		(net "GND")
	)
	(via
		(at 213.995 -358.481122)
		(size 0.5588)
		(drill 0.3048)
		(layers "F.Cu" "B.Cu")
		(net "GND")
	)
	(via
		(at 68.98386 -119.326406)
		(size 0.5588)
		(drill 0.3048)
		(layers "F.Cu" "B.Cu")
		(net "GND")
	)
	(via
		(at 5.184648 -1.524)
		(size 0.7112)
		(drill 0.4064)
		(layers "F.Cu" "B.Cu")
		(net "GND")
	)
	(via
		(at 489.926122 -77.21219)
		(size 0.7112)
		(drill 0.4064)
		(layers "F.Cu" "B.Cu")
		(net "GND")
	)
	(via
		(at 457.581 -162.179)
		(size 0.5588)
		(drill 0.3048)
		(layers "F.Cu" "B.Cu")
		(net "GND")
	)
	(via
		(at 489.926122 -61.97219)
		(size 0.7112)
		(drill 0.4064)
		(layers "F.Cu" "B.Cu")
		(net "GND")
	)
	(via
		(at 220.8022 -65.666874)
		(size 0.6604)
		(drill 0.3556)
		(layers "F.Cu" "B.Cu")
		(net "GND")
	)
	(via
		(at 12.573 -265.684)
		(size 0.5588)
		(drill 0.3048)
		(layers "F.Cu" "B.Cu")
		(net "GND")
	)
	(via
		(at 404.368 -59.944)
		(size 0.5588)
		(drill 0.3048)
		(layers "F.Cu" "B.Cu")
		(net "GND")
	)
	(via
		(at 385.786376 -1.524)
		(size 0.7112)
		(drill 0.4064)
		(layers "F.Cu" "B.Cu")
		(net "GND")
	)
	(via
		(at 44.135802 -230.51135)
		(size 0.5588)
		(drill 0.3048)
		(layers "F.Cu" "B.Cu")
		(net "GND")
	)
	(via
		(at 463.81416 -384.38201)
		(size 0.7112)
		(drill 0.4064)
		(layers "F.Cu" "B.Cu")
		(net "GND")
	)
	(via
		(at 1.524 -138.833352)
		(size 0.7112)
		(drill 0.4064)
		(layers "F.Cu" "B.Cu")
		(net "GND")
	)
	(via
		(at 22.606 -225.933)
		(size 0.5588)
		(drill 0.3048)
		(layers "F.Cu" "B.Cu")
		(net "GND")
	)
	(via
		(at 485.541828 -384.47599)
		(size 0.7112)
		(drill 0.4064)
		(layers "F.Cu" "B.Cu")
		(net "GND")
	)
	(via
		(at 94.866968 -339.710014)
		(size 0.5588)
		(drill 0.3048)
		(layers "F.Cu" "B.Cu")
		(net "GND")
	)
	(via
		(at 420.304976 -268.435074)
		(size 0.5588)
		(drill 0.3048)
		(layers "F.Cu" "B.Cu")
		(net "GND")
	)
	(via
		(at 202.7936 -141.5796)
		(size 0.7112)
		(drill 0.4064)
		(layers "F.Cu" "B.Cu")
		(net "GND")
	)
	(via
		(at 65.024 -372.364)
		(size 0.5588)
		(drill 0.3048)
		(layers "F.Cu" "B.Cu")
		(net "GND")
	)
	(via
		(at 90.261948 -256.23012)
		(size 0.5588)
		(drill 0.3048)
		(layers "F.Cu" "B.Cu")
		(net "GND")
	)
	(via
		(at 285.651448 -352.748342)
		(size 0.5588)
		(drill 0.3048)
		(layers "F.Cu" "B.Cu")
		(net "GND")
	)
	(via
		(at 422.616376 -1.524)
		(size 0.7112)
		(drill 0.4064)
		(layers "F.Cu" "B.Cu")
		(net "GND")
	)
	(via
		(at 1.524 -265.833352)
		(size 0.7112)
		(drill 0.4064)
		(layers "F.Cu" "B.Cu")
		(net "GND")
	)
	(via
		(at 121.811796 -138.83005)
		(size 0.5588)
		(drill 0.3048)
		(layers "F.Cu" "B.Cu")
		(net "GND")
	)
	(via
		(at 91.404948 -16.845026)
		(size 0.5588)
		(drill 0.3048)
		(layers "F.Cu" "B.Cu")
		(net "GND")
	)
	(via
		(at 1.524 -223.923352)
		(size 0.7112)
		(drill 0.4064)
		(layers "F.Cu" "B.Cu")
		(net "GND")
	)
	(via
		(at 450.711824 -141.230096)
		(size 0.5588)
		(drill 0.3048)
		(layers "F.Cu" "B.Cu")
		(net "GND")
	)
	(via
		(at 40.57396 -215.067388)
		(size 0.5588)
		(drill 0.3048)
		(layers "F.Cu" "B.Cu")
		(net "GND")
	)
	(via
		(at 52.324 -256.667)
		(size 0.5588)
		(drill 0.3048)
		(layers "F.Cu" "B.Cu")
		(net "GND")
	)
	(via
		(at 262.414004 -384.457956)
		(size 0.7112)
		(drill 0.4064)
		(layers "F.Cu" "B.Cu")
		(net "GND")
	)
	(via
		(at 199.141588 -49.470056)
		(size 0.7112)
		(drill 0.4064)
		(layers "F.Cu" "B.Cu")
		(net "GND")
	)
	(via
		(at 388.754874 -270.975074)
		(size 0.5588)
		(drill 0.3048)
		(layers "F.Cu" "B.Cu")
		(net "GND")
	)
	(via
		(at 4.523994 -374.064022)
		(size 0.7112)
		(drill 0.4064)
		(layers "F.Cu" "B.Cu")
		(net "GND")
	)
	(via
		(at 288.911284 -144.694402)
		(size 0.6604)
		(drill 0.3556)
		(layers "F.Cu" "B.Cu")
		(net "GND")
	)
	(via
		(at 104.14 -156.464)
		(size 0.5588)
		(drill 0.3048)
		(layers "F.Cu" "B.Cu")
		(net "GND")
	)
	(via
		(at 205.476094 -60.116212)
		(size 0.7112)
		(drill 0.4064)
		(layers "F.Cu" "B.Cu")
		(net "GND")
	)
	(via
		(at 457.2 -203.2)
		(size 0.5588)
		(drill 0.3048)
		(layers "F.Cu" "B.Cu")
		(net "GND")
	)
	(via
		(at 93.182948 -165.785038)
		(size 0.5588)
		(drill 0.3048)
		(layers "F.Cu" "B.Cu")
		(net "GND")
	)
	(via
		(at 279.4 -63.5)
		(size 0.5588)
		(drill 0.3048)
		(layers "F.Cu" "B.Cu")
		(net "GND")
	)
	(via
		(at 451.854824 -153.43505)
		(size 0.5588)
		(drill 0.3048)
		(layers "F.Cu" "B.Cu")
		(net "GND")
	)
	(via
		(at 19.05 -248.6152)
		(size 0.5588)
		(drill 0.3048)
		(layers "F.Cu" "B.Cu")
		(net "GND")
	)
	(via
		(at 287.241742 -378.675392)
		(size 0.5588)
		(drill 0.3048)
		(layers "F.Cu" "B.Cu")
		(net "GND")
	)
	(via
		(at 172.339 -383.667)
		(size 0.7112)
		(drill 0.4064)
		(layers "F.Cu" "B.Cu")
		(net "GND")
	)
	(via
		(at 489.926122 -248.66219)
		(size 0.7112)
		(drill 0.4064)
		(layers "F.Cu" "B.Cu")
		(net "GND")
	)
	(via
		(at 393.319 -15.9766)
		(size 0.5588)
		(drill 0.3048)
		(layers "F.Cu" "B.Cu")
		(net "GND")
	)
	(via
		(at 59.854846 -148.35505)
		(size 0.5588)
		(drill 0.3048)
		(layers "F.Cu" "B.Cu")
		(net "GND")
	)
	(via
		(at 333.756 -38.227)
		(size 0.5588)
		(drill 0.3048)
		(layers "F.Cu" "B.Cu")
		(net "GND")
	)
	(via
		(at 1.524 -229.003352)
		(size 0.7112)
		(drill 0.4064)
		(layers "F.Cu" "B.Cu")
		(net "GND")
	)
	(via
		(at 489.926122 -276.60219)
		(size 0.7112)
		(drill 0.4064)
		(layers "F.Cu" "B.Cu")
		(net "GND")
	)
	(via
		(at 357.205026 -270.975074)
		(size 0.5588)
		(drill 0.3048)
		(layers "F.Cu" "B.Cu")
		(net "GND")
	)
	(via
		(at 27.287982 -384.47599)
		(size 0.7112)
		(drill 0.4064)
		(layers "F.Cu" "B.Cu")
		(net "GND")
	)
	(via
		(at 328.803 -84.201)
		(size 0.5588)
		(drill 0.3048)
		(layers "F.Cu" "B.Cu")
		(net "GND")
	)
	(via
		(at 221.375224 -326.131174)
		(size 0.5588)
		(drill 0.3048)
		(layers "F.Cu" "B.Cu")
		(net "GND")
	)
	(via
		(at 87.376 -47.244)
		(size 0.5588)
		(drill 0.3048)
		(layers "F.Cu" "B.Cu")
		(net "GND")
	)
	(via
		(at 473.837 -381)
		(size 0.7112)
		(drill 0.4064)
		(layers "F.Cu" "B.Cu")
		(net "GND")
	)
	(via
		(at 489.926122 -348.99219)
		(size 0.7112)
		(drill 0.4064)
		(layers "F.Cu" "B.Cu")
		(net "GND")
	)
	(via
		(at 312.523886 -18.43151)
		(size 0.7112)
		(drill 0.4064)
		(layers "F.Cu" "B.Cu")
		(net "GND")
	)
	(via
		(at 154.504898 -38.435026)
		(size 0.5588)
		(drill 0.3048)
		(layers "F.Cu" "B.Cu")
		(net "GND")
	)
	(via
		(at 489.926122 -308.35219)
		(size 0.7112)
		(drill 0.4064)
		(layers "F.Cu" "B.Cu")
		(net "GND")
	)
	(via
		(at 489.926122 -148.33219)
		(size 0.7112)
		(drill 0.4064)
		(layers "F.Cu" "B.Cu")
		(net "GND")
	)
	(via
		(at 480.761802 -230.51135)
		(size 0.5588)
		(drill 0.3048)
		(layers "F.Cu" "B.Cu")
		(net "GND")
	)
	(via
		(at 9.352026 -384.47599)
		(size 0.7112)
		(drill 0.4064)
		(layers "F.Cu" "B.Cu")
		(net "GND")
	)
	(via
		(at 205.105 -120.3198)
		(size 0.5588)
		(drill 0.3048)
		(layers "F.Cu" "B.Cu")
		(net "GND")
	)
	(via
		(at 257.408172 -373.59971)
		(size 0.5588)
		(drill 0.3048)
		(layers "F.Cu" "B.Cu")
		(net "GND")
	)
	(via
		(at 366.395 -250.063)
		(size 0.5588)
		(drill 0.3048)
		(layers "F.Cu" "B.Cu")
		(net "GND")
	)
	(via
		(at 194.414648 -1.524)
		(size 0.7112)
		(drill 0.4064)
		(layers "F.Cu" "B.Cu")
		(net "GND")
	)
	(via
		(at 92.477844 -333.554832)
		(size 0.5588)
		(drill 0.3048)
		(layers "F.Cu" "B.Cu")
		(net "GND")
	)
	(via
		(at 197.612 -2.413)
		(size 0.7112)
		(drill 0.4064)
		(layers "F.Cu" "B.Cu")
		(net "GND")
	)
	(via
		(at 179.7558 -135.4328)
		(size 0.5588)
		(drill 0.3048)
		(layers "F.Cu" "B.Cu")
		(net "GND")
	)
	(via
		(at 1.524 -146.453352)
		(size 0.7112)
		(drill 0.4064)
		(layers "F.Cu" "B.Cu")
		(net "GND")
	)
	(via
		(at 98.425 -238.506)
		(size 0.5588)
		(drill 0.3048)
		(layers "F.Cu" "B.Cu")
		(net "GND")
	)
	(via
		(at 250.563634 -210.747864)
		(size 0.5588)
		(drill 0.3048)
		(layers "F.Cu" "B.Cu")
		(net "GND")
	)
	(via
		(at 260.14045 -376.476006)
		(size 0.5588)
		(drill 0.3048)
		(layers "F.Cu" "B.Cu")
		(net "GND")
	)
	(via
		(at 132.063998 -384.47599)
		(size 0.7112)
		(drill 0.4064)
		(layers "F.Cu" "B.Cu")
		(net "GND")
	)
	(via
		(at 27.161998 -141.230096)
		(size 0.5588)
		(drill 0.3048)
		(layers "F.Cu" "B.Cu")
		(net "GND")
	)
	(via
		(at 39.303198 -216.11463)
		(size 0.5588)
		(drill 0.3048)
		(layers "F.Cu" "B.Cu")
		(net "GND")
	)
	(via
		(at 448.630802 -227.20935)
		(size 0.5588)
		(drill 0.3048)
		(layers "F.Cu" "B.Cu")
		(net "GND")
	)
	(via
		(at 87.296752 -338.514944)
		(size 0.5588)
		(drill 0.3048)
		(layers "F.Cu" "B.Cu")
		(net "GND")
	)
	(via
		(at 197.993 -378.714)
		(size 0.7112)
		(drill 0.4064)
		(layers "F.Cu" "B.Cu")
		(net "GND")
	)
	(via
		(at 452.501 -92.964)
		(size 0.5588)
		(drill 0.3048)
		(layers "F.Cu" "B.Cu")
		(net "GND")
	)
	(via
		(at 4.523994 -377.874022)
		(size 0.7112)
		(drill 0.4064)
		(layers "F.Cu" "B.Cu")
		(net "GND")
	)
	(via
		(at 45.8216 -216.4842)
		(size 0.5588)
		(drill 0.3048)
		(layers "F.Cu" "B.Cu")
		(net "GND")
	)
	(via
		(at 241.935 -288.163)
		(size 0.5588)
		(drill 0.3048)
		(layers "F.Cu" "B.Cu")
		(net "GND")
	)
	(via
		(at 6.454648 -1.524)
		(size 0.7112)
		(drill 0.4064)
		(layers "F.Cu" "B.Cu")
		(net "GND")
	)
	(via
		(at 396.621 -47.117)
		(size 0.5588)
		(drill 0.3048)
		(layers "F.Cu" "B.Cu")
		(net "GND")
	)
	(via
		(at 135.636 -56.515)
		(size 0.5588)
		(drill 0.3048)
		(layers "F.Cu" "B.Cu")
		(net "GND")
	)
	(via
		(at 130.793998 -384.47599)
		(size 0.7112)
		(drill 0.4064)
		(layers "F.Cu" "B.Cu")
		(net "GND")
	)
	(via
		(at 342.9 -279.4)
		(size 0.5588)
		(drill 0.3048)
		(layers "F.Cu" "B.Cu")
		(net "GND")
	)
	(via
		(at 470.916 -122.428)
		(size 0.5588)
		(drill 0.3048)
		(layers "F.Cu" "B.Cu")
		(net "GND")
	)
	(via
		(at 120.754648 -1.524)
		(size 0.7112)
		(drill 0.4064)
		(layers "F.Cu" "B.Cu")
		(net "GND")
	)
	(via
		(at 406.4 -330.2)
		(size 0.5588)
		(drill 0.3048)
		(layers "F.Cu" "B.Cu")
		(net "GND")
	)
	(via
		(at 410.137864 -378.476002)
		(size 0.7112)
		(drill 0.4064)
		(layers "F.Cu" "B.Cu")
		(net "GND")
	)
	(via
		(at 366.0394 -33.2232)
		(size 0.5588)
		(drill 0.3048)
		(layers "F.Cu" "B.Cu")
		(net "GND")
	)
	(via
		(at 225.552 -361.696)
		(size 0.5588)
		(drill 0.3048)
		(layers "F.Cu" "B.Cu")
		(net "GND")
	)
	(via
		(at 323.556376 -1.524)
		(size 0.7112)
		(drill 0.4064)
		(layers "F.Cu" "B.Cu")
		(net "GND")
	)
	(via
		(at 439.547 -45.085)
		(size 0.5588)
		(drill 0.3048)
		(layers "F.Cu" "B.Cu")
		(net "GND")
	)
	(via
		(at 483.809802 -230.51135)
		(size 0.5588)
		(drill 0.3048)
		(layers "F.Cu" "B.Cu")
		(net "GND")
	)
	(via
		(at 350.012 -109.22)
		(size 0.5588)
		(drill 0.3048)
		(layers "F.Cu" "B.Cu")
		(net "GND")
	)
	(via
		(at 246.8118 -303.0474)
		(size 0.5588)
		(drill 0.3048)
		(layers "F.Cu" "B.Cu")
		(net "GND")
	)
	(via
		(at 482.6 -368.3)
		(size 0.5588)
		(drill 0.3048)
		(layers "F.Cu" "B.Cu")
		(net "GND")
	)
	(via
		(at 331.089 -8.89)
		(size 0.5588)
		(drill 0.3048)
		(layers "F.Cu" "B.Cu")
		(net "GND")
	)
	(via
		(at 390.532874 -122.035062)
		(size 0.5588)
		(drill 0.3048)
		(layers "F.Cu" "B.Cu")
		(net "GND")
	)
	(via
		(at 356.489 -384.429)
		(size 0.7112)
		(drill 0.4064)
		(layers "F.Cu" "B.Cu")
		(net "GND")
	)
	(via
		(at 280.791158 -101.186488)
		(size 0.7112)
		(drill 0.4064)
		(layers "F.Cu" "B.Cu")
		(net "GND")
	)
	(via
		(at 79.676752 -343.594944)
		(size 0.5588)
		(drill 0.3048)
		(layers "F.Cu" "B.Cu")
		(net "GND")
	)
	(via
		(at 101.6 -88.9)
		(size 0.5588)
		(drill 0.3048)
		(layers "F.Cu" "B.Cu")
		(net "GND")
	)
	(via
		(at 71.12 -22.86)
		(size 0.5588)
		(drill 0.3048)
		(layers "F.Cu" "B.Cu")
		(net "GND")
	)
	(via
		(at 1.524 -212.493352)
		(size 0.7112)
		(drill 0.4064)
		(layers "F.Cu" "B.Cu")
		(net "GND")
	)
	(via
		(at 352.766376 -1.524)
		(size 0.7112)
		(drill 0.4064)
		(layers "F.Cu" "B.Cu")
		(net "GND")
	)
	(via
		(at 287.556448 -350.716342)
		(size 0.5588)
		(drill 0.3048)
		(layers "F.Cu" "B.Cu")
		(net "GND")
	)
	(via
		(at 312.5724 -326.593962)
		(size 0.5588)
		(drill 0.3048)
		(layers "F.Cu" "B.Cu")
		(net "GND")
	)
	(via
		(at 331.47 -47.117)
		(size 0.5588)
		(drill 0.3048)
		(layers "F.Cu" "B.Cu")
		(net "GND")
	)
	(via
		(at 186.055 -270.975074)
		(size 0.5588)
		(drill 0.3048)
		(layers "F.Cu" "B.Cu")
		(net "GND")
	)
	(via
		(at 489.926122 -216.91219)
		(size 0.7112)
		(drill 0.4064)
		(layers "F.Cu" "B.Cu")
		(net "GND")
	)
	(via
		(at 489.926122 -224.53219)
		(size 0.7112)
		(drill 0.4064)
		(layers "F.Cu" "B.Cu")
		(net "GND")
	)
	(via
		(at 395.224 -242.316)
		(size 0.5588)
		(drill 0.3048)
		(layers "F.Cu" "B.Cu")
		(net "GND")
	)
	(via
		(at 133.096 -142.24)
		(size 0.5588)
		(drill 0.3048)
		(layers "F.Cu" "B.Cu")
		(net "GND")
	)
	(via
		(at 222.980758 -226.384358)
		(size 0.5588)
		(drill 0.3048)
		(layers "F.Cu" "B.Cu")
		(net "GND")
	)
	(via
		(at 387.611874 -138.83005)
		(size 0.5588)
		(drill 0.3048)
		(layers "F.Cu" "B.Cu")
		(net "GND")
	)
	(via
		(at 1.524 -359.813352)
		(size 0.7112)
		(drill 0.4064)
		(layers "F.Cu" "B.Cu")
		(net "GND")
	)
	(via
		(at 12.385802 -225.30435)
		(size 0.5588)
		(drill 0.3048)
		(layers "F.Cu" "B.Cu")
		(net "GND")
	)
	(via
		(at 348.859856 -384.47599)
		(size 0.7112)
		(drill 0.4064)
		(layers "F.Cu" "B.Cu")
		(net "GND")
	)
	(via
		(at 489.926122 -256.28219)
		(size 0.7112)
		(drill 0.4064)
		(layers "F.Cu" "B.Cu")
		(net "GND")
	)
	(via
		(at 186.055 -40.975026)
		(size 0.5588)
		(drill 0.3048)
		(layers "F.Cu" "B.Cu")
		(net "GND")
	)
	(via
		(at 464.526376 -1.524)
		(size 0.7112)
		(drill 0.4064)
		(layers "F.Cu" "B.Cu")
		(net "GND")
	)
	(via
		(at 328.539856 -384.47599)
		(size 0.7112)
		(drill 0.4064)
		(layers "F.Cu" "B.Cu")
		(net "GND")
	)
	(via
		(at 53.444648 -1.524)
		(size 0.7112)
		(drill 0.4064)
		(layers "F.Cu" "B.Cu")
		(net "GND")
	)
	(via
		(at 459.646782 -105.899458)
		(size 0.5588)
		(drill 0.3048)
		(layers "F.Cu" "B.Cu")
		(net "GND")
	)
	(via
		(at 1.524 -315.363352)
		(size 0.7112)
		(drill 0.4064)
		(layers "F.Cu" "B.Cu")
		(net "GND")
	)
	(via
		(at 378.166376 -1.524)
		(size 0.7112)
		(drill 0.4064)
		(layers "F.Cu" "B.Cu")
		(net "GND")
	)
	(via
		(at 342.509856 -384.47599)
		(size 0.7112)
		(drill 0.4064)
		(layers "F.Cu" "B.Cu")
		(net "GND")
	)
	(via
		(at 59.854846 -128.03505)
		(size 0.5588)
		(drill 0.3048)
		(layers "F.Cu" "B.Cu")
		(net "GND")
	)
	(via
		(at 312.523886 -15.89151)
		(size 0.7112)
		(drill 0.4064)
		(layers "F.Cu" "B.Cu")
		(net "GND")
	)
	(via
		(at 489.926122 -241.04219)
		(size 0.7112)
		(drill 0.4064)
		(layers "F.Cu" "B.Cu")
		(net "GND")
	)
	(via
		(at 235.7755 -224.8535)
		(size 0.5588)
		(drill 0.3048)
		(layers "F.Cu" "B.Cu")
		(net "GND")
	)
	(via
		(at 54.9275 -135.382)
		(size 0.5588)
		(drill 0.3048)
		(layers "F.Cu" "B.Cu")
		(net "GND")
	)
	(via
		(at 294.318436 -49.724056)
		(size 0.7112)
		(drill 0.4064)
		(layers "F.Cu" "B.Cu")
		(net "GND")
	)
	(via
		(at 197.47611 -3.542538)
		(size 0.7112)
		(drill 0.4064)
		(layers "F.Cu" "B.Cu")
		(net "GND")
	)
	(via
		(at 197.47611 -46.722538)
		(size 0.7112)
		(drill 0.4064)
		(layers "F.Cu" "B.Cu")
		(net "GND")
	)
	(via
		(at 325.654924 -246.845074)
		(size 0.5588)
		(drill 0.3048)
		(layers "F.Cu" "B.Cu")
		(net "GND")
	)
	(via
		(at 140.024104 -151.87295)
		(size 0.5588)
		(drill 0.3048)
		(layers "F.Cu" "B.Cu")
		(net "GND")
	)
	(via
		(at 383.032 -189.992)
		(size 0.5588)
		(drill 0.3048)
		(layers "F.Cu" "B.Cu")
		(net "GND")
	)
	(via
		(at 376.936 -109.728)
		(size 0.5588)
		(drill 0.3048)
		(layers "F.Cu" "B.Cu")
		(net "GND")
	)
	(via
		(at 489.926122 -124.20219)
		(size 0.7112)
		(drill 0.4064)
		(layers "F.Cu" "B.Cu")
		(net "GND")
	)
	(via
		(at 332.446376 -1.524)
		(size 0.7112)
		(drill 0.4064)
		(layers "F.Cu" "B.Cu")
		(net "GND")
	)
	(via
		(at 1.524 -8.023352)
		(size 0.7112)
		(drill 0.4064)
		(layers "F.Cu" "B.Cu")
		(net "GND")
	)
	(via
		(at 457.2 -223.901)
		(size 0.5588)
		(drill 0.3048)
		(layers "F.Cu" "B.Cu")
		(net "GND")
	)
	(via
		(at 407.416 -136.144)
		(size 0.5588)
		(drill 0.3048)
		(layers "F.Cu" "B.Cu")
		(net "GND")
	)
	(via
		(at 391.087864 -378.476002)
		(size 0.7112)
		(drill 0.4064)
		(layers "F.Cu" "B.Cu")
		(net "GND")
	)
	(via
		(at 438.301384 -113.584228)
		(size 0.5588)
		(drill 0.3048)
		(layers "F.Cu" "B.Cu")
		(net "GND")
	)
	(via
		(at 357.205026 -155.97505)
		(size 0.5588)
		(drill 0.3048)
		(layers "F.Cu" "B.Cu")
		(net "GND")
	)
	(via
		(at 420.304976 -155.97505)
		(size 0.5588)
		(drill 0.3048)
		(layers "F.Cu" "B.Cu")
		(net "GND")
	)
	(via
		(at 88.56599 -378.476002)
		(size 0.7112)
		(drill 0.4064)
		(layers "F.Cu" "B.Cu")
		(net "GND")
	)
	(via
		(at 154.923998 -384.47599)
		(size 0.7112)
		(drill 0.4064)
		(layers "F.Cu" "B.Cu")
		(net "GND")
	)
	(via
		(at 420.304976 -131.84505)
		(size 0.5588)
		(drill 0.3048)
		(layers "F.Cu" "B.Cu")
		(net "GND")
	)
	(via
		(at 389.817864 -378.476002)
		(size 0.7112)
		(drill 0.4064)
		(layers "F.Cu" "B.Cu")
		(net "GND")
	)
	(via
		(at 356.062026 -21.42998)
		(size 0.5588)
		(drill 0.3048)
		(layers "F.Cu" "B.Cu")
		(net "GND")
	)
	(via
		(at 1.524 -334.413352)
		(size 0.7112)
		(drill 0.4064)
		(layers "F.Cu" "B.Cu")
		(net "GND")
	)
	(via
		(at 281.380692 -384.47599)
		(size 0.7112)
		(drill 0.4064)
		(layers "F.Cu" "B.Cu")
		(net "GND")
	)
	(via
		(at 475.381828 -384.47599)
		(size 0.7112)
		(drill 0.4064)
		(layers "F.Cu" "B.Cu")
		(net "GND")
	)
	(via
		(at 27.161998 -26.230072)
		(size 0.5588)
		(drill 0.3048)
		(layers "F.Cu" "B.Cu")
		(net "GND")
	)
	(via
		(at 459.627986 -123.572778)
		(size 0.5588)
		(drill 0.3048)
		(layers "F.Cu" "B.Cu")
		(net "GND")
	)
	(via
		(at 419.161976 -26.230072)
		(size 0.5588)
		(drill 0.3048)
		(layers "F.Cu" "B.Cu")
		(net "GND")
	)
	(via
		(at 468.695024 -380.775972)
		(size 0.7112)
		(drill 0.4064)
		(layers "F.Cu" "B.Cu")
		(net "GND")
	)
	(via
		(at 482.6 -76.2)
		(size 0.5588)
		(drill 0.3048)
		(layers "F.Cu" "B.Cu")
		(net "GND")
	)
	(via
		(at 155.044648 -1.524)
		(size 0.7112)
		(drill 0.4064)
		(layers "F.Cu" "B.Cu")
		(net "GND")
	)
	(via
		(at 263.040876 -194.813682)
		(size 0.7112)
		(drill 0.4064)
		(layers "F.Cu" "B.Cu")
		(net "GND")
	)
	(via
		(at 184.0484 -123.7234)
		(size 0.5588)
		(drill 0.3048)
		(layers "F.Cu" "B.Cu")
		(net "GND")
	)
	(via
		(at 425.7802 -247.65)
		(size 0.5588)
		(drill 0.3048)
		(layers "F.Cu" "B.Cu")
		(net "GND")
	)
	(via
		(at 170.307 -35.687)
		(size 0.5588)
		(drill 0.3048)
		(layers "F.Cu" "B.Cu")
		(net "GND")
	)
	(via
		(at 314.96 -271.78)
		(size 0.5588)
		(drill 0.3048)
		(layers "F.Cu" "B.Cu")
		(net "GND")
	)
	(via
		(at 67.414648 -1.524)
		(size 0.7112)
		(drill 0.4064)
		(layers "F.Cu" "B.Cu")
		(net "GND")
	)
	(via
		(at 129.523998 -384.47599)
		(size 0.7112)
		(drill 0.4064)
		(layers "F.Cu" "B.Cu")
		(net "GND")
	)
	(via
		(at 240.487962 -378.476002)
		(size 0.7112)
		(drill 0.4064)
		(layers "F.Cu" "B.Cu")
		(net "GND")
	)
	(via
		(at 489.926122 -262.63219)
		(size 0.7112)
		(drill 0.4064)
		(layers "F.Cu" "B.Cu")
		(net "GND")
	)
	(via
		(at 45.464222 -114.558572)
		(size 0.5588)
		(drill 0.3048)
		(layers "F.Cu" "B.Cu")
		(net "GND")
	)
	(via
		(at 28.557982 -384.47599)
		(size 0.7112)
		(drill 0.4064)
		(layers "F.Cu" "B.Cu")
		(net "GND")
	)
	(via
		(at 150.495 -162.179)
		(size 0.5588)
		(drill 0.3048)
		(layers "F.Cu" "B.Cu")
		(net "GND")
	)
	(via
		(at 1.524 -263.293352)
		(size 0.7112)
		(drill 0.4064)
		(layers "F.Cu" "B.Cu")
		(net "GND")
	)
	(via
		(at 28.304998 -135.65505)
		(size 0.5588)
		(drill 0.3048)
		(layers "F.Cu" "B.Cu")
		(net "GND")
	)
	(via
		(at 97.45599 -378.476002)
		(size 0.7112)
		(drill 0.4064)
		(layers "F.Cu" "B.Cu")
		(net "GND")
	)
	(via
		(at 397.256 -222.504)
		(size 0.5588)
		(drill 0.3048)
		(layers "F.Cu" "B.Cu")
		(net "GND")
	)
	(via
		(at 275.064982 -358.476042)
		(size 0.7112)
		(drill 0.4064)
		(layers "F.Cu" "B.Cu")
		(net "GND")
	)
	(via
		(at 24.257 -277.241)
		(size 0.5588)
		(drill 0.3048)
		(layers "F.Cu" "B.Cu")
		(net "GND")
	)
	(via
		(at 90.261948 -141.230096)
		(size 0.5588)
		(drill 0.3048)
		(layers "F.Cu" "B.Cu")
		(net "GND")
	)
	(via
		(at 312.523886 -9.54151)
		(size 0.7112)
		(drill 0.4064)
		(layers "F.Cu" "B.Cu")
		(net "GND")
	)
	(via
		(at 66.929 -238.633)
		(size 0.5588)
		(drill 0.3048)
		(layers "F.Cu" "B.Cu")
		(net "GND")
	)
	(via
		(at 19.304 -58.928)
		(size 0.5588)
		(drill 0.3048)
		(layers "F.Cu" "B.Cu")
		(net "GND")
	)
	(via
		(at 312.523886 -29.86151)
		(size 0.7112)
		(drill 0.4064)
		(layers "F.Cu" "B.Cu")
		(net "GND")
	)
	(via
		(at 489.926122 -338.83219)
		(size 0.7112)
		(drill 0.4064)
		(layers "F.Cu" "B.Cu")
		(net "GND")
	)
	(via
		(at 197.47611 -7.352538)
		(size 0.7112)
		(drill 0.4064)
		(layers "F.Cu" "B.Cu")
		(net "GND")
	)
	(via
		(at 99.568 -124.46)
		(size 0.5588)
		(drill 0.3048)
		(layers "F.Cu" "B.Cu")
		(net "GND")
	)
	(via
		(at 186.055 -268.435074)
		(size 0.5588)
		(drill 0.3048)
		(layers "F.Cu" "B.Cu")
		(net "GND")
	)
	(via
		(at 258.164076 -196.007482)
		(size 0.7112)
		(drill 0.4064)
		(layers "F.Cu" "B.Cu")
		(net "GND")
	)
	(via
		(at 149.81047 -217.0684)
		(size 0.5588)
		(drill 0.3048)
		(layers "F.Cu" "B.Cu")
		(net "GND")
	)
	(via
		(at 420.304976 -135.65505)
		(size 0.5588)
		(drill 0.3048)
		(layers "F.Cu" "B.Cu")
		(net "GND")
	)
	(via
		(at 321.6656 -260.2738)
		(size 0.5588)
		(drill 0.3048)
		(layers "F.Cu" "B.Cu")
		(net "GND")
	)
	(via
		(at 439.42 -14.732)
		(size 0.5588)
		(drill 0.3048)
		(layers "F.Cu" "B.Cu")
		(net "GND")
	)
	(via
		(at 73.152 -271.272)
		(size 0.5588)
		(drill 0.3048)
		(layers "F.Cu" "B.Cu")
		(net "GND")
	)
	(via
		(at 127.635 -35.433)
		(size 0.5588)
		(drill 0.3048)
		(layers "F.Cu" "B.Cu")
		(net "GND")
	)
	(via
		(at 478.469198 -216.26703)
		(size 0.5588)
		(drill 0.3048)
		(layers "F.Cu" "B.Cu")
		(net "GND")
	)
	(via
		(at 364.5408 -129.921)
		(size 0.5588)
		(drill 0.3048)
		(layers "F.Cu" "B.Cu")
		(net "GND")
	)
	(via
		(at 264.260076 -194.813682)
		(size 0.7112)
		(drill 0.4064)
		(layers "F.Cu" "B.Cu")
		(net "GND")
	)
	(via
		(at 489.926122 -105.15219)
		(size 0.7112)
		(drill 0.4064)
		(layers "F.Cu" "B.Cu")
		(net "GND")
	)
	(via
		(at 46.438058 -113.732056)
		(size 0.5588)
		(drill 0.3048)
		(layers "F.Cu" "B.Cu")
		(net "GND")
	)
	(via
		(at 1.524 -166.773352)
		(size 0.7112)
		(drill 0.4064)
		(layers "F.Cu" "B.Cu")
		(net "GND")
	)
	(via
		(at 288.911284 -184.694576)
		(size 0.6604)
		(drill 0.3556)
		(layers "F.Cu" "B.Cu")
		(net "GND")
	)
	(via
		(at 223.769682 -204.32268)
		(size 0.5588)
		(drill 0.3048)
		(layers "F.Cu" "B.Cu")
		(net "GND")
	)
	(via
		(at 424.434 -162.179)
		(size 0.5588)
		(drill 0.3048)
		(layers "F.Cu" "B.Cu")
		(net "GND")
	)
	(via
		(at 122.954796 -270.975074)
		(size 0.5588)
		(drill 0.3048)
		(layers "F.Cu" "B.Cu")
		(net "GND")
	)
	(via
		(at 433.315872 -384.47599)
		(size 0.7112)
		(drill 0.4064)
		(layers "F.Cu" "B.Cu")
		(net "GND")
	)
	(via
		(at 463.3468 -5.9436)
		(size 0.5588)
		(drill 0.3048)
		(layers "F.Cu" "B.Cu")
		(net "GND")
	)
	(via
		(at 270.926052 -381.611632)
		(size 0.7112)
		(drill 0.4064)
		(layers "F.Cu" "B.Cu")
		(net "GND")
	)
	(via
		(at 55.0545 -250.444)
		(size 0.5588)
		(drill 0.3048)
		(layers "F.Cu" "B.Cu")
		(net "GND")
	)
	(via
		(at 182.372 -84.328)
		(size 0.5588)
		(drill 0.3048)
		(layers "F.Cu" "B.Cu")
		(net "GND")
	)
	(via
		(at 428.966376 -1.524)
		(size 0.7112)
		(drill 0.4064)
		(layers "F.Cu" "B.Cu")
		(net "GND")
	)
	(via
		(at 489.926122 -205.48219)
		(size 0.7112)
		(drill 0.4064)
		(layers "F.Cu" "B.Cu")
		(net "GND")
	)
	(via
		(at 489.926122 -2.28219)
		(size 0.7112)
		(drill 0.4064)
		(layers "F.Cu" "B.Cu")
		(net "GND")
	)
	(via
		(at 320.919856 -384.47599)
		(size 0.7112)
		(drill 0.4064)
		(layers "F.Cu" "B.Cu")
		(net "GND")
	)
	(via
		(at 93.64599 -378.476002)
		(size 0.7112)
		(drill 0.4064)
		(layers "F.Cu" "B.Cu")
		(net "GND")
	)
	(via
		(at 71.01586 -119.326406)
		(size 0.5588)
		(drill 0.3048)
		(layers "F.Cu" "B.Cu")
		(net "GND")
	)
	(via
		(at 91.404948 -128.03505)
		(size 0.5588)
		(drill 0.3048)
		(layers "F.Cu" "B.Cu")
		(net "GND")
	)
	(via
		(at 420.304976 -30.815026)
		(size 0.5588)
		(drill 0.3048)
		(layers "F.Cu" "B.Cu")
		(net "GND")
	)
	(via
		(at 87.296752 -337.244944)
		(size 0.5588)
		(drill 0.3048)
		(layers "F.Cu" "B.Cu")
		(net "GND")
	)
	(via
		(at 1.524 -147.723352)
		(size 0.7112)
		(drill 0.4064)
		(layers "F.Cu" "B.Cu")
		(net "GND")
	)
	(via
		(at 215.1253 -164.03828)
		(size 0.5588)
		(drill 0.3048)
		(layers "F.Cu" "B.Cu")
		(net "GND")
	)
	(via
		(at 482.6 -114.3)
		(size 0.5588)
		(drill 0.3048)
		(layers "F.Cu" "B.Cu")
		(net "GND")
	)
	(via
		(at 182.2704 -368.2238)
		(size 0.5588)
		(drill 0.3048)
		(layers "F.Cu" "B.Cu")
		(net "GND")
	)
	(via
		(at 241.3 -274.574)
		(size 0.6096)
		(drill 0.3048)
		(layers "F.Cu" "B.Cu")
		(net "GND")
	)
	(via
		(at 1.524 -316.633352)
		(size 0.7112)
		(drill 0.4064)
		(layers "F.Cu" "B.Cu")
		(net "GND")
	)
	(via
		(at 91.404948 -246.845074)
		(size 0.5588)
		(drill 0.3048)
		(layers "F.Cu" "B.Cu")
		(net "GND")
	)
	(via
		(at 456.946 -153.67)
		(size 0.5588)
		(drill 0.3048)
		(layers "F.Cu" "B.Cu")
		(net "GND")
	)
	(via
		(at 205.476094 -56.306212)
		(size 0.7112)
		(drill 0.4064)
		(layers "F.Cu" "B.Cu")
		(net "GND")
	)
	(via
		(at 122.954796 -13.035026)
		(size 0.5588)
		(drill 0.3048)
		(layers "F.Cu" "B.Cu")
		(net "GND")
	)
	(via
		(at 193.179954 -384.47599)
		(size 0.7112)
		(drill 0.4064)
		(layers "F.Cu" "B.Cu")
		(net "GND")
	)
	(via
		(at 1.524 -311.553352)
		(size 0.7112)
		(drill 0.4064)
		(layers "F.Cu" "B.Cu")
		(net "GND")
	)
	(via
		(at 304.8 -368.3)
		(size 0.5588)
		(drill 0.3048)
		(layers "F.Cu" "B.Cu")
		(net "GND")
	)
	(via
		(at 285.428436 -49.724056)
		(size 0.7112)
		(drill 0.4064)
		(layers "F.Cu" "B.Cu")
		(net "GND")
	)
	(via
		(at 482.6 -88.9)
		(size 0.5588)
		(drill 0.3048)
		(layers "F.Cu" "B.Cu")
		(net "GND")
	)
	(via
		(at 48.986694 -101.722428)
		(size 0.5588)
		(drill 0.3048)
		(layers "F.Cu" "B.Cu")
		(net "GND")
	)
	(via
		(at 448.037204 -360.426)
		(size 0.7112)
		(drill 0.4064)
		(layers "F.Cu" "B.Cu")
		(net "GND")
	)
	(via
		(at 489.926122 -117.85219)
		(size 0.7112)
		(drill 0.4064)
		(layers "F.Cu" "B.Cu")
		(net "GND")
	)
	(via
		(at 62.334648 -1.524)
		(size 0.7112)
		(drill 0.4064)
		(layers "F.Cu" "B.Cu")
		(net "GND")
	)
	(via
		(at 154.504898 -260.815074)
		(size 0.5588)
		(drill 0.3048)
		(layers "F.Cu" "B.Cu")
		(net "GND")
	)
	(segment
		(start 221.383606 -327.664064)
		(end 221.383606 -326.139556)
		(width 0.508)
		(layer "B.Cu")
		(net "GND")
	)
	(segment
		(start 218.207844 -326.13854)
		(end 218.214702 -326.131682)
		(width 0.508)
		(layer "B.Cu")
		(net "GND")
	)
	(segment
		(start 260.168136 -279.187656)
		(end 259.58038 -278.5999)
		(width 0.381)
		(layer "B.Cu")
		(net "GND")
	)
	(segment
		(start 261.001002 -283.006546)
		(end 262.179054 -283.006546)
		(width 0.508)
		(layer "B.Cu")
		(net "GND")
	)
	(segment
		(start 257.360674 -278.033734)
		(end 257.360674 -276.6822)
		(width 0.508)
		(layer "B.Cu")
		(net "GND")
	)
	(segment
		(start 213.995 -356.865936)
		(end 213.995 -358.481122)
		(width 0.508)
		(layer "B.Cu")
		(net "GND")
	)
	(segment
		(start 129.266696 -361.08767)
		(end 128.618742 -361.735624)
		(width 0.508)
		(layer "B.Cu")
		(net "GND")
	)
	(segment
		(start 221.383606 -326.139556)
		(end 221.375224 -326.131174)
		(width 0.508)
		(layer "B.Cu")
		(net "GND")
	)
	(segment
		(start 260.168136 -279.294844)
		(end 260.168136 -279.187656)
		(width 0.381)
		(layer "B.Cu")
		(net "GND")
	)
	(segment
		(start 182.6514 -371.7544)
		(end 183.461152 -371.7544)
		(width 0.508)
		(layer "B.Cu")
		(net "GND")
	)
	(segment
		(start 224.55124 -327.672192)
		(end 224.55124 -326.13219)
		(width 0.508)
		(layer "B.Cu")
		(net "GND")
	)
	(segment
		(start 224.55124 -326.13219)
		(end 224.550224 -326.131174)
		(width 0.508)
		(layer "B.Cu")
		(net "GND")
	)
	(segment
		(start 222.631 -356.865936)
		(end 222.631 -358.354122)
		(width 0.508)
		(layer "B.Cu")
		(net "GND")
	)
	(segment
		(start 183.461152 -371.7544)
		(end 183.958992 -372.25224)
		(width 0.508)
		(layer "B.Cu")
		(net "GND")
	)
	(segment
		(start 218.44 -356.865936)
		(end 218.44 -358.354122)
		(width 0.508)
		(layer "B.Cu")
		(net "GND")
	)
	(segment
		(start 128.618742 -361.735624)
		(end 128.326896 -361.735624)
		(width 0.508)
		(layer "B.Cu")
		(net "GND")
	)
	(segment
		(start 262.179054 -283.006546)
		(end 262.219694 -282.965906)
		(width 0.508)
		(layer "B.Cu")
		(net "GND")
	)
	(segment
		(start 218.207844 -327.664064)
		(end 218.207844 -326.13854)
		(width 0.508)
		(layer "B.Cu")
		(net "GND")
	)
	(segment
		(start 173.736 -376.428)
		(end 173.736 -376.301)
		(width 0.254)
		(layer "F.Cu")
		(net "AGND_CURRENT_MON")
	)
	(segment
		(start 170.688 -361.2515)
		(end 170.688 -360.426)
		(width 0.254)
		(layer "F.Cu")
		(net "AGND_CURRENT_MON")
	)
	(segment
		(start 182.372 -366.649)
		(end 182.372 -366.165384)
		(width 0.254)
		(layer "F.Cu")
		(net "AGND_CURRENT_MON")
	)
	(segment
		(start 171.831 -361.569)
		(end 171.831 -360.553)
		(width 0.254)
		(layer "F.Cu")
		(net "AGND_CURRENT_MON")
	)
	(segment
		(start 174.509938 -369.939062)
		(end 175.26 -369.189)
		(width 0.254)
		(layer "F.Cu")
		(net "AGND_CURRENT_MON")
	)
	(segment
		(start 182.0545 -365.847884)
		(end 182.0545 -365.379)
		(width 0.254)
		(layer "F.Cu")
		(net "AGND_CURRENT_MON")
	)
	(segment
		(start 177.419 -361.2515)
		(end 177.419 -360.4006)
		(width 0.254)
		(layer "F.Cu")
		(net "AGND_CURRENT_MON")
	)
	(segment
		(start 181.2925 -366.649)
		(end 182.372 -366.649)
		(width 0.254)
		(layer "F.Cu")
		(net "AGND_CURRENT_MON")
	)
	(segment
		(start 173.736 -376.301)
		(end 174.8155 -375.2215)
		(width 0.254)
		(layer "F.Cu")
		(net "AGND_CURRENT_MON")
	)
	(segment
		(start 175.006 -361.2515)
		(end 175.006 -360.426)
		(width 0.254)
		(layer "F.Cu")
		(net "AGND_CURRENT_MON")
	)
	(segment
		(start 168.148 -367.919)
		(end 167.9702 -368.0968)
		(width 0.254)
		(layer "F.Cu")
		(net "AGND_CURRENT_MON")
	)
	(segment
		(start 174.8155 -375.2215)
		(end 174.8155 -374.904)
		(width 0.254)
		(layer "F.Cu")
		(net "AGND_CURRENT_MON")
	)
	(segment
		(start 169.672 -361.2515)
		(end 169.672 -360.4006)
		(width 0.254)
		(layer "F.Cu")
		(net "AGND_CURRENT_MON")
	)
	(segment
		(start 178.689 -363.0295)
		(end 178.689 -362.204)
		(width 0.254)
		(layer "F.Cu")
		(net "AGND_CURRENT_MON")
	)
	(segment
		(start 182.0545 -365.379)
		(end 182.99557 -365.379)
		(width 0.254)
		(layer "F.Cu")
		(net "AGND_CURRENT_MON")
	)
	(segment
		(start 167.9702 -368.0968)
		(end 167.132 -368.0968)
		(width 0.254)
		(layer "F.Cu")
		(net "AGND_CURRENT_MON")
	)
	(segment
		(start 176.7205 -374.904)
		(end 177.673 -374.904)
		(width 0.254)
		(layer "F.Cu")
		(net "AGND_CURRENT_MON")
	)
	(segment
		(start 172.974 -361.2515)
		(end 172.974 -360.4514)
		(width 0.254)
		(layer "F.Cu")
		(net "AGND_CURRENT_MON")
	)
	(segment
		(start 174.509938 -371.6655)
		(end 174.509938 -369.939062)
		(width 0.254)
		(layer "F.Cu")
		(net "AGND_CURRENT_MON")
	)
	(segment
		(start 173.99 -361.2515)
		(end 173.99 -360.4006)
		(width 0.254)
		(layer "F.Cu")
		(net "AGND_CURRENT_MON")
	)
	(segment
		(start 182.372 -366.165384)
		(end 182.0545 -365.847884)
		(width 0.254)
		(layer "F.Cu")
		(net "AGND_CURRENT_MON")
	)
	(segment
		(start 176.022 -361.2515)
		(end 176.022 -360.3752)
		(width 0.254)
		(layer "F.Cu")
		(net "AGND_CURRENT_MON")
	)
	(via
		(at 182.99557 -365.379)
		(size 0.5588)
		(drill 0.3048)
		(layers "F.Cu" "B.Cu")
		(net "AGND_CURRENT_MON")
	)
	(via
		(at 169.672 -360.4006)
		(size 0.5588)
		(drill 0.3048)
		(layers "F.Cu" "B.Cu")
		(net "AGND_CURRENT_MON")
	)
	(via
		(at 178.689 -362.204)
		(size 0.5588)
		(drill 0.3048)
		(layers "F.Cu" "B.Cu")
		(net "AGND_CURRENT_MON")
	)
	(via
		(at 171.831 -360.553)
		(size 0.5588)
		(drill 0.3048)
		(layers "F.Cu" "B.Cu")
		(net "AGND_CURRENT_MON")
	)
	(via
		(at 177.419 -360.4006)
		(size 0.5588)
		(drill 0.3048)
		(layers "F.Cu" "B.Cu")
		(net "AGND_CURRENT_MON")
	)
	(via
		(at 173.99 -369.189)
		(size 0.5588)
		(drill 0.3048)
		(layers "F.Cu" "B.Cu")
		(net "AGND_CURRENT_MON")
	)
	(via
		(at 167.090344 -364.062772)
		(size 0.5588)
		(drill 0.3048)
		(layers "F.Cu" "B.Cu")
		(net "AGND_CURRENT_MON")
	)
	(via
		(at 175.26 -370.459)
		(size 0.5588)
		(drill 0.3048)
		(layers "F.Cu" "B.Cu")
		(net "AGND_CURRENT_MON")
	)
	(via
		(at 173.736 -376.428)
		(size 0.5588)
		(drill 0.3048)
		(layers "F.Cu" "B.Cu")
		(net "AGND_CURRENT_MON")
	)
	(via
		(at 170.688 -360.426)
		(size 0.5588)
		(drill 0.3048)
		(layers "F.Cu" "B.Cu")
		(net "AGND_CURRENT_MON")
	)
	(via
		(at 175.26 -367.919)
		(size 0.5588)
		(drill 0.3048)
		(layers "F.Cu" "B.Cu")
		(net "AGND_CURRENT_MON")
	)
	(via
		(at 176.53 -369.189)
		(size 0.5588)
		(drill 0.3048)
		(layers "F.Cu" "B.Cu")
		(net "AGND_CURRENT_MON")
	)
	(via
		(at 175.26 -369.189)
		(size 0.5588)
		(drill 0.3048)
		(layers "F.Cu" "B.Cu")
		(net "AGND_CURRENT_MON")
	)
	(via
		(at 167.132 -368.0968)
		(size 0.5588)
		(drill 0.3048)
		(layers "F.Cu" "B.Cu")
		(net "AGND_CURRENT_MON")
	)
	(via
		(at 176.022 -360.3752)
		(size 0.5588)
		(drill 0.3048)
		(layers "F.Cu" "B.Cu")
		(net "AGND_CURRENT_MON")
	)
	(via
		(at 173.99 -360.4006)
		(size 0.5588)
		(drill 0.3048)
		(layers "F.Cu" "B.Cu")
		(net "AGND_CURRENT_MON")
	)
	(via
		(at 175.006 -360.426)
		(size 0.5588)
		(drill 0.3048)
		(layers "F.Cu" "B.Cu")
		(net "AGND_CURRENT_MON")
	)
	(via
		(at 164.141404 -363.990382)
		(size 0.6604)
		(drill 0.3302)
		(layers "F.Cu" "B.Cu")
		(net "AGND_CURRENT_MON")
	)
	(via
		(at 172.974 -360.4514)
		(size 0.5588)
		(drill 0.3048)
		(layers "F.Cu" "B.Cu")
		(net "AGND_CURRENT_MON")
	)
	(via
		(at 177.673 -374.904)
		(size 0.5588)
		(drill 0.3048)
		(layers "F.Cu" "B.Cu")
		(net "AGND_CURRENT_MON")
	)
	(segment
		(start 413.866076 -269.705074)
		(end 422.025064 -269.705074)
		(width 0.17145)
		(layer "F.Cu")
		(net "ACT_HDD_9")
	)
	(segment
		(start 382.315974 -269.705074)
		(end 390.474962 -269.705074)
		(width 0.17145)
		(layer "F.Cu")
		(net "ACT_HDD_8")
	)
	(segment
		(start 350.766126 -269.705074)
		(end 358.925114 -269.705074)
		(width 0.17145)
		(layer "F.Cu")
		(net "ACT_HDD_7")
	)
	(segment
		(start 319.216024 -269.705074)
		(end 327.375012 -269.705074)
		(width 0.17145)
		(layer "F.Cu")
		(net "ACT_HDD_6")
	)
	(segment
		(start 187.775088 -269.705074)
		(end 192.513966 -269.705074)
		(width 0.17145)
		(layer "F.Cu")
		(net "ACT_HDD_5")
	)
	(segment
		(start 156.224986 -269.705074)
		(end 160.963864 -269.705074)
		(width 0.17145)
		(layer "F.Cu")
		(net "ACT_HDD_4")
	)
	(segment
		(start 480.9744 -37.9984)
		(end 482.681026 -39.705026)
		(width 0.17145)
		(layer "F.Cu")
		(net "ACT_HDD_35")
	)
	(segment
		(start 477.0374 -37.9984)
		(end 480.9744 -37.9984)
		(width 0.17145)
		(layer "F.Cu")
		(net "ACT_HDD_35")
	)
	(segment
		(start 482.681026 -39.705026)
		(end 485.125014 -39.705026)
		(width 0.17145)
		(layer "F.Cu")
		(net "ACT_HDD_35")
	)
	(segment
		(start 445.415924 -39.705026)
		(end 453.574912 -39.705026)
		(width 0.17145)
		(layer "F.Cu")
		(net "ACT_HDD_34")
	)
	(segment
		(start 413.866076 -39.705026)
		(end 422.025064 -39.705026)
		(width 0.17145)
		(layer "F.Cu")
		(net "ACT_HDD_33")
	)
	(segment
		(start 382.315974 -39.705026)
		(end 390.474962 -39.705026)
		(width 0.17145)
		(layer "F.Cu")
		(net "ACT_HDD_32")
	)
	(segment
		(start 350.766126 -39.705026)
		(end 358.925114 -39.705026)
		(width 0.17145)
		(layer "F.Cu")
		(net "ACT_HDD_31")
	)
	(segment
		(start 319.216024 -39.705026)
		(end 327.375012 -39.705026)
		(width 0.17145)
		(layer "F.Cu")
		(net "ACT_HDD_30")
	)
	(segment
		(start 124.674884 -269.705074)
		(end 129.413762 -269.705074)
		(width 0.17145)
		(layer "F.Cu")
		(net "ACT_HDD_3")
	)
	(segment
		(start 184.277 -38.6842)
		(end 185.297826 -39.705026)
		(width 0.17145)
		(layer "F.Cu")
		(net "ACT_HDD_29")
	)
	(segment
		(start 179.8828 -37.8206)
		(end 180.7464 -38.6842)
		(width 0.17145)
		(layer "F.Cu")
		(net "ACT_HDD_29")
	)
	(segment
		(start 185.297826 -39.705026)
		(end 187.775088 -39.705026)
		(width 0.17145)
		(layer "F.Cu")
		(net "ACT_HDD_29")
	)
	(segment
		(start 180.7464 -38.6842)
		(end 184.277 -38.6842)
		(width 0.17145)
		(layer "F.Cu")
		(net "ACT_HDD_29")
	)
	(segment
		(start 156.224986 -39.705026)
		(end 160.963864 -39.705026)
		(width 0.17145)
		(layer "F.Cu")
		(net "ACT_HDD_28")
	)
	(segment
		(start 124.674884 -39.705026)
		(end 129.413762 -39.705026)
		(width 0.17145)
		(layer "F.Cu")
		(net "ACT_HDD_27")
	)
	(segment
		(start 93.125036 -39.705026)
		(end 97.863914 -39.705026)
		(width 0.17145)
		(layer "F.Cu")
		(net "ACT_HDD_26")
	)
	(segment
		(start 61.574934 -39.705026)
		(end 66.313812 -39.705026)
		(width 0.17145)
		(layer "F.Cu")
		(net "ACT_HDD_25")
	)
	(segment
		(start 34.763964 -39.705026)
		(end 30.025086 -39.705026)
		(width 0.17145)
		(layer "F.Cu")
		(net "ACT_HDD_24")
	)
	(segment
		(start 477.0628 -153.1366)
		(end 481.1776 -153.1366)
		(width 0.17145)
		(layer "F.Cu")
		(net "ACT_HDD_23")
	)
	(segment
		(start 482.74605 -154.70505)
		(end 485.125014 -154.70505)
		(width 0.17145)
		(layer "F.Cu")
		(net "ACT_HDD_23")
	)
	(segment
		(start 481.1776 -153.1366)
		(end 482.74605 -154.70505)
		(width 0.17145)
		(layer "F.Cu")
		(net "ACT_HDD_23")
	)
	(segment
		(start 445.415924 -154.70505)
		(end 453.574912 -154.70505)
		(width 0.17145)
		(layer "F.Cu")
		(net "ACT_HDD_22")
	)
	(segment
		(start 413.866076 -154.70505)
		(end 422.025064 -154.70505)
		(width 0.17145)
		(layer "F.Cu")
		(net "ACT_HDD_21")
	)
	(segment
		(start 382.315974 -154.70505)
		(end 390.474962 -154.70505)
		(width 0.17145)
		(layer "F.Cu")
		(net "ACT_HDD_20")
	)
	(segment
		(start 93.125036 -269.705074)
		(end 97.863914 -269.705074)
		(width 0.17145)
		(layer "F.Cu")
		(net "ACT_HDD_2")
	)
	(segment
		(start 350.766126 -154.70505)
		(end 358.925114 -154.70505)
		(width 0.17145)
		(layer "F.Cu")
		(net "ACT_HDD_19")
	)
	(segment
		(start 319.216024 -154.70505)
		(end 327.375012 -154.70505)
		(width 0.17145)
		(layer "F.Cu")
		(net "ACT_HDD_18")
	)
	(segment
		(start 192.513966 -154.70505)
		(end 187.775088 -154.70505)
		(width 0.17145)
		(layer "F.Cu")
		(net "ACT_HDD_17")
	)
	(segment
		(start 156.224986 -154.70505)
		(end 160.963864 -154.70505)
		(width 0.17145)
		(layer "F.Cu")
		(net "ACT_HDD_16")
	)
	(segment
		(start 124.674884 -154.70505)
		(end 129.413762 -154.70505)
		(width 0.17145)
		(layer "F.Cu")
		(net "ACT_HDD_15")
	)
	(segment
		(start 93.125036 -154.70505)
		(end 97.863914 -154.70505)
		(width 0.17145)
		(layer "F.Cu")
		(net "ACT_HDD_14")
	)
	(segment
		(start 66.313812 -154.70505)
		(end 61.574934 -154.70505)
		(width 0.17145)
		(layer "F.Cu")
		(net "ACT_HDD_13")
	)
	(segment
		(start 30.025086 -154.70505)
		(end 34.763964 -154.70505)
		(width 0.17145)
		(layer "F.Cu")
		(net "ACT_HDD_12")
	)
	(segment
		(start 477.0882 -268.2494)
		(end 481.2284 -268.2494)
		(width 0.17145)
		(layer "F.Cu")
		(net "ACT_HDD_11")
	)
	(segment
		(start 482.684074 -269.705074)
		(end 485.125014 -269.705074)
		(width 0.17145)
		(layer "F.Cu")
		(net "ACT_HDD_11")
	)
	(segment
		(start 481.2284 -268.2494)
		(end 482.684074 -269.705074)
		(width 0.17145)
		(layer "F.Cu")
		(net "ACT_HDD_11")
	)
	(segment
		(start 445.415924 -269.705074)
		(end 453.574912 -269.705074)
		(width 0.17145)
		(layer "F.Cu")
		(net "ACT_HDD_10")
	)
	(segment
		(start 61.574934 -269.705074)
		(end 66.313812 -269.705074)
		(width 0.17145)
		(layer "F.Cu")
		(net "ACT_HDD_1")
	)
	(via
		(at 426.653452 -272.1864)
		(size 0.6604)
		(drill 0.3302)
		(layers "F.Cu" "B.Cu")
		(net "12V_PRE_9")
	)
	(via
		(at 395.10335 -272.1864)
		(size 0.6604)
		(drill 0.3302)
		(layers "F.Cu" "B.Cu")
		(net "12V_PRE_8")
	)
	(via
		(at 363.553502 -272.1864)
		(size 0.6604)
		(drill 0.3302)
		(layers "F.Cu" "B.Cu")
		(net "12V_PRE_7")
	)
	(via
		(at 332.0034 -272.1864)
		(size 0.6604)
		(drill 0.3302)
		(layers "F.Cu" "B.Cu")
		(net "12V_PRE_6")
	)
	(via
		(at 178.816 -267.462)
		(size 0.6604)
		(drill 0.3302)
		(layers "F.Cu" "B.Cu")
		(net "12V_PRE_5")
	)
	(via
		(at 147.32 -267.462)
		(size 0.6604)
		(drill 0.3302)
		(layers "F.Cu" "B.Cu")
		(net "12V_PRE_4")
	)
	(via
		(at 475.996 -37.084)
		(size 0.6604)
		(drill 0.3302)
		(layers "F.Cu" "B.Cu")
		(net "12V_PRE_35")
	)
	(via
		(at 458.216 -42.1894)
		(size 0.6604)
		(drill 0.3302)
		(layers "F.Cu" "B.Cu")
		(net "12V_PRE_34")
	)
	(via
		(at 426.6184 -42.1894)
		(size 0.6604)
		(drill 0.3302)
		(layers "F.Cu" "B.Cu")
		(net "12V_PRE_33")
	)
	(via
		(at 395.0716 -42.164)
		(size 0.6604)
		(drill 0.3302)
		(layers "F.Cu" "B.Cu")
		(net "12V_PRE_32")
	)
	(via
		(at 363.4994 -42.164)
		(size 0.6604)
		(drill 0.3302)
		(layers "F.Cu" "B.Cu")
		(net "12V_PRE_31")
	)
	(via
		(at 331.978 -42.1894)
		(size 0.6604)
		(drill 0.3302)
		(layers "F.Cu" "B.Cu")
		(net "12V_PRE_30")
	)
	(via
		(at 115.697 -267.462)
		(size 0.6604)
		(drill 0.3302)
		(layers "F.Cu" "B.Cu")
		(net "12V_PRE_3")
	)
	(via
		(at 178.1302 -37.5158)
		(size 0.6604)
		(drill 0.3302)
		(layers "F.Cu" "B.Cu")
		(net "12V_PRE_29")
	)
	(via
		(at 147.32 -37.465)
		(size 0.6604)
		(drill 0.3302)
		(layers "F.Cu" "B.Cu")
		(net "12V_PRE_28")
	)
	(via
		(at 115.697 -37.465)
		(size 0.6604)
		(drill 0.3302)
		(layers "F.Cu" "B.Cu")
		(net "12V_PRE_27")
	)
	(via
		(at 84.201 -37.465)
		(size 0.6604)
		(drill 0.3302)
		(layers "F.Cu" "B.Cu")
		(net "12V_PRE_26")
	)
	(via
		(at 52.578 -37.465)
		(size 0.6604)
		(drill 0.3302)
		(layers "F.Cu" "B.Cu")
		(net "12V_PRE_25")
	)
	(via
		(at 21.082 -37.465)
		(size 0.6604)
		(drill 0.3302)
		(layers "F.Cu" "B.Cu")
		(net "12V_PRE_24")
	)
	(via
		(at 475.996 -152.146)
		(size 0.6604)
		(drill 0.3302)
		(layers "F.Cu" "B.Cu")
		(net "12V_PRE_23")
	)
	(via
		(at 458.1398 -157.1752)
		(size 0.6604)
		(drill 0.3302)
		(layers "F.Cu" "B.Cu")
		(net "12V_PRE_22")
	)
	(via
		(at 426.589952 -157.1752)
		(size 0.6604)
		(drill 0.3302)
		(layers "F.Cu" "B.Cu")
		(net "12V_PRE_21")
	)
	(via
		(at 395.097 -157.1752)
		(size 0.6604)
		(drill 0.3302)
		(layers "F.Cu" "B.Cu")
		(net "12V_PRE_20")
	)
	(via
		(at 84.201 -267.462)
		(size 0.6604)
		(drill 0.3302)
		(layers "F.Cu" "B.Cu")
		(net "12V_PRE_2")
	)
	(via
		(at 363.5502 -157.2006)
		(size 0.6604)
		(drill 0.3302)
		(layers "F.Cu" "B.Cu")
		(net "12V_PRE_19")
	)
	(via
		(at 332.0034 -157.1752)
		(size 0.6604)
		(drill 0.3302)
		(layers "F.Cu" "B.Cu")
		(net "12V_PRE_18")
	)
	(via
		(at 178.816 -152.4)
		(size 0.6604)
		(drill 0.3302)
		(layers "F.Cu" "B.Cu")
		(net "12V_PRE_17")
	)
	(via
		(at 147.32 -152.4)
		(size 0.6604)
		(drill 0.3302)
		(layers "F.Cu" "B.Cu")
		(net "12V_PRE_16")
	)
	(via
		(at 115.697 -152.4)
		(size 0.6604)
		(drill 0.3302)
		(layers "F.Cu" "B.Cu")
		(net "12V_PRE_15")
	)
	(via
		(at 84.201 -152.4)
		(size 0.6604)
		(drill 0.3302)
		(layers "F.Cu" "B.Cu")
		(net "12V_PRE_14")
	)
	(via
		(at 52.578 -152.4)
		(size 0.6604)
		(drill 0.3302)
		(layers "F.Cu" "B.Cu")
		(net "12V_PRE_13")
	)
	(via
		(at 21.082 -152.4)
		(size 0.6604)
		(drill 0.3302)
		(layers "F.Cu" "B.Cu")
		(net "12V_PRE_12")
	)
	(via
		(at 475.996 -267.208)
		(size 0.6604)
		(drill 0.3302)
		(layers "F.Cu" "B.Cu")
		(net "12V_PRE_11")
	)
	(via
		(at 458.2033 -272.1864)
		(size 0.6604)
		(drill 0.3302)
		(layers "F.Cu" "B.Cu")
		(net "12V_PRE_10")
	)
	(via
		(at 52.832 -267.462)
		(size 0.6604)
		(drill 0.3302)
		(layers "F.Cu" "B.Cu")
		(net "12V_PRE_1")
	)
	(segment
		(start 183.8325 -369.189)
		(end 183.8325 -368.046)
		(width 0.254)
		(layer "F.Cu")
		(net "12V_HS_ENABLE")
	)
	(segment
		(start 182.626 -369.189)
		(end 181.4195 -369.189)
		(width 0.254)
		(layer "F.Cu")
		(net "12V_HS_ENABLE")
	)
	(segment
		(start 182.626 -369.189)
		(end 183.8325 -369.189)
		(width 0.254)
		(layer "F.Cu")
		(net "12V_HS_ENABLE")
	)
	(via
		(at 182.626 -369.189)
		(size 0.6604)
		(drill 0.3302)
		(layers "F.Cu" "B.Cu")
		(net "12V_HS_ENABLE")
	)
	(zone
		(layer "F.Cu")
		(hatch none 0.5)
		(connect_pads
			(clearance 0)
		)
		(min_thickness 0.25)
		(keepout
			(tracks allowed)
			(vias allowed)
			(pads allowed)
			(copperpour allowed)
			(footprints allowed)
		)
		(placement
			(enabled no)
			(sheetname "")
		)
		(fill
			(thermal_gap 0.5)
			(thermal_bridge_width 0.5)
			(island_removal_mode 0)
		)
		(polygon
			(pts
				(xy 94.6658 -134.62) (xy 95.6818 -134.62) (xy 95.8596 -134.4422) (xy 95.8596 -133.1722) (xy 95.5294 -132.842)
				(xy 94.6404 -132.842) (xy 94.4118 -133.0706) (xy 94.4118 -134.366)
			)
		)
	)
	(zone
		(net "GND")
		(layer "F.Cu")
		(hatch none 0.5)
		(connect_pads
			(clearance 0.5)
		)
		(min_thickness 0.25)
		(fill yes
			(thermal_gap 0.5)
			(thermal_bridge_width 0.5)
			(island_removal_mode 0)
		)
		(polygon
			(pts
				(xy 136.161272 -155.2702) (xy 134.96036 -156.471112)
				(arc
					(start 134.96036 -160.65881)
					(mid 134.058285 -164.689233)
					(end 130.103118 -165.87851)
				)
				(xy 129.545588 -165.87851) (xy 128.942846 -166.481252) (xy 128.942846 -167.352726)
				(arc
					(start 129.488438 -167.898318)
					(mid 135.508117 -170.095762)
					(end 139.918186 -174.745142)
				)
				(xy 141.126464 -174.745142) (xy 142.447772 -173.424088)
				(arc
					(start 149.93366 -173.424088)
					(mid 150.390995 -172.694048)
					(end 150.904956 -172.002704)
				)
				(xy 150.904956 -171.441618) (xy 150.354538 -170.8912) (xy 149.293834 -170.8912) (xy 149.293834 -167.03294)
				(xy 147.616418 -165.355524) (xy 146.251676 -165.355524) (xy 146.251676 -162.816286) (xy 146.136614 -162.701224)
				(xy 145.603976 -162.701224) (xy 145.603976 -162.168586)
				(arc
					(start 139.341098 -155.905708)
					(mid 138.509957 -155.672554)
					(end 137.746232 -155.2702)
				)
			)
		)
	)
	(zone
		(net "P12V_B")
		(layer "F.Cu")
		(hatch none 0.5)
		(connect_pads
			(clearance 0.5)
		)
		(min_thickness 0.25)
		(fill yes
			(thermal_gap 0.5)
			(thermal_bridge_width 0.5)
			(island_removal_mode 0)
		)
		(polygon
			(pts
				(xy 77.343 -25.146) (xy 76.327 -26.162) (xy 74.512932 -26.162) (xy 74.257154 -26.417778) (xy 74.257154 -28.808934)
				(xy 74.78522 -29.337) (xy 78.867 -29.337) (xy 79.121 -29.083) (xy 79.121 -27.097482) (xy 78.185518 -26.162)
				(xy 78.105 -26.162) (xy 77.82687 -25.88387) (xy 77.82687 -25.24887) (xy 77.724 -25.146)
			)
		)
		(polygon
			(pts
				(xy 77.3176 -25.7302) (xy 77.1144 -25.7302) (xy 77.1144 -25.9334) (xy 77.3176 -25.9334)
			)
		)
	)
	(zone
		(net "GND")
		(layer "F.Cu")
		(hatch none 0.5)
		(connect_pads
			(clearance 0.5)
		)
		(min_thickness 0.25)
		(fill yes
			(thermal_gap 0.5)
			(thermal_bridge_width 0.5)
			(island_removal_mode 0)
		)
		(polygon
			(pts
				(xy 39.89705 -37.7698) (xy 39.58336 -38.08349) (xy 39.58336 -47.816262) (xy 42.813224 -51.046126)
				(xy 50.893726 -51.046126) (xy 51.4858 -50.454052) (xy 51.4858 -48.264318) (xy 50.988976 -47.767494)
				(xy 50.988976 -47.360586) (xy 43.825414 -40.197024) (xy 40.752776 -40.197024)
				(arc
					(start 40.752776 -38.081204)
					(mid 40.647248 -37.927825)
					(end 40.548814 -37.7698)
				)
			)
		)
	)
	(zone
		(net "P12V_B")
		(layer "F.Cu")
		(hatch none 0.5)
		(connect_pads
			(clearance 0.5)
		)
		(min_thickness 0.25)
		(fill yes
			(thermal_gap 0.5)
			(thermal_bridge_width 0.5)
			(island_removal_mode 0)
		)
		(polygon
			(pts
				(xy 461.518 -27.432) (xy 460.9846 -27.9654) (xy 460.9846 -28.9052) (xy 460.248 -29.6418) (xy 460.248 -31.369)
				(xy 460.502 -31.623) (xy 463.677 -31.623) (xy 463.931 -31.369) (xy 463.931 -29.337) (xy 464.058 -29.21)
				(xy 464.439 -29.21) (xy 464.566 -29.083) (xy 464.566 -27.559) (xy 464.439 -27.432)
			)
		)
		(polygon
			(pts
				(xy 463.9056 -28.4226) (xy 463.7024 -28.4226) (xy 463.7024 -28.6258) (xy 463.9056 -28.6258)
			)
		)
		(polygon
			(pts
				(xy 463.9564 -27.9908) (xy 463.7532 -27.9908) (xy 463.7532 -28.194) (xy 463.9564 -28.194)
			)
		)
	)
	(zone
		(net "5V_PRE_26")
		(layer "F.Cu")
		(hatch none 0.5)
		(connect_pads
			(clearance 0.5)
		)
		(min_thickness 0.25)
		(fill yes
			(thermal_gap 0.5)
			(thermal_bridge_width 0.5)
			(island_removal_mode 0)
		)
		(polygon
			(pts
				(xy 86.058502 -30.9626) (xy 85.906102 -31.115) (xy 85.906102 -32.512) (xy 86.490302 -33.0962) (xy 87.760302 -33.0962)
				(xy 89.843102 -35.179) (xy 94.288102 -35.179) (xy 94.415102 -35.052) (xy 94.415102 -34.29) (xy 94.288102 -34.163)
				(xy 91.265502 -34.163) (xy 88.065102 -30.9626)
			)
		)
	)
	(zone
		(layer "F.Cu")
		(hatch none 0.5)
		(connect_pads
			(clearance 0)
		)
		(min_thickness 0.25)
		(keepout
			(tracks allowed)
			(vias allowed)
			(pads allowed)
			(copperpour allowed)
			(footprints allowed)
		)
		(placement
			(enabled no)
			(sheetname "")
		)
		(fill
			(thermal_gap 0.5)
			(thermal_bridge_width 0.5)
			(island_removal_mode 0)
		)
		(polygon
			(pts
				(xy 392.942318 -134.097522) (xy 394.533628 -134.097522) (xy 394.533628 -136.00557) (xy 392.942318 -136.00557)
			)
		)
	)
	(zone
		(layer "F.Cu")
		(hatch none 0.5)
		(connect_pads
			(clearance 0)
		)
		(min_thickness 0.25)
		(keepout
			(tracks not_allowed)
			(vias allowed)
			(pads allowed)
			(copperpour not_allowed)
			(footprints allowed)
		)
		(placement
			(enabled no)
			(sheetname "")
		)
		(fill
			(thermal_gap 0.5)
			(thermal_bridge_width 0.5)
			(island_removal_mode 0)
		)
		(polygon
			(pts
				(arc
					(start 190.744094 -248.115328)
					(mid 190.259081 -247.629934)
					(end 189.773814 -248.115074)
				)
				(xy 189.773814 -248.527824)
				(arc
					(start 190.131954 -248.527824)
					(mid 190.167875 -248.512945)
					(end 190.182754 -248.477024)
				)
				(arc
					(start 190.182754 -248.370598)
					(mid 190.258954 -247.84843)
					(end 190.335154 -248.370598)
				)
				(xy 190.335154 -248.50852)
				(arc
					(start 190.332106 -248.511568)
					(mid 190.275575 -248.620645)
					(end 190.166498 -248.677176)
				)
				(xy 190.16345 -248.680224) (xy 189.773814 -248.680224) (xy 189.773814 -248.819924) (xy 190.16345 -248.819924)
				(arc
					(start 190.166498 -248.822972)
					(mid 190.275575 -248.879503)
					(end 190.332106 -248.98858)
				)
				(xy 190.335154 -248.991628)
				(arc
					(start 190.335154 -249.12955)
					(mid 190.258954 -249.651718)
					(end 190.182754 -249.12955)
				)
				(arc
					(start 190.182754 -249.023124)
					(mid 190.167875 -248.987203)
					(end 190.131954 -248.972324)
				)
				(xy 189.773814 -248.972324)
				(arc
					(start 189.773814 -249.385074)
					(mid 190.258954 -249.870214)
					(end 190.744094 -249.385074)
				)
			)
		)
	)
	(zone
		(net "P12V_HDD28")
		(layer "F.Cu")
		(hatch none 0.5)
		(connect_pads
			(clearance 0.5)
		)
		(min_thickness 0.25)
		(fill yes
			(thermal_gap 0.5)
			(thermal_bridge_width 0.5)
			(island_removal_mode 0)
		)
		(polygon
			(pts
				(xy 138.557 -32.258) (xy 138.303 -32.512) (xy 138.303 -34.163) (xy 138.557 -34.417) (xy 140.716 -34.417)
				(xy 141.224 -34.925) (xy 141.224 -37.465) (xy 148.971 -45.212) (xy 157.48 -45.212) (xy 157.607 -45.085)
				(xy 157.607 -43.307) (xy 157.48 -43.18) (xy 151.511 -43.18) (xy 150.876 -42.545) (xy 149.225 -42.545)
				(xy 144.907 -38.227) (xy 144.907 -34.671) (xy 143.764 -33.528) (xy 143.764 -32.512) (xy 143.51 -32.258)
			)
		)
		(polygon
			(pts
				(xy 151.0284 -44.2214) (xy 150.8252 -44.2214) (xy 150.8252 -44.4246) (xy 151.0284 -44.4246)
			)
		)
		(polygon
			(pts
				(xy 150.1648 -44.2214) (xy 149.9616 -44.2214) (xy 149.9616 -44.4246) (xy 150.1648 -44.4246)
			)
		)
	)
	(zone
		(layer "F.Cu")
		(hatch none 0.5)
		(connect_pads
			(clearance 0)
		)
		(min_thickness 0.25)
		(keepout
			(tracks allowed)
			(vias allowed)
			(pads allowed)
			(copperpour allowed)
			(footprints allowed)
		)
		(placement
			(enabled no)
			(sheetname "")
		)
		(fill
			(thermal_gap 0.5)
			(thermal_bridge_width 0.5)
			(island_removal_mode 0)
		)
		(polygon
			(pts
				(xy 276.131274 -332.231492) (xy 276.131274 -330.605892) (xy 278.645874 -330.605892) (xy 278.645874 -332.231492)
			)
		)
	)
	(zone
		(layer "F.Cu")
		(hatch none 0.5)
		(connect_pads
			(clearance 0)
		)
		(min_thickness 0.25)
		(keepout
			(tracks allowed)
			(vias allowed)
			(pads allowed)
			(copperpour allowed)
			(footprints allowed)
		)
		(placement
			(enabled no)
			(sheetname "")
		)
		(fill
			(thermal_gap 0.5)
			(thermal_bridge_width 0.5)
			(island_removal_mode 0)
		)
		(polygon
			(pts
				(xy 28.111196 -375.26976) (xy 28.111196 -373.624856) (xy 29.330396 -373.624856) (xy 29.330396 -375.26976)
			)
		)
	)
	(zone
		(layer "F.Cu")
		(hatch none 0.5)
		(connect_pads
			(clearance 0)
		)
		(min_thickness 0.25)
		(keepout
			(tracks allowed)
			(vias allowed)
			(pads allowed)
			(copperpour allowed)
			(footprints allowed)
		)
		(placement
			(enabled no)
			(sheetname "")
		)
		(fill
			(thermal_gap 0.5)
			(thermal_bridge_width 0.5)
			(island_removal_mode 0)
		)
		(polygon
			(pts
				(xy 126.3142 -134.5438) (xy 127.3556 -134.5438) (xy 127.508 -134.3914) (xy 127.508 -133.1722) (xy 127.1778 -132.842)
				(xy 126.111 -132.842) (xy 125.9332 -133.0198) (xy 125.9332 -134.1628)
			)
		)
	)
	(zone
		(net "P5V_B_4")
		(layer "F.Cu")
		(hatch none 0.5)
		(connect_pads
			(clearance 0.5)
		)
		(min_thickness 0.25)
		(fill yes
			(thermal_gap 0.5)
			(thermal_bridge_width 0.5)
			(island_removal_mode 0)
		)
		(polygon
			(pts
				(xy 473.456 -21.717) (xy 473.202 -21.971) (xy 473.202 -24.257) (xy 473.456 -24.511) (xy 478.155 -24.511)
				(xy 478.409 -24.257) (xy 478.409 -21.971) (xy 478.155 -21.717)
			)
		)
	)
	(zone
		(net "GND")
		(layer "F.Cu")
		(hatch none 0.5)
		(connect_pads
			(clearance 0.5)
		)
		(min_thickness 0.25)
		(fill yes
			(thermal_gap 0.5)
			(thermal_bridge_width 0.5)
			(island_removal_mode 0)
		)
		(polygon
			(pts
				(xy 240.421922 -352.9076) (xy 239.704626 -353.624896) (xy 235.680504 -353.624896) (xy 235.6104 -353.695)
				(xy 235.6104 -355.7778) (xy 235.7628 -355.9302) (xy 240.2332 -355.9302) (xy 240.4364 -355.727) (xy 240.4364 -355.2952)
				(xy 240.919 -354.8126) (xy 241.681 -354.8126) (xy 242.2144 -354.2792) (xy 242.2144 -353.1108) (xy 242.0112 -352.9076)
			)
		)
		(polygon
			(pts
				(xy 241.792506 -353.416362) (xy 241.589306 -353.416362) (xy 241.589306 -353.619562) (xy 241.792506 -353.619562)
			)
		)
		(polygon
			(pts
				(xy 241.182906 -353.416362) (xy 240.979706 -353.416362) (xy 240.979706 -353.619562) (xy 241.182906 -353.619562)
			)
		)
	)
	(zone
		(layer "F.Cu")
		(hatch none 0.5)
		(connect_pads
			(clearance 0)
		)
		(min_thickness 0.25)
		(keepout
			(tracks allowed)
			(vias allowed)
			(pads allowed)
			(copperpour allowed)
			(footprints allowed)
		)
		(placement
			(enabled no)
			(sheetname "")
		)
		(fill
			(thermal_gap 0.5)
			(thermal_bridge_width 0.5)
			(island_removal_mode 0)
		)
		(polygon
			(pts
				(xy 157.7848 -134.5946) (xy 158.9024 -134.5946) (xy 159.004 -134.493) (xy 159.004 -133.0452) (xy 158.6992 -132.7404)
				(xy 157.8102 -132.7404) (xy 157.48 -133.0706) (xy 157.48 -134.2898)
			)
		)
	)
	(zone
		(net "12V_PRE_33")
		(layer "F.Cu")
		(hatch none 0.5)
		(connect_pads
			(clearance 0.5)
		)
		(min_thickness 0.25)
		(fill yes
			(thermal_gap 0.5)
			(thermal_bridge_width 0.5)
			(island_removal_mode 0)
		)
		(polygon
			(pts
				(xy 425.243752 -39.685976) (xy 423.211752 -41.717976) (xy 420.646352 -41.717976) (xy 420.392352 -41.971976)
				(xy 420.392352 -42.505376) (xy 420.620952 -42.733976) (xy 426.615352 -42.733976) (xy 427.631352 -41.717976)
				(xy 427.631352 -39.812976) (xy 427.504352 -39.685976)
			)
		)
	)
	(zone
		(net "GND")
		(layer "F.Cu")
		(hatch none 0.5)
		(connect_pads
			(clearance 0.5)
		)
		(min_thickness 0.25)
		(fill yes
			(thermal_gap 0.5)
			(thermal_bridge_width 0.5)
			(island_removal_mode 0)
		)
		(polygon
			(pts
				(xy 98.384614 -238.1123) (xy 98.11766 -238.379254) (xy 98.11766 -239.180116)
				(arc
					(start 98.405442 -239.467898)
					(mid 100.600751 -240.915204)
					(end 101.451156 -243.403374)
				)
				(arc
					(start 101.451156 -246.578374)
					(mid 100.979633 -248.478869)
					(end 99.674426 -249.93854)
				)
				(arc
					(start 99.674426 -250.40209)
					(mid 99.637459 -250.948584)
					(end 99.52736 -251.485146)
				)
				(arc
					(start 99.52736 -251.485146)
					(mid 99.348679 -253.617615)
					(end 98.11766 -255.368044)
				)
				(xy 98.11766 -256.69494)
				(arc
					(start 98.581718 -257.158998)
					(mid 100.060902 -257.326226)
					(end 101.382322 -258.011676)
				)
				(xy 102.540054 -258.011676) (xy 102.931976 -257.619754) (xy 102.931976 -253.680976) (xy 104.277414 -253.680976)
				(xy 104.900476 -253.057914)
				(arc
					(start 104.900476 -250.410726)
					(mid 104.310521 -249.092295)
					(end 104.215692 -247.651016)
				)
				(arc
					(start 104.215692 -247.192546)
					(mid 104.403937 -245.96992)
					(end 104.951276 -244.860572)
				)
				(xy 104.951276 -242.543076) (xy 105.383076 -242.111276) (xy 112.545876 -242.111276) (xy 112.545876 -242.085876)
				(arc
					(start 112.869218 -242.085876)
					(mid 114.2238 -241.858054)
					(end 115.578382 -242.085876)
				)
				(xy 117.072156 -242.085876) (xy 117.743732 -241.4143) (xy 117.743732 -238.847884) (xy 117.008148 -238.1123)
			)
		)
	)
	(zone
		(layer "F.Cu")
		(hatch none 0.5)
		(connect_pads
			(clearance 0)
		)
		(min_thickness 0.25)
		(keepout
			(tracks allowed)
			(vias allowed)
			(pads allowed)
			(copperpour allowed)
			(footprints allowed)
		)
		(placement
			(enabled no)
			(sheetname "")
		)
		(fill
			(thermal_gap 0.5)
			(thermal_bridge_width 0.5)
			(island_removal_mode 0)
		)
		(polygon
			(pts
				(xy 174.601632 -375.616724) (xy 174.601632 -377.089924) (xy 172.179996 -377.089924) (xy 172.179996 -375.616724)
			)
		)
	)
	(zone
		(layer "F.Cu")
		(hatch none 0.5)
		(connect_pads
			(clearance 0)
		)
		(min_thickness 0.25)
		(keepout
			(tracks allowed)
			(vias allowed)
			(pads allowed)
			(copperpour allowed)
			(footprints not_allowed)
		)
		(placement
			(enabled no)
			(sheetname "")
		)
		(fill
			(thermal_gap 0.5)
			(thermal_bridge_width 0.5)
			(island_removal_mode 0)
		)
		(polygon
			(pts
				(arc
					(start 386.675122 -63.799974)
					(mid 393.675108 -56.799988)
					(end 400.675094 -63.799974)
				)
				(arc
					(start 400.675094 -69.799962)
					(mid 393.675108 -76.799948)
					(end 386.675122 -69.799962)
				)
			)
		)
	)
	(zone
		(net "P5V_B_2")
		(layer "F.Cu")
		(hatch none 0.5)
		(connect_pads
			(clearance 0.5)
		)
		(min_thickness 0.25)
		(fill yes
			(thermal_gap 0.5)
			(thermal_bridge_width 0.5)
			(island_removal_mode 0)
		)
		(polygon
			(pts
				(xy 144.653 -21.844) (xy 144.399 -22.098) (xy 144.399 -24.384) (xy 144.653 -24.638) (xy 149.352 -24.638)
				(xy 149.606 -24.384) (xy 149.606 -22.098) (xy 149.352 -21.844)
			)
		)
	)
	(zone
		(layer "F.Cu")
		(hatch none 0.5)
		(connect_pads
			(clearance 0)
		)
		(min_thickness 0.25)
		(keepout
			(tracks not_allowed)
			(vias allowed)
			(pads allowed)
			(copperpour not_allowed)
			(footprints allowed)
		)
		(placement
			(enabled no)
			(sheetname "")
		)
		(fill
			(thermal_gap 0.5)
			(thermal_bridge_width 0.5)
			(island_removal_mode 0)
		)
		(polygon
			(pts
				(arc
					(start 129.42062 -244.419374)
					(mid 128.93548 -243.934234)
					(end 128.45034 -244.419374)
				)
				(xy 128.45034 -244.768624)
				(arc
					(start 128.776476 -244.768624)
					(mid 128.835027 -244.744371)
					(end 128.85928 -244.68582)
				)
				(arc
					(start 128.85928 -244.674898)
					(mid 128.93548 -244.15273)
					(end 129.01168 -244.674898)
				)
				(xy 129.01168 -244.717316)
				(arc
					(start 129.00914 -244.719856)
					(mid 128.942745 -244.852089)
					(end 128.810512 -244.918484)
				)
				(xy 128.807972 -244.921024) (xy 128.45034 -244.921024) (xy 128.45034 -245.060724) (xy 128.807972 -245.060724)
				(arc
					(start 128.810512 -245.063264)
					(mid 128.942745 -245.129659)
					(end 129.00914 -245.261892)
				)
				(xy 129.01168 -245.264432)
				(arc
					(start 129.01168 -245.30685)
					(mid 128.93548 -245.829018)
					(end 128.85928 -245.30685)
				)
				(arc
					(start 128.85928 -245.295928)
					(mid 128.835027 -245.237377)
					(end 128.776476 -245.213124)
				)
				(xy 128.45034 -245.213124)
				(arc
					(start 128.45034 -245.56212)
					(mid 128.935353 -246.047514)
					(end 129.42062 -245.562374)
				)
			)
		)
	)
	(zone
		(layer "F.Cu")
		(hatch none 0.5)
		(connect_pads
			(clearance 0)
		)
		(min_thickness 0.25)
		(keepout
			(tracks not_allowed)
			(vias allowed)
			(pads allowed)
			(copperpour not_allowed)
			(footprints allowed)
		)
		(placement
			(enabled no)
			(sheetname "")
		)
		(fill
			(thermal_gap 0.5)
			(thermal_bridge_width 0.5)
			(island_removal_mode 0)
		)
		(polygon
			(pts
				(arc
					(start 293.200074 -244.00002)
					(mid 300.20006 -237.000034)
					(end 307.200046 -244.00002)
				)
				(arc
					(start 307.200046 -250.000008)
					(mid 300.20006 -256.999994)
					(end 293.200074 -250.000008)
				)
			)
		)
	)
	(zone
		(net "12V_PRE_24")
		(layer "F.Cu")
		(hatch none 0.5)
		(connect_pads
			(clearance 0.5)
		)
		(min_thickness 0.25)
		(fill yes
			(thermal_gap 0.5)
			(thermal_bridge_width 0.5)
			(island_removal_mode 0)
		)
		(polygon
			(pts
				(xy 19.685 -34.798) (xy 19.558 -34.925) (xy 19.558 -36.449) (xy 20.955 -37.846) (xy 22.352 -37.846)
				(xy 27.305 -42.799) (xy 31.242 -42.799) (xy 31.369 -42.672) (xy 31.369 -41.91) (xy 31.242 -41.783)
				(xy 27.94 -41.783) (xy 20.955 -34.798)
			)
		)
	)
	(zone
		(layer "F.Cu")
		(hatch none 0.5)
		(connect_pads
			(clearance 0)
		)
		(min_thickness 0.25)
		(keepout
			(tracks not_allowed)
			(vias allowed)
			(pads allowed)
			(copperpour not_allowed)
			(footprints allowed)
		)
		(placement
			(enabled no)
			(sheetname "")
		)
		(fill
			(thermal_gap 0.5)
			(thermal_bridge_width 0.5)
			(island_removal_mode 0)
		)
		(polygon
			(pts
				(arc
					(start 450.27469 -248.115328)
					(mid 449.789677 -247.629934)
					(end 449.30441 -248.115074)
				)
				(arc
					(start 449.30441 -249.385074)
					(mid 449.78955 -249.870214)
					(end 450.27469 -249.385074)
				)
				(xy 450.27469 -248.972324)
				(arc
					(start 449.91655 -248.972324)
					(mid 449.880629 -248.987203)
					(end 449.86575 -249.023124)
				)
				(arc
					(start 449.86575 -249.12955)
					(mid 449.78955 -249.651718)
					(end 449.71335 -249.12955)
				)
				(xy 449.71335 -248.991628)
				(arc
					(start 449.716398 -248.98858)
					(mid 449.772929 -248.879503)
					(end 449.882006 -248.822972)
				)
				(xy 449.885054 -248.819924) (xy 450.27469 -248.819924) (xy 450.27469 -248.680224) (xy 449.885054 -248.680224)
				(arc
					(start 449.882006 -248.677176)
					(mid 449.772929 -248.620645)
					(end 449.716398 -248.511568)
				)
				(xy 449.71335 -248.50852)
				(arc
					(start 449.71335 -248.370598)
					(mid 449.78955 -247.84843)
					(end 449.86575 -248.370598)
				)
				(arc
					(start 449.86575 -248.477024)
					(mid 449.880629 -248.512945)
					(end 449.91655 -248.527824)
				)
				(xy 450.27469 -248.527824)
			)
		)
	)
	(zone
		(net "12V_PRE_32")
		(layer "F.Cu")
		(hatch none 0.5)
		(connect_pads
			(clearance 0.5)
		)
		(min_thickness 0.25)
		(fill yes
			(thermal_gap 0.5)
			(thermal_bridge_width 0.5)
			(island_removal_mode 0)
		)
		(polygon
			(pts
				(xy 393.922504 -39.685976) (xy 391.890504 -41.717976) (xy 389.09625 -41.717976) (xy 388.84225 -41.971976)
				(xy 388.84225 -42.505376) (xy 389.07085 -42.733976) (xy 395.06525 -42.733976) (xy 396.08125 -41.717976)
				(xy 396.08125 -39.812976) (xy 395.95425 -39.685976)
			)
		)
	)
	(zone
		(net "P12V_HDD31")
		(layer "F.Cu")
		(hatch none 0.5)
		(connect_pads
			(clearance 0.5)
		)
		(min_thickness 0.25)
		(fill yes
			(thermal_gap 0.5)
			(thermal_bridge_width 0.5)
			(island_removal_mode 0)
		)
		(polygon
			(pts
				(xy 366.141 -34.544) (xy 365.887 -34.798) (xy 365.887 -38.862) (xy 365.3663 -39.3827) (xy 365.3663 -41.5163)
				(xy 363.8296 -43.053) (xy 357.759 -43.053) (xy 357.505 -43.307) (xy 357.505 -44.958) (xy 357.759 -45.212)
				(xy 361.696 -45.212) (xy 362.204 -44.704) (xy 369.951 -44.704) (xy 370.84 -43.815) (xy 370.84 -34.798)
				(xy 370.586 -34.544)
			)
		)
		(polygon
			(pts
				(xy 361.8484 -44.0944) (xy 361.6452 -44.0944) (xy 361.6452 -44.2976) (xy 361.8484 -44.2976)
			)
		)
		(polygon
			(pts
				(xy 360.9848 -44.0944) (xy 360.7816 -44.0944) (xy 360.7816 -44.2976) (xy 360.9848 -44.2976)
			)
		)
	)
	(zone
		(net "P5V_B_1")
		(layer "F.Cu")
		(hatch none 0.5)
		(connect_pads
			(clearance 0.5)
		)
		(min_thickness 0.25)
		(fill yes
			(thermal_gap 0.5)
			(thermal_bridge_width 0.5)
			(island_removal_mode 0)
		)
		(polygon
			(pts
				(xy 81.534 -251.841) (xy 81.28 -252.095) (xy 81.28 -254.381) (xy 81.534 -254.635) (xy 86.233 -254.635)
				(xy 86.487 -254.381) (xy 86.487 -252.095) (xy 86.233 -251.841)
			)
		)
	)
	(zone
		(layer "F.Cu")
		(hatch none 0.5)
		(connect_pads
			(clearance 0)
		)
		(min_thickness 0.25)
		(keepout
			(tracks allowed)
			(vias allowed)
			(pads allowed)
			(copperpour allowed)
			(footprints allowed)
		)
		(placement
			(enabled no)
			(sheetname "")
		)
		(fill
			(thermal_gap 0.5)
			(thermal_bridge_width 0.5)
			(island_removal_mode 0)
		)
		(polygon
			(pts
				(xy 276.09673 -330.28001) (xy 276.09673 -328.65441) (xy 278.61133 -328.65441) (xy 278.61133 -330.28001)
			)
		)
	)
	(zone
		(layer "F.Cu")
		(hatch none 0.5)
		(connect_pads
			(clearance 0)
		)
		(min_thickness 0.25)
		(keepout
			(tracks allowed)
			(vias allowed)
			(pads allowed)
			(copperpour allowed)
			(footprints allowed)
		)
		(placement
			(enabled no)
			(sheetname "")
		)
		(fill
			(thermal_gap 0.5)
			(thermal_bridge_width 0.5)
			(island_removal_mode 0)
		)
		(polygon
			(pts
				(xy 456.101704 -369.062) (xy 457.092304 -369.062) (xy 458.006704 -369.062) (xy 458.006704 -370.2812)
				(xy 456.101704 -370.2812) (xy 456.101704 -369.8494)
			)
		)
	)
	(zone
		(net "P5V_HDD8")
		(layer "F.Cu")
		(hatch none 0.5)
		(connect_pads
			(clearance 0.5)
		)
		(min_thickness 0.25)
		(fill yes
			(thermal_gap 0.5)
			(thermal_bridge_width 0.5)
			(island_removal_mode 0)
		)
		(polygon
			(pts
				(xy 394.716 -252.73) (xy 394.462 -252.984) (xy 394.462 -263.779) (xy 392.811 -265.43) (xy 389.382 -265.43)
				(xy 389.128 -265.684) (xy 389.128 -267.335) (xy 389.382 -267.589) (xy 393.954 -267.589) (xy 394.589 -266.954)
				(xy 396.367 -266.954) (xy 396.875 -266.446) (xy 396.875 -252.984) (xy 396.621 -252.73)
			)
		)
		(polygon
			(pts
				(xy 393.4714 -266.5984) (xy 393.2682 -266.5984) (xy 393.2682 -266.8016) (xy 393.4714 -266.8016)
			)
		)
		(polygon
			(pts
				(xy 392.6078 -266.5984) (xy 392.4046 -266.5984) (xy 392.4046 -266.8016) (xy 392.6078 -266.8016)
			)
		)
	)
	(zone
		(layer "F.Cu")
		(hatch none 0.5)
		(connect_pads
			(clearance 0)
		)
		(min_thickness 0.25)
		(keepout
			(tracks allowed)
			(vias allowed)
			(pads allowed)
			(copperpour allowed)
			(footprints allowed)
		)
		(placement
			(enabled no)
			(sheetname "")
		)
		(fill
			(thermal_gap 0.5)
			(thermal_bridge_width 0.5)
			(island_removal_mode 0)
		)
		(polygon
			(pts
				(xy 319.741296 -369.2144) (xy 320.731896 -369.2144) (xy 321.646296 -369.2144) (xy 321.646296 -370.4336)
				(xy 319.741296 -370.4336) (xy 319.741296 -370.0018)
			)
		)
	)
	(zone
		(layer "F.Cu")
		(hatch none 0.5)
		(connect_pads
			(clearance 0)
		)
		(min_thickness 0.25)
		(keepout
			(tracks allowed)
			(vias allowed)
			(pads allowed)
			(copperpour allowed)
			(footprints not_allowed)
		)
		(placement
			(enabled no)
			(sheetname "")
		)
		(fill
			(thermal_gap 0.5)
			(thermal_bridge_width 0.5)
			(island_removal_mode 0)
		)
		(polygon
			(pts
				(xy 210.780122 -100.469954) (xy 203.160122 -100.469954) (xy 203.160122 -109.840014) (xy 210.780122 -109.840014)
			)
		)
	)
	(zone
		(layer "F.Cu")
		(hatch none 0.5)
		(connect_pads
			(clearance 0)
		)
		(min_thickness 0.25)
		(keepout
			(tracks allowed)
			(vias allowed)
			(pads allowed)
			(copperpour allowed)
			(footprints allowed)
		)
		(placement
			(enabled no)
			(sheetname "")
		)
		(fill
			(thermal_gap 0.5)
			(thermal_bridge_width 0.5)
			(island_removal_mode 0)
		)
		(polygon
			(pts
				(xy 189.6618 -379.3871) (xy 189.6618 -378.3965) (xy 189.6618 -377.4821) (xy 190.881 -377.4821) (xy 190.881 -379.3871)
				(xy 190.4492 -379.3871)
			)
		)
	)
	(zone
		(net "GND")
		(layer "F.Cu")
		(hatch none 0.5)
		(connect_pads
			(clearance 0.5)
		)
		(min_thickness 0.25)
		(fill yes
			(thermal_gap 0.5)
			(thermal_bridge_width 0.5)
			(island_removal_mode 0)
		)
		(polygon
			(pts
				(xy 324.538086 -79.053436) (xy 324.246748 -79.344774) (xy 324.246748 -83.528154)
				(arc
					(start 327.877932 -87.159084)
					(mid 329.996375 -87.214154)
					(end 331.802994 -88.321896)
				)
				(xy 332.723744 -88.321896) (xy 334.16494 -86.8807) (xy 334.16494 -80.698086) (xy 333.860902 -80.394048)
				(arc
					(start 332.852522 -80.394048)
					(mid 328.836943 -80.458162)
					(end 325.074534 -79.053436)
				)
			)
		)
	)
	(zone
		(layer "F.Cu")
		(hatch none 0.5)
		(connect_pads
			(clearance 0)
		)
		(min_thickness 0.25)
		(keepout
			(tracks allowed)
			(vias allowed)
			(pads allowed)
			(copperpour allowed)
			(footprints allowed)
		)
		(placement
			(enabled no)
			(sheetname "")
		)
		(fill
			(thermal_gap 0.5)
			(thermal_bridge_width 0.5)
			(island_removal_mode 0)
		)
		(polygon
			(pts
				(xy 260.382512 -372.502176) (xy 260.382512 -373.975376) (xy 257.960876 -373.975376) (xy 257.960876 -372.502176)
			)
		)
	)
	(zone
		(layer "F.Cu")
		(hatch none 0.5)
		(connect_pads
			(clearance 0)
		)
		(min_thickness 0.25)
		(keepout
			(tracks allowed)
			(vias allowed)
			(pads allowed)
			(copperpour allowed)
			(footprints allowed)
		)
		(placement
			(enabled no)
			(sheetname "")
		)
		(fill
			(thermal_gap 0.5)
			(thermal_bridge_width 0.5)
			(island_removal_mode 0)
		)
		(polygon
			(pts
				(xy 126.238 -249.5804) (xy 127.3556 -249.5804) (xy 127.4572 -249.4788) (xy 127.4572 -248.031) (xy 127.1524 -247.7262)
				(xy 126.2634 -247.7262) (xy 125.9332 -248.0564) (xy 125.9332 -249.2756)
			)
		)
	)
	(zone
		(layer "F.Cu")
		(hatch none 0.5)
		(connect_pads
			(clearance 0)
		)
		(min_thickness 0.25)
		(keepout
			(tracks allowed)
			(vias allowed)
			(pads allowed)
			(copperpour allowed)
			(footprints allowed)
		)
		(placement
			(enabled no)
			(sheetname "")
		)
		(fill
			(thermal_gap 0.5)
			(thermal_bridge_width 0.5)
			(island_removal_mode 0)
		)
		(polygon
			(pts
				(xy 186.390026 -370.968524) (xy 186.390026 -369.387628) (xy 187.609226 -369.387628) (xy 187.609226 -370.968524)
			)
		)
	)
	(zone
		(net "P12V_IN")
		(layer "F.Cu")
		(hatch none 0.5)
		(connect_pads
			(clearance 0.5)
		)
		(min_thickness 0.25)
		(fill yes
			(thermal_gap 0.5)
			(thermal_bridge_width 0.5)
			(island_removal_mode 0)
		)
		(polygon
			(pts
				(xy 128.71069 -364.370874) (xy 128.45669 -364.624874) (xy 128.45669 -367.85169) (xy 128.7399 -368.1349)
				(xy 132.1308 -368.1349) (xy 132.4102 -367.8555) (xy 132.4102 -367.081562) (xy 131.907534 -366.578896)
				(xy 131.907534 -364.430564) (xy 131.847844 -364.370874)
			)
		)
	)
	(zone
		(layer "F.Cu")
		(hatch none 0.5)
		(connect_pads
			(clearance 0)
		)
		(min_thickness 0.25)
		(keepout
			(tracks allowed)
			(vias allowed)
			(pads allowed)
			(copperpour allowed)
			(footprints not_allowed)
		)
		(placement
			(enabled no)
			(sheetname "")
		)
		(fill
			(thermal_gap 0.5)
			(thermal_bridge_width 0.5)
			(island_removal_mode 0)
		)
		(polygon
			(pts
				(xy 191.799972 -326.799956) (xy 0 -326.799956)
				(arc
					(start 0 -370.000022)
					(mid 0.292893 -370.707127)
					(end 0.999998 -371.00002)
				)
				(arc
					(start 1.999996 -371.00002)
					(mid 2.707101 -371.292913)
					(end 2.999994 -372.000018)
				)
				(arc
					(start 2.999994 -384.999992)
					(mid 3.292887 -385.707097)
					(end 3.999992 -385.99999)
				)
				(arc
					(start 15.249906 -385.99999)
					(mid 15.957011 -385.707097)
					(end 16.249904 -384.999992)
				)
				(arc
					(start 16.249904 -383.29997)
					(mid 16.542797 -382.592865)
					(end 17.249902 -382.299972)
				)
				(arc
					(start 23.750016 -382.299972)
					(mid 24.457121 -382.592865)
					(end 24.750014 -383.29997)
				)
				(arc
					(start 24.750014 -384.999992)
					(mid 25.042907 -385.707097)
					(end 25.750012 -385.99999)
				)
				(arc
					(start 71.300086 -385.99999)
					(mid 72.007191 -385.707097)
					(end 72.300084 -384.999992)
				)
				(arc
					(start 72.300084 -381)
					(mid 72.592977 -380.292895)
					(end 73.300082 -380.000002)
				)
				(xy 72.300084 -380.000002) (xy 72.300084 -370.000022) (xy 126.299976 -370.000022) (xy 126.299976 -380.000002)
				(arc
					(start 125.299978 -380.000002)
					(mid 126.007083 -380.292895)
					(end 126.299976 -381)
				)
				(arc
					(start 126.299976 -384.999992)
					(mid 126.592869 -385.707097)
					(end 127.299974 -385.99999)
				)
				(arc
					(start 172.850048 -385.99999)
					(mid 173.557153 -385.707097)
					(end 173.850046 -384.999992)
				)
				(arc
					(start 173.850046 -383.29997)
					(mid 174.142939 -382.592865)
					(end 174.850044 -382.299972)
				)
				(arc
					(start 181.349904 -382.299972)
					(mid 182.057009 -382.592865)
					(end 182.349902 -383.29997)
				)
				(arc
					(start 182.349902 -384.999992)
					(mid 182.642795 -385.707097)
					(end 183.3499 -385.99999)
				)
				(xy 191.799972 -385.99999)
			)
		)
	)
	(zone
		(net "P12V_HDD4")
		(layer "F.Cu")
		(hatch none 0.5)
		(connect_pads
			(clearance 0.5)
		)
		(min_thickness 0.25)
		(fill yes
			(thermal_gap 0.5)
			(thermal_bridge_width 0.5)
			(island_removal_mode 0)
		)
		(polygon
			(pts
				(xy 138.557 -262.255) (xy 138.303 -262.509) (xy 138.303 -264.16) (xy 138.557 -264.414) (xy 140.716 -264.414)
				(xy 141.224 -264.922) (xy 141.224 -267.462) (xy 148.971 -275.209) (xy 157.48 -275.209) (xy 157.607 -275.082)
				(xy 157.607 -273.304) (xy 157.48 -273.177) (xy 151.511 -273.177) (xy 150.876 -272.542) (xy 149.225 -272.542)
				(xy 144.907 -268.224) (xy 144.907 -264.668) (xy 143.764 -263.525) (xy 143.764 -262.509) (xy 143.51 -262.255)
			)
		)
		(polygon
			(pts
				(xy 151.0284 -274.2184) (xy 150.8252 -274.2184) (xy 150.8252 -274.4216) (xy 151.0284 -274.4216)
			)
		)
		(polygon
			(pts
				(xy 150.1648 -274.2184) (xy 149.9616 -274.2184) (xy 149.9616 -274.4216) (xy 150.1648 -274.4216)
			)
		)
	)
	(zone
		(layer "F.Cu")
		(hatch none 0.5)
		(connect_pads
			(clearance 0)
		)
		(min_thickness 0.25)
		(keepout
			(tracks allowed)
			(vias allowed)
			(pads allowed)
			(copperpour allowed)
			(footprints allowed)
		)
		(placement
			(enabled no)
			(sheetname "")
		)
		(fill
			(thermal_gap 0.5)
			(thermal_bridge_width 0.5)
			(island_removal_mode 0)
		)
		(polygon
			(pts
				(xy 188.903356 -375.352056) (xy 188.903356 -374.361456) (xy 188.903356 -373.447056) (xy 190.122556 -373.447056)
				(xy 190.122556 -375.352056) (xy 189.690756 -375.352056)
			)
		)
	)
	(zone
		(layer "F.Cu")
		(hatch none 0.5)
		(connect_pads
			(clearance 0)
		)
		(min_thickness 0.25)
		(keepout
			(tracks allowed)
			(vias allowed)
			(pads allowed)
			(copperpour allowed)
			(footprints not_allowed)
		)
		(placement
			(enabled no)
			(sheetname "")
		)
		(fill
			(thermal_gap 0.5)
			(thermal_bridge_width 0.5)
			(island_removal_mode 0)
		)
		(polygon
			(pts
				(xy 491.450122 -211.799932) (xy 491.450122 -276.800056) (xy 478.00006 -276.800056) (xy 478.00006 -266.800076)
				(xy 463.449924 -266.800076) (xy 463.449924 -276.800056) (xy 446.449958 -276.800056) (xy 446.449958 -266.800076)
				(xy 431.900076 -266.800076) (xy 431.900076 -276.800056) (xy 414.90011 -276.800056) (xy 414.90011 -266.800076)
				(xy 400.349974 -266.800076) (xy 400.349974 -276.800056) (xy 383.350008 -276.800056) (xy 383.350008 -266.800076)
				(xy 368.800126 -266.800076) (xy 368.800126 -276.800056) (xy 351.799906 -276.800056) (xy 351.799906 -266.800076)
				(xy 337.250024 -266.800076) (xy 337.250024 -276.800056) (xy 320.250058 -276.800056) (xy 320.250058 -266.800076)
				(xy 305.699922 -266.800076) (xy 305.699922 -276.800056) (xy 298.200064 -276.800056) (xy 298.200064 -259.999988)
				(xy 312.699908 -259.999988) (xy 312.699908 -234.00004) (xy 298.200064 -234.00004) (xy 298.200064 -211.799932)
			)
		)
	)
	(zone
		(net "IR_SWITCH_C")
		(layer "F.Cu")
		(hatch none 0.5)
		(connect_pads
			(clearance 0.5)
		)
		(min_thickness 0.25)
		(fill yes
			(thermal_gap 0.5)
			(thermal_bridge_width 0.5)
			(island_removal_mode 0)
		)
		(polygon
			(pts
				(xy 264.5791 -375.313956) (xy 264.4521 -375.440956) (xy 264.4521 -377.498356) (xy 264.5791 -377.625356)
				(xy 271.0815 -377.625356) (xy 271.3355 -377.371356) (xy 271.3355 -375.542556) (xy 271.1069 -375.313956)
			)
		)
		(polygon
			(pts
				(xy 265.5443 -376.329956) (xy 265.3411 -376.329956) (xy 265.3411 -376.533156) (xy 265.5443 -376.533156)
			)
		)
		(polygon
			(pts
				(xy 265.5443 -375.466356) (xy 265.3411 -375.466356) (xy 265.3411 -375.669556) (xy 265.5443 -375.669556)
			)
		)
	)
	(zone
		(net "5V_PRE_25")
		(layer "F.Cu")
		(hatch none 0.5)
		(connect_pads
			(clearance 0.5)
		)
		(min_thickness 0.25)
		(fill yes
			(thermal_gap 0.5)
			(thermal_bridge_width 0.5)
			(island_removal_mode 0)
		)
		(polygon
			(pts
				(xy 54.5084 -30.9626) (xy 54.356 -31.115) (xy 54.356 -32.512) (xy 54.9402 -33.0962) (xy 56.2102 -33.0962)
				(xy 58.293 -35.179) (xy 62.738 -35.179) (xy 62.865 -35.052) (xy 62.865 -34.29) (xy 62.738 -34.163)
				(xy 59.7154 -34.163) (xy 56.515 -30.9626)
			)
		)
	)
	(zone
		(net "GND")
		(layer "F.Cu")
		(hatch none 0.5)
		(connect_pads
			(clearance 0.5)
		)
		(min_thickness 0.25)
		(fill yes
			(thermal_gap 0.5)
			(thermal_bridge_width 0.5)
			(island_removal_mode 0)
		)
		(polygon
			(pts
				(xy 208.518252 -368.282728) (xy 212.007958 -364.792768) (xy 212.007958 -362.965492) (xy 211.04606 -362.003594)
				(xy 205.700122 -362.003594) (xy 205.689962 -362.013754) (xy 194.31508 -362.013754) (xy 194.080892 -362.247942)
				(arc
					(start 194.080892 -362.920788)
					(mid 194.46055 -363.597027)
					(end 194.705732 -364.332774)
				)
				(arc
					(start 195.202302 -364.829344)
					(mid 198.185007 -365.236175)
					(end 200.081388 -367.574068)
				)
				(xy 200.790048 -368.282728)
			)
		)
	)
	(zone
		(net "5V_PRE_7")
		(layer "F.Cu")
		(hatch none 0.5)
		(connect_pads
			(clearance 0.5)
		)
		(min_thickness 0.25)
		(fill yes
			(thermal_gap 0.5)
			(thermal_bridge_width 0.5)
			(island_removal_mode 0)
		)
		(polygon
			(pts
				(xy 360.934 -260.985) (xy 360.68 -261.239) (xy 360.68 -263.779) (xy 360.299 -264.16) (xy 357.759 -264.16)
				(xy 357.505 -264.414) (xy 357.505 -264.795) (xy 357.759 -265.049) (xy 361.061 -265.049) (xy 362.331 -263.779)
				(xy 362.331 -261.239) (xy 362.077 -260.985)
			)
		)
	)
	(zone
		(layer "F.Cu")
		(hatch none 0.5)
		(connect_pads
			(clearance 0)
		)
		(min_thickness 0.25)
		(keepout
			(tracks allowed)
			(vias allowed)
			(pads allowed)
			(copperpour allowed)
			(footprints allowed)
		)
		(placement
			(enabled no)
			(sheetname "")
		)
		(fill
			(thermal_gap 0.5)
			(thermal_bridge_width 0.5)
			(island_removal_mode 0)
		)
		(polygon
			(pts
				(xy 63.246 -134.6454) (xy 64.2874 -134.6454) (xy 64.4398 -134.493) (xy 64.4398 -133.2738) (xy 64.1096 -132.9436)
				(xy 63.0428 -132.9436) (xy 62.865 -133.1214) (xy 62.865 -134.2644)
			)
		)
	)
	(zone
		(net "P12V_FAN3")
		(layer "F.Cu")
		(hatch none 0.5)
		(connect_pads
			(clearance 0.5)
		)
		(min_thickness 0.25)
		(fill yes
			(thermal_gap 0.5)
			(thermal_bridge_width 0.5)
			(island_removal_mode 0)
		)
		(polygon
			(pts
				(xy 441.865004 -358.14) (xy 441.738004 -358.267) (xy 441.738004 -359.3592) (xy 441.712604 -359.3846)
				(xy 441.687204 -359.3846) (xy 439.350404 -361.7214) (xy 437.166004 -361.7214) (xy 436.429404 -362.458)
				(xy 436.429404 -364.49) (xy 437.191404 -365.252) (xy 440.493404 -365.252) (xy 441.103004 -365.8616)
				(xy 441.103004 -374.65) (xy 441.865004 -375.412) (xy 444.434468 -375.412) (xy 445.040004 -374.806464)
				(xy 445.040004 -365.660432) (xy 444.884048 -365.504476) (xy 444.884048 -358.619044) (xy 444.405004 -358.14)
			)
		)
		(polygon
			(pts
				(xy 444.442596 -364.466886) (xy 444.239396 -364.466886) (xy 444.239396 -364.670086) (xy 444.442596 -364.670086)
			)
		)
		(polygon
			(pts
				(xy 444.442596 -363.857286) (xy 444.239396 -363.857286) (xy 444.239396 -364.060486) (xy 444.442596 -364.060486)
			)
		)
		(polygon
			(pts
				(xy 444.125604 -363.5502) (xy 443.922404 -363.5502) (xy 443.922404 -363.7534) (xy 444.125604 -363.7534)
			)
		)
		(polygon
			(pts
				(xy 444.125604 -362.6866) (xy 443.922404 -362.6866) (xy 443.922404 -362.8898) (xy 444.125604 -362.8898)
			)
		)
	)
	(zone
		(net "12V_PRE_1")
		(layer "F.Cu")
		(hatch none 0.5)
		(connect_pads
			(clearance 0.5)
		)
		(min_thickness 0.25)
		(fill yes
			(thermal_gap 0.5)
			(thermal_bridge_width 0.5)
			(island_removal_mode 0)
		)
		(polygon
			(pts
				(xy 51.308 -264.795) (xy 51.181 -264.922) (xy 51.181 -266.446) (xy 52.578 -267.843) (xy 53.975 -267.843)
				(xy 58.928 -272.796) (xy 62.865 -272.796) (xy 62.992 -272.669) (xy 62.992 -271.907) (xy 62.865 -271.78)
				(xy 59.563 -271.78) (xy 52.578 -264.795)
			)
		)
	)
	(zone
		(layer "F.Cu")
		(hatch none 0.5)
		(connect_pads
			(clearance 0)
		)
		(min_thickness 0.25)
		(keepout
			(tracks allowed)
			(vias allowed)
			(pads allowed)
			(copperpour allowed)
			(footprints allowed)
		)
		(placement
			(enabled no)
			(sheetname "")
		)
		(fill
			(thermal_gap 0.5)
			(thermal_bridge_width 0.5)
			(island_removal_mode 0)
		)
		(polygon
			(pts
				(xy 320.329814 -374.24106) (xy 320.329814 -375.087896) (xy 319.906396 -375.511314) (xy 319.906396 -375.8819)
				(xy 319.474596 -375.8819) (xy 319.228216 -375.8819) (xy 319.228216 -374.24106)
			)
		)
	)
	(zone
		(net "P12V_B")
		(layer "F.Cu")
		(hatch none 0.5)
		(connect_pads
			(clearance 0.5)
		)
		(min_thickness 0.25)
		(fill yes
			(thermal_gap 0.5)
			(thermal_bridge_width 0.5)
			(island_removal_mode 0)
		)
		(polygon
			(pts
				(xy 460.756 -142.494) (xy 460.248 -143.002) (xy 460.248 -146.431) (xy 460.502 -146.685) (xy 463.804 -146.685)
				(xy 464.058 -146.431) (xy 464.058 -144.399) (xy 464.185 -144.272) (xy 464.566 -144.272) (xy 464.665568 -144.172432)
				(xy 464.665568 -142.593568) (xy 464.566 -142.494)
			)
		)
		(polygon
			(pts
				(xy 464.1596 -143.4846) (xy 463.9564 -143.4846) (xy 463.9564 -143.6878) (xy 464.1596 -143.6878)
			)
		)
		(polygon
			(pts
				(xy 464.2104 -143.0528) (xy 464.0072 -143.0528) (xy 464.0072 -143.256) (xy 464.2104 -143.256)
			)
		)
	)
	(zone
		(layer "F.Cu")
		(hatch none 0.5)
		(connect_pads
			(clearance 0)
		)
		(min_thickness 0.25)
		(keepout
			(tracks allowed)
			(vias allowed)
			(pads allowed)
			(copperpour allowed)
			(footprints allowed)
		)
		(placement
			(enabled no)
			(sheetname "")
		)
		(fill
			(thermal_gap 0.5)
			(thermal_bridge_width 0.5)
			(island_removal_mode 0)
		)
		(polygon
			(pts
				(xy 126.2888 -19.5072) (xy 127.3302 -19.5072) (xy 127.4826 -19.3548) (xy 127.4826 -18.1356) (xy 127.1524 -17.8054)
				(xy 126.0856 -17.8054) (xy 125.9078 -17.9832) (xy 125.9078 -19.1262)
			)
		)
	)
	(zone
		(net "P3V3_IN")
		(layer "F.Cu")
		(hatch none 0.5)
		(connect_pads
			(clearance 0.5)
		)
		(min_thickness 0.25)
		(fill yes
			(thermal_gap 0.5)
			(thermal_bridge_width 0.5)
			(island_removal_mode 0)
		)
		(polygon
			(pts
				(xy 306.498498 -330.525882) (xy 306.410868 -330.613512) (xy 306.410868 -332.70444) (xy 306.51831 -332.811882)
				(xy 310.361076 -332.811882) (xy 310.488076 -332.684882) (xy 310.488076 -330.652882) (xy 310.361076 -330.525882)
			)
		)
		(polygon
			(pts
				(xy 307.475382 -332.116176) (xy 307.272182 -332.116176) (xy 307.272182 -332.319376) (xy 307.475382 -332.319376)
			)
		)
		(polygon
			(pts
				(xy 306.865782 -332.116176) (xy 306.662582 -332.116176) (xy 306.662582 -332.319376) (xy 306.865782 -332.319376)
			)
		)
		(polygon
			(pts
				(xy 308.643782 -331.735176) (xy 308.440582 -331.735176) (xy 308.440582 -331.938376) (xy 308.643782 -331.938376)
			)
		)
		(polygon
			(pts
				(xy 307.780182 -331.735176) (xy 307.576982 -331.735176) (xy 307.576982 -331.938376) (xy 307.780182 -331.938376)
			)
		)
	)
	(zone
		(layer "F.Cu")
		(hatch none 0.5)
		(connect_pads
			(clearance 0)
		)
		(min_thickness 0.25)
		(keepout
			(tracks allowed)
			(vias allowed)
			(pads allowed)
			(copperpour allowed)
			(footprints allowed)
		)
		(placement
			(enabled no)
			(sheetname "")
		)
		(fill
			(thermal_gap 0.5)
			(thermal_bridge_width 0.5)
			(island_removal_mode 0)
		)
		(polygon
			(pts
				(xy 435.553358 -114.610134) (xy 435.553358 -110.511844) (xy 436.804308 -110.511844) (xy 436.804308 -114.610134)
			)
		)
	)
	(zone
		(layer "F.Cu")
		(hatch none 0.5)
		(connect_pads
			(clearance 0)
		)
		(min_thickness 0.25)
		(keepout
			(tracks not_allowed)
			(vias allowed)
			(pads allowed)
			(copperpour not_allowed)
			(footprints allowed)
		)
		(placement
			(enabled no)
			(sheetname "")
		)
		(fill
			(thermal_gap 0.5)
			(thermal_bridge_width 0.5)
			(island_removal_mode 0)
		)
		(polygon
			(pts
				(arc
					(start 481.824792 -248.115328)
					(mid 481.339779 -247.629934)
					(end 480.854512 -248.115074)
				)
				(arc
					(start 480.854512 -249.385074)
					(mid 481.339652 -249.870214)
					(end 481.824792 -249.385074)
				)
				(xy 481.824792 -248.972324)
				(arc
					(start 481.5078 -248.972324)
					(mid 481.442783 -248.999255)
					(end 481.415852 -249.064272)
				)
				(arc
					(start 481.415852 -249.12955)
					(mid 481.339652 -249.651718)
					(end 481.263452 -249.12955)
				)
				(xy 481.263452 -249.032776)
				(arc
					(start 481.265738 -249.030236)
					(mid 481.334953 -248.891425)
					(end 481.473764 -248.82221)
				)
				(xy 481.476304 -248.819924) (xy 481.824792 -248.819924) (xy 481.824792 -248.680224) (xy 481.476304 -248.680224)
				(arc
					(start 481.473764 -248.677938)
					(mid 481.334953 -248.608723)
					(end 481.265738 -248.469912)
				)
				(xy 481.263452 -248.467372)
				(arc
					(start 481.263452 -248.370598)
					(mid 481.339652 -247.84843)
					(end 481.415852 -248.370598)
				)
				(arc
					(start 481.415852 -248.435876)
					(mid 481.442783 -248.500893)
					(end 481.5078 -248.527824)
				)
				(xy 481.824792 -248.527824)
			)
		)
	)
	(zone
		(net "P5V_HDD2")
		(layer "F.Cu")
		(hatch none 0.5)
		(connect_pads
			(clearance 0.5)
		)
		(min_thickness 0.25)
		(fill yes
			(thermal_gap 0.5)
			(thermal_bridge_width 0.5)
			(island_removal_mode 0)
		)
		(polygon
			(pts
				(xy 82.804 -257.683) (xy 82.55 -257.937) (xy 82.55 -260.223) (xy 82.804 -260.477) (xy 82.804 -262.509)
				(xy 83.566 -263.271) (xy 83.566 -264.033) (xy 83.947 -264.414) (xy 84.328 -264.414) (xy 87.503 -267.589)
				(xy 94.361 -267.589) (xy 94.488 -267.462) (xy 94.488 -265.684) (xy 94.361 -265.557) (xy 89.281 -265.557)
				(xy 87.376 -263.652) (xy 86.487 -263.652) (xy 85.598 -262.763) (xy 85.598 -260.223) (xy 86.233 -259.588)
				(xy 86.233 -257.937) (xy 85.979 -257.683)
			)
		)
		(polygon
			(pts
				(xy 84.5312 -263.2456) (xy 84.328 -263.2456) (xy 84.328 -263.4488) (xy 84.5312 -263.4488)
			)
		)
	)
	(zone
		(net "GND")
		(layer "F.Cu")
		(hatch none 0.5)
		(connect_pads
			(clearance 0.5)
		)
		(min_thickness 0.25)
		(fill yes
			(thermal_gap 0.5)
			(thermal_bridge_width 0.5)
			(island_removal_mode 0)
		)
		(polygon
			(pts
				(xy 129.958592 -238.1123) (xy 129.667508 -238.403384) (xy 129.667508 -239.166146)
				(arc
					(start 129.97434 -239.472978)
					(mid 132.156678 -240.923005)
					(end 133.001004 -243.403374)
				)
				(arc
					(start 133.001004 -246.578374)
					(mid 132.529481 -248.478869)
					(end 131.224274 -249.93854)
				)
				(arc
					(start 131.224274 -250.401074)
					(mid 131.184519 -250.968214)
					(end 131.066032 -251.524262)
				)
				(arc
					(start 131.066032 -251.524262)
					(mid 130.804712 -253.469229)
					(end 129.667508 -255.068578)
				)
				(xy 129.667508 -256.743454)
				(arc
					(start 130.082544 -257.15849)
					(mid 131.559271 -257.326771)
					(end 132.878322 -258.011676)
				)
				(xy 133.82625 -258.011676) (xy 134.554976 -257.28295) (xy 134.554976 -253.680976) (xy 135.900414 -253.680976)
				(xy 136.523476 -253.057914)
				(arc
					(start 136.523476 -251.13361)
					(mid 135.913538 -249.799923)
					(end 135.813292 -248.336816)
				)
				(arc
					(start 135.813292 -247.776746)
					(mid 136.008198 -246.533201)
					(end 136.574276 -245.408958)
				)
				(xy 136.574276 -242.543076) (xy 137.006076 -242.111276) (xy 144.216374 -242.111276)
				(arc
					(start 144.338548 -242.091718)
					(mid 145.873307 -241.807358)
					(end 147.404328 -242.111276)
				)
				(xy 148.435314 -242.111276)
				(arc
					(start 148.905722 -241.640868)
					(mid 149.069765 -241.15276)
					(end 149.293834 -240.68913)
				)
				(xy 149.293834 -239.031272) (xy 148.374862 -238.1123)
			)
		)
	)
	(zone
		(net "P3V3_IN_BIAS")
		(layer "F.Cu")
		(hatch none 0.5)
		(connect_pads
			(clearance 0.5)
		)
		(min_thickness 0.25)
		(fill yes
			(thermal_gap 0.5)
			(thermal_bridge_width 0.5)
			(island_removal_mode 0)
		)
		(polygon
			(pts
				(xy 264.998962 -363.018578) (xy 264.672064 -363.345476) (xy 262.828532 -363.345476) (xy 262.6868 -363.487208)
				(xy 262.6868 -364.103666) (xy 262.446262 -364.344204) (xy 261.613904 -364.344204) (xy 261.287006 -364.671102)
				(xy 261.287006 -365.814864) (xy 261.487666 -366.015524) (xy 263.01954 -366.015524) (xy 264.447274 -364.58779)
				(xy 265.489182 -364.58779) (xy 265.75131 -364.325662) (xy 265.75131 -363.111034) (xy 265.658854 -363.018578)
			)
		)
		(polygon
			(pts
				(xy 264.725658 -364.1344) (xy 264.522458 -364.1344) (xy 264.522458 -364.3376) (xy 264.725658 -364.3376)
			)
		)
		(polygon
			(pts
				(xy 263.862058 -364.1344) (xy 263.658858 -364.1344) (xy 263.658858 -364.3376) (xy 263.862058 -364.3376)
			)
		)
		(polygon
			(pts
				(xy 263.535922 -363.854746) (xy 263.332722 -363.854746) (xy 263.332722 -364.057946) (xy 263.535922 -364.057946)
			)
		)
	)
	(zone
		(net "P5V_HDD34")
		(layer "F.Cu")
		(hatch none 0.5)
		(connect_pads
			(clearance 0.5)
		)
		(min_thickness 0.25)
		(fill yes
			(thermal_gap 0.5)
			(thermal_bridge_width 0.5)
			(island_removal_mode 0)
		)
		(polygon
			(pts
				(xy 457.327 -24.765) (xy 456.819 -25.273) (xy 456.819 -30.607) (xy 457.454 -31.242) (xy 457.454 -33.782)
				(xy 455.803 -35.433) (xy 452.374 -35.433) (xy 452.12 -35.687) (xy 452.12 -37.338) (xy 452.374 -37.592)
				(xy 456.946 -37.592) (xy 457.581 -36.957) (xy 459.359 -36.957) (xy 459.867 -36.449) (xy 459.867 -29.7688)
				(xy 461.01 -28.6258) (xy 461.01 -25.019) (xy 460.756 -24.765)
			)
		)
		(polygon
			(pts
				(xy 456.4634 -36.6014) (xy 456.2602 -36.6014) (xy 456.2602 -36.8046) (xy 456.4634 -36.8046)
			)
		)
		(polygon
			(pts
				(xy 455.5998 -36.6014) (xy 455.3966 -36.6014) (xy 455.3966 -36.8046) (xy 455.5998 -36.8046)
			)
		)
	)
	(zone
		(layer "F.Cu")
		(hatch none 0.5)
		(connect_pads
			(clearance 0)
		)
		(min_thickness 0.25)
		(keepout
			(tracks not_allowed)
			(vias allowed)
			(pads allowed)
			(copperpour not_allowed)
			(footprints allowed)
		)
		(placement
			(enabled no)
			(sheetname "")
		)
		(fill
			(thermal_gap 0.5)
			(thermal_bridge_width 0.5)
			(island_removal_mode 0)
		)
		(polygon
			(pts
				(arc
					(start 182.79999 -204.0001)
					(mid 189.799976 -197.000114)
					(end 196.799962 -204.0001)
				)
				(arc
					(start 196.799962 -210.000088)
					(mid 189.799976 -217.000074)
					(end 182.79999 -210.000088)
				)
			)
		)
	)
	(zone
		(layer "F.Cu")
		(hatch none 0.5)
		(connect_pads
			(clearance 0)
		)
		(min_thickness 0.25)
		(keepout
			(tracks allowed)
			(vias allowed)
			(pads allowed)
			(copperpour allowed)
			(footprints not_allowed)
		)
		(placement
			(enabled no)
			(sheetname "")
		)
		(fill
			(thermal_gap 0.5)
			(thermal_bridge_width 0.5)
			(island_removal_mode 0)
		)
		(polygon
			(pts
				(arc
					(start 198.000112 0)
					(mid 198.204315 -0.021177)
					(end 198.399908 -0.083566)
				)
				(xy 198.399908 -84.000086) (xy 191.799972 -84.000086) (xy 191.799972 0)
			)
		)
	)
	(zone
		(net "MB0_CM_GATE_R")
		(layer "F.Cu")
		(hatch none 0.5)
		(connect_pads
			(clearance 0.5)
		)
		(min_thickness 0.25)
		(fill yes
			(thermal_gap 0.5)
			(thermal_bridge_width 0.5)
			(island_removal_mode 0)
		)
		(polygon
			(pts
				(xy 212.891624 -352.893376) (xy 210.286092 -355.498908) (xy 210.286092 -357.694738) (xy 210.482942 -357.891588)
				(xy 213.854538 -357.891588) (xy 213.924134 -357.821992) (xy 213.924134 -353.067874) (xy 213.749636 -352.893376)
			)
		)
	)
	(zone
		(layer "F.Cu")
		(hatch none 0.5)
		(connect_pads
			(clearance 0)
		)
		(min_thickness 0.25)
		(keepout
			(tracks not_allowed)
			(vias allowed)
			(pads allowed)
			(copperpour not_allowed)
			(footprints allowed)
		)
		(placement
			(enabled no)
			(sheetname "")
		)
		(fill
			(thermal_gap 0.5)
			(thermal_bridge_width 0.5)
			(island_removal_mode 0)
		)
		(polygon
			(pts
				(arc
					(start 477.637602 -244.312694)
					(mid 477.152462 -243.827554)
					(end 476.667322 -244.312694)
				)
				(arc
					(start 476.667322 -245.45544)
					(mid 477.152335 -245.940834)
					(end 477.637602 -245.455694)
				)
				(xy 477.637602 -245.106444)
				(arc
					(start 477.338136 -245.106444)
					(mid 477.266408 -245.133215)
					(end 477.229678 -245.200424)
				)
				(arc
					(start 477.229678 -245.200424)
					(mid 477.151939 -245.722386)
					(end 477.076262 -245.20017)
				)
				(xy 477.076262 -245.184422)
				(arc
					(start 477.078548 -245.182136)
					(mid 477.153032 -245.030814)
					(end 477.304354 -244.95633)
				)
				(xy 477.30664 -244.954044) (xy 477.637602 -244.954044) (xy 477.637602 -244.814344) (xy 477.296988 -244.814344)
				(arc
					(start 477.292924 -244.810534)
					(mid 477.148923 -244.73358)
					(end 477.078548 -244.586252)
				)
				(xy 477.076262 -244.583966)
				(arc
					(start 477.076262 -244.568218)
					(mid 477.151939 -244.046051)
					(end 477.229678 -244.567964)
				)
				(arc
					(start 477.229678 -244.567964)
					(mid 477.266353 -244.635237)
					(end 477.338136 -244.661944)
				)
				(xy 477.637602 -244.661944)
			)
		)
	)
	(zone
		(layer "F.Cu")
		(hatch none 0.5)
		(connect_pads
			(clearance 0)
		)
		(min_thickness 0.25)
		(keepout
			(tracks not_allowed)
			(vias allowed)
			(pads allowed)
			(copperpour not_allowed)
			(footprints allowed)
		)
		(placement
			(enabled no)
			(sheetname "")
		)
		(fill
			(thermal_gap 0.5)
			(thermal_bridge_width 0.5)
			(island_removal_mode 0)
		)
		(polygon
			(pts
				(arc
					(start 34.770822 -244.419374)
					(mid 34.285682 -243.934234)
					(end 33.800542 -244.419374)
				)
				(xy 33.800542 -244.768624)
				(arc
					(start 34.126678 -244.768624)
					(mid 34.185229 -244.744371)
					(end 34.209482 -244.68582)
				)
				(arc
					(start 34.209482 -244.674898)
					(mid 34.285682 -244.15273)
					(end 34.361882 -244.674898)
				)
				(xy 34.361882 -244.717316)
				(arc
					(start 34.359342 -244.719856)
					(mid 34.292947 -244.852089)
					(end 34.160714 -244.918484)
				)
				(xy 34.158174 -244.921024) (xy 33.800542 -244.921024) (xy 33.800542 -245.060724) (xy 34.158174 -245.060724)
				(arc
					(start 34.160714 -245.063264)
					(mid 34.292947 -245.129659)
					(end 34.359342 -245.261892)
				)
				(xy 34.361882 -245.264432)
				(arc
					(start 34.361882 -245.30685)
					(mid 34.285682 -245.829018)
					(end 34.209482 -245.30685)
				)
				(arc
					(start 34.209482 -245.295928)
					(mid 34.185229 -245.237377)
					(end 34.126678 -245.213124)
				)
				(xy 33.800542 -245.213124)
				(arc
					(start 33.800542 -245.56212)
					(mid 34.285555 -246.047514)
					(end 34.770822 -245.562374)
				)
			)
		)
	)
	(zone
		(net "GND")
		(layer "F.Cu")
		(hatch none 0.5)
		(connect_pads
			(clearance 0.5)
		)
		(min_thickness 0.25)
		(fill yes
			(thermal_gap 0.5)
			(thermal_bridge_width 0.5)
			(island_removal_mode 0)
		)
		(polygon
			(pts
				(arc
					(start 324.21195 -350.997266)
					(mid 325.208642 -352.042937)
					(end 325.779638 -353.36988)
				)
				(arc
					(start 326.338184 -353.928426)
					(mid 327.574951 -354.394545)
					(end 328.59853 -355.230684)
				)
				(xy 328.754232 -355.230684) (xy 329.087734 -354.897182) (xy 329.087734 -353.944428) (xy 326.562212 -351.418906)
				(xy 326.562212 -330.84008) (xy 325.398384 -329.676252) (xy 318.995044 -329.676252) (xy 318.479424 -330.191872)
				(xy 318.479424 -335.268824) (xy 319.4812 -336.2706)
				(arc
					(start 319.4812 -347.37421)
					(mid 319.539258 -347.428136)
					(end 319.596262 -347.483176)
				)
				(arc
					(start 319.596262 -347.483176)
					(mid 320.121163 -347.835123)
					(end 320.585592 -348.263718)
				)
				(arc
					(start 320.585592 -348.263718)
					(mid 322.81294 -349.081016)
					(end 324.21195 -350.997266)
				)
			)
		)
	)
	(zone
		(net "P12V_B")
		(layer "F.Cu")
		(hatch none 0.5)
		(connect_pads
			(clearance 0.5)
		)
		(min_thickness 0.25)
		(fill yes
			(thermal_gap 0.5)
			(thermal_bridge_width 0.5)
			(island_removal_mode 0)
		)
		(polygon
			(pts
				(xy 334.645 -142.494) (xy 334.137 -143.002) (xy 334.137 -146.431) (xy 334.391 -146.685) (xy 337.693 -146.685)
				(xy 337.947 -146.431) (xy 337.947 -144.399) (xy 338.074 -144.272) (xy 338.455 -144.272) (xy 338.582 -144.145)
				(xy 338.582 -142.621) (xy 338.455 -142.494)
			)
		)
		(polygon
			(pts
				(xy 338.0486 -143.4846) (xy 337.8454 -143.4846) (xy 337.8454 -143.6878) (xy 338.0486 -143.6878)
			)
		)
		(polygon
			(pts
				(xy 338.0994 -143.0528) (xy 337.8962 -143.0528) (xy 337.8962 -143.256) (xy 338.0994 -143.256)
			)
		)
	)
	(zone
		(layer "F.Cu")
		(hatch none 0.5)
		(connect_pads
			(clearance 0)
		)
		(min_thickness 0.25)
		(keepout
			(tracks allowed)
			(vias allowed)
			(pads allowed)
			(copperpour allowed)
			(footprints allowed)
		)
		(placement
			(enabled no)
			(sheetname "")
		)
		(fill
			(thermal_gap 0.5)
			(thermal_bridge_width 0.5)
			(island_removal_mode 0)
		)
		(polygon
			(pts
				(xy 184.55132 -367.393982) (xy 186.02452 -367.393982) (xy 186.02452 -369.815618) (xy 184.55132 -369.815618)
			)
		)
	)
	(zone
		(layer "F.Cu")
		(hatch none 0.5)
		(connect_pads
			(clearance 0)
		)
		(min_thickness 0.25)
		(keepout
			(tracks allowed)
			(vias allowed)
			(pads allowed)
			(copperpour allowed)
			(footprints not_allowed)
		)
		(placement
			(enabled no)
			(sheetname "")
		)
		(fill
			(thermal_gap 0.5)
			(thermal_bridge_width 0.5)
			(island_removal_mode 0)
		)
		(polygon
			(pts
				(xy 191.799972 0) (xy 191.799972 -46.800008) (xy 180.64988 -46.800008) (xy 180.64988 -36.800028)
				(xy 166.099998 -36.800028) (xy 166.099998 -46.800008) (xy 149.100032 -46.800008) (xy 149.100032 -36.800028)
				(xy 134.549896 -36.800028) (xy 134.549896 -46.800008) (xy 117.54993 -46.800008) (xy 117.54993 -36.800028)
				(xy 103.000048 -36.800028) (xy 103.000048 -46.800008) (xy 86.000082 -46.800008) (xy 86.000082 -36.800028)
				(xy 71.449946 -36.800028) (xy 71.449946 -46.800008) (xy 54.44998 -46.800008) (xy 54.44998 -36.800028)
				(xy 39.900098 -36.800028) (xy 39.900098 -46.800008) (xy 22.899878 -46.800008) (xy 22.899878 -36.800028)
				(xy 8.349996 -36.800028) (xy 8.349996 -46.800008) (xy 0 -46.800008)
				(arc
					(start 0 -0.999998)
					(mid 0.292893 -0.292893)
					(end 0.999998 0)
				)
			)
		)
	)
	(zone
		(layer "F.Cu")
		(hatch none 0.5)
		(connect_pads
			(clearance 0)
		)
		(min_thickness 0.25)
		(keepout
			(tracks allowed)
			(vias allowed)
			(pads allowed)
			(copperpour allowed)
			(footprints allowed)
		)
		(placement
			(enabled no)
			(sheetname "")
		)
		(fill
			(thermal_gap 0.5)
			(thermal_bridge_width 0.5)
			(island_removal_mode 0)
		)
		(polygon
			(pts
				(xy 189.61227 -373.138192) (xy 188.031374 -373.138192) (xy 188.031374 -371.918992) (xy 189.61227 -371.918992)
			)
		)
	)
	(zone
		(net "MB3_CM_GATE")
		(layer "F.Cu")
		(hatch none 0.5)
		(connect_pads
			(clearance 0.5)
		)
		(min_thickness 0.25)
		(fill yes
			(thermal_gap 0.5)
			(thermal_bridge_width 0.5)
			(island_removal_mode 0)
		)
		(polygon
			(pts
				(xy 250.4821 -368.2111) (xy 250.2408 -368.4524) (xy 250.2408 -369.824) (xy 250.3932 -369.9764) (xy 251.4981 -369.9764)
				(xy 251.7521 -369.7224) (xy 251.7521 -368.2111)
			)
		)
	)
	(zone
		(net "GND")
		(layer "F.Cu")
		(hatch none 0.5)
		(connect_pads
			(clearance 0.5)
		)
		(min_thickness 0.25)
		(fill yes
			(thermal_gap 0.5)
			(thermal_bridge_width 0.5)
			(island_removal_mode 0)
		)
		(polygon
			(pts
				(xy 166.496238 -40.197024) (xy 165.77056 -40.922702) (xy 165.77056 -51.95951) (xy 166.30269 -52.49164)
				(xy 180.33873 -52.49164) (xy 180.843936 -51.986434) (xy 180.843936 -51.45532)
				(arc
					(start 180.401214 -51.012598)
					(mid 179.886895 -50.751435)
					(end 179.414424 -50.420524)
				)
				(xy 177.747676 -50.420524) (xy 177.747676 -47.881286) (xy 177.632614 -47.766224) (xy 177.176176 -47.766224)
				(xy 177.176176 -47.309786) (xy 170.063414 -40.197024)
			)
		)
	)
	(zone
		(layer "F.Cu")
		(hatch none 0.5)
		(connect_pads
			(clearance 0)
		)
		(min_thickness 0.25)
		(keepout
			(tracks allowed)
			(vias allowed)
			(pads allowed)
			(copperpour allowed)
			(footprints not_allowed)
		)
		(placement
			(enabled no)
			(sheetname "")
		)
		(fill
			(thermal_gap 0.5)
			(thermal_bridge_width 0.5)
			(island_removal_mode 0)
		)
		(polygon
			(pts
				(xy 177.299874 -84.000086) (xy 177.299874 -110.000034) (xy 202.300078 -110.000034) (xy 202.300078 -84.000086)
			)
		)
	)
	(zone
		(net "P5V_HDD32")
		(layer "F.Cu")
		(hatch none 0.5)
		(connect_pads
			(clearance 0.5)
		)
		(min_thickness 0.25)
		(fill yes
			(thermal_gap 0.5)
			(thermal_bridge_width 0.5)
			(island_removal_mode 0)
		)
		(polygon
			(pts
				(xy 394.335 -24.765) (xy 394.081 -25.019) (xy 394.081 -30.607) (xy 394.462 -30.988) (xy 394.462 -33.782)
				(xy 392.811 -35.433) (xy 389.382 -35.433) (xy 389.128 -35.687) (xy 389.128 -37.338) (xy 389.382 -37.592)
				(xy 393.954 -37.592) (xy 394.589 -36.957) (xy 396.367 -36.957) (xy 396.875 -36.449) (xy 396.875 -27.813)
				(xy 397.764 -26.924) (xy 397.764 -25.019) (xy 397.51 -24.765)
			)
		)
		(polygon
			(pts
				(xy 393.4714 -36.6014) (xy 393.2682 -36.6014) (xy 393.2682 -36.8046) (xy 393.4714 -36.8046)
			)
		)
		(polygon
			(pts
				(xy 392.6078 -36.6014) (xy 392.4046 -36.6014) (xy 392.4046 -36.8046) (xy 392.6078 -36.8046)
			)
		)
	)
	(zone
		(net "P5V_HDD3")
		(layer "F.Cu")
		(hatch none 0.5)
		(connect_pads
			(clearance 0.5)
		)
		(min_thickness 0.25)
		(fill yes
			(thermal_gap 0.5)
			(thermal_bridge_width 0.5)
			(island_removal_mode 0)
		)
		(polygon
			(pts
				(xy 114.3 -257.683) (xy 114.046 -257.937) (xy 114.046 -260.223) (xy 114.3 -260.477) (xy 114.3 -262.509)
				(xy 115.062 -263.271) (xy 115.062 -264.033) (xy 115.443 -264.414) (xy 115.824 -264.414) (xy 118.999 -267.589)
				(xy 125.857 -267.589) (xy 125.984 -267.462) (xy 125.984 -265.684) (xy 125.857 -265.557) (xy 120.777 -265.557)
				(xy 118.872 -263.652) (xy 117.983 -263.652) (xy 117.094 -262.763) (xy 117.094 -260.223) (xy 117.729 -259.588)
				(xy 117.729 -257.937) (xy 117.475 -257.683)
			)
		)
		(polygon
			(pts
				(xy 116.0272 -263.2456) (xy 115.824 -263.2456) (xy 115.824 -263.4488) (xy 116.0272 -263.4488)
			)
		)
	)
	(zone
		(layer "F.Cu")
		(hatch none 0.5)
		(connect_pads
			(clearance 0)
		)
		(min_thickness 0.25)
		(keepout
			(tracks allowed)
			(vias allowed)
			(pads allowed)
			(copperpour allowed)
			(footprints allowed)
		)
		(placement
			(enabled no)
			(sheetname "")
		)
		(fill
			(thermal_gap 0.5)
			(thermal_bridge_width 0.5)
			(island_removal_mode 0)
		)
		(polygon
			(pts
				(xy 331.241908 -363.136688) (xy 331.241908 -364.609888) (xy 328.820272 -364.609888) (xy 328.820272 -363.136688)
			)
		)
	)
	(zone
		(layer "F.Cu")
		(hatch none 0.5)
		(connect_pads
			(clearance 0)
		)
		(min_thickness 0.25)
		(keepout
			(tracks allowed)
			(vias allowed)
			(pads allowed)
			(copperpour allowed)
			(footprints not_allowed)
		)
		(placement
			(enabled no)
			(sheetname "")
		)
		(fill
			(thermal_gap 0.5)
			(thermal_bridge_width 0.5)
			(island_removal_mode 0)
		)
		(polygon
			(pts
				(arc
					(start 317.149988 -385.99999)
					(mid 316.442883 -385.707097)
					(end 316.14999 -384.999992)
				)
				(arc
					(start 316.14999 -383.29997)
					(mid 315.857097 -382.592865)
					(end 315.149992 -382.299972)
				)
				(arc
					(start 308.649878 -382.299972)
					(mid 307.942773 -382.592865)
					(end 307.64988 -383.29997)
				)
				(arc
					(start 307.64988 -384.999992)
					(mid 307.356987 -385.707097)
					(end 306.649882 -385.99999)
				)
				(xy 298.200064 -385.99999) (xy 298.200064 -326.799956) (xy 491.450122 -326.799956)
				(arc
					(start 491.450122 -370.000022)
					(mid 491.157229 -370.707127)
					(end 490.450124 -371.00002)
				)
				(arc
					(start 489.450126 -371.00002)
					(mid 488.742856 -371.292823)
					(end 488.449874 -372.000018)
				)
				(arc
					(start 488.449874 -384.999992)
					(mid 488.156981 -385.707097)
					(end 487.449876 -385.99999)
				)
				(arc
					(start 474.749876 -385.99999)
					(mid 474.042771 -385.707097)
					(end 473.749878 -384.999992)
				)
				(arc
					(start 473.749878 -383.29997)
					(mid 473.456985 -382.592865)
					(end 472.74988 -382.299972)
				)
				(arc
					(start 466.25002 -382.299972)
					(mid 465.542915 -382.592865)
					(end 465.250022 -383.29997)
				)
				(arc
					(start 465.250022 -384.999992)
					(mid 464.957129 -385.707097)
					(end 464.250024 -385.99999)
				)
				(arc
					(start 418.69995 -385.99999)
					(mid 417.992845 -385.707097)
					(end 417.699952 -384.999992)
				)
				(arc
					(start 417.699952 -381)
					(mid 417.407059 -380.292895)
					(end 416.699954 -380.000002)
				)
				(xy 417.699952 -380.000002) (xy 417.699952 -370.000022) (xy 363.70006 -370.000022) (xy 363.70006 -380.000002)
				(arc
					(start 364.700058 -380.000002)
					(mid 363.992953 -380.292895)
					(end 363.70006 -381)
				)
				(arc
					(start 363.70006 -384.999992)
					(mid 363.407167 -385.707097)
					(end 362.700062 -385.99999)
				)
			)
		)
	)
	(zone
		(net "P12V_HDD29")
		(layer "F.Cu")
		(hatch none 0.5)
		(connect_pads
			(clearance 0.5)
		)
		(min_thickness 0.25)
		(fill yes
			(thermal_gap 0.5)
			(thermal_bridge_width 0.5)
			(island_removal_mode 0)
		)
		(polygon
			(pts
				(xy 169.799 -26.035) (xy 169.545 -26.289) (xy 169.545 -27.813) (xy 171.958 -30.226) (xy 171.958 -33.782)
				(xy 172.72 -34.544) (xy 172.72 -37.465) (xy 180.467 -45.212) (xy 188.976 -45.212) (xy 189.103 -45.085)
				(xy 189.103 -43.307) (xy 188.976 -43.18) (xy 183.007 -43.18) (xy 182.372 -42.545) (xy 180.721 -42.545)
				(xy 176.403 -38.227) (xy 176.403 -34.671) (xy 174.752 -33.02) (xy 174.752 -26.289) (xy 174.498 -26.035)
			)
		)
		(polygon
			(pts
				(xy 182.5244 -44.2214) (xy 182.3212 -44.2214) (xy 182.3212 -44.4246) (xy 182.5244 -44.4246)
			)
		)
		(polygon
			(pts
				(xy 181.6608 -44.2214) (xy 181.4576 -44.2214) (xy 181.4576 -44.4246) (xy 181.6608 -44.4246)
			)
		)
	)
	(zone
		(net "GND")
		(layer "F.Cu")
		(hatch none 0.5)
		(connect_pads
			(clearance 0.5)
		)
		(min_thickness 0.25)
		(fill yes
			(thermal_gap 0.5)
			(thermal_bridge_width 0.5)
			(island_removal_mode 0)
		)
		(polygon
			(pts
				(xy 262.581898 -93.74124) (xy 260.731 -95.592138) (xy 259.029708 -95.592138) (xy 258.731766 -95.89008)
				(xy 258.731766 -97.386394) (xy 260.20776 -98.862388) (xy 266.16279 -98.862388) (xy 266.984226 -98.040952)
				(xy 266.984226 -94.742254) (xy 265.983212 -93.74124)
			)
		)
	)
	(zone
		(layer "F.Cu")
		(hatch none 0.5)
		(connect_pads
			(clearance 0)
		)
		(min_thickness 0.25)
		(keepout
			(tracks allowed)
			(vias allowed)
			(pads allowed)
			(copperpour allowed)
			(footprints not_allowed)
		)
		(placement
			(enabled no)
			(sheetname "")
		)
		(fill
			(thermal_gap 0.5)
			(thermal_bridge_width 0.5)
			(island_removal_mode 0)
		)
		(polygon
			(pts
				(xy 126.299976 -370.000022) (xy 72.300084 -370.000022) (xy 72.300084 -380.000002) (xy 126.299976 -380.000002)
			)
		)
	)
	(zone
		(net "P5V_B_2")
		(layer "F.Cu")
		(hatch none 0.5)
		(connect_pads
			(clearance 0.5)
		)
		(min_thickness 0.25)
		(fill yes
			(thermal_gap 0.5)
			(thermal_bridge_width 0.5)
			(island_removal_mode 0)
		)
		(polygon
			(pts
				(xy 176.149 -136.779) (xy 175.895 -137.033) (xy 175.895 -139.319) (xy 176.149 -139.573) (xy 180.848 -139.573)
				(xy 181.102 -139.319) (xy 181.102 -137.033) (xy 180.848 -136.779)
			)
		)
	)
	(zone
		(net "5V_PRE_12")
		(layer "F.Cu")
		(hatch none 0.5)
		(connect_pads
			(clearance 0.5)
		)
		(min_thickness 0.25)
		(fill yes
			(thermal_gap 0.5)
			(thermal_bridge_width 0.5)
			(island_removal_mode 0)
		)
		(polygon
			(pts
				(xy 22.958552 -145.962624) (xy 22.806152 -146.115024) (xy 22.806152 -147.512024) (xy 23.390352 -148.096224)
				(xy 24.660352 -148.096224) (xy 26.743152 -150.179024) (xy 31.188152 -150.179024) (xy 31.315152 -150.052024)
				(xy 31.315152 -149.290024) (xy 31.188152 -149.163024) (xy 28.165552 -149.163024) (xy 24.965152 -145.962624)
			)
		)
	)
	(zone
		(layer "F.Cu")
		(hatch none 0.5)
		(connect_pads
			(clearance 0)
		)
		(min_thickness 0.25)
		(keepout
			(tracks allowed)
			(vias allowed)
			(pads allowed)
			(copperpour allowed)
			(footprints not_allowed)
		)
		(placement
			(enabled no)
			(sheetname "")
		)
		(fill
			(thermal_gap 0.5)
			(thermal_bridge_width 0.5)
			(island_removal_mode 0)
		)
		(polygon
			(pts
				(xy 265.020044 -193.799968) (xy 257.400044 -193.799968) (xy 257.400044 -203.170028) (xy 265.020044 -203.170028)
			)
		)
	)
	(zone
		(net "P5V_B_3")
		(layer "F.Cu")
		(hatch none 0.5)
		(connect_pads
			(clearance 0.5)
		)
		(min_thickness 0.25)
		(fill yes
			(thermal_gap 0.5)
			(thermal_bridge_width 0.5)
			(island_removal_mode 0)
		)
		(polygon
			(pts
				(xy 368.3 -251.333) (xy 368.046 -251.587) (xy 368.046 -256.286) (xy 368.3 -256.54) (xy 370.586 -256.54)
				(xy 370.84 -256.286) (xy 370.84 -251.587) (xy 370.586 -251.333)
			)
		)
	)
	(zone
		(net "5V_PRE_28")
		(layer "F.Cu")
		(hatch none 0.5)
		(connect_pads
			(clearance 0.5)
		)
		(min_thickness 0.25)
		(fill yes
			(thermal_gap 0.5)
			(thermal_bridge_width 0.5)
			(island_removal_mode 0)
		)
		(polygon
			(pts
				(xy 149.158452 -30.9626) (xy 149.006052 -31.115) (xy 149.006052 -32.512) (xy 149.590252 -33.0962)
				(xy 150.860252 -33.0962) (xy 152.943052 -35.179) (xy 157.388052 -35.179) (xy 157.515052 -35.052)
				(xy 157.515052 -34.29) (xy 157.388052 -34.163) (xy 154.365452 -34.163) (xy 151.165052 -30.9626)
			)
		)
	)
	(zone
		(net "12V_PRE_15")
		(layer "F.Cu")
		(hatch none 0.5)
		(connect_pads
			(clearance 0.5)
		)
		(min_thickness 0.25)
		(fill yes
			(thermal_gap 0.5)
			(thermal_bridge_width 0.5)
			(island_removal_mode 0)
		)
		(polygon
			(pts
				(xy 114.3 -149.733) (xy 114.173 -149.86) (xy 114.173 -151.384) (xy 115.57 -152.781) (xy 116.967 -152.781)
				(xy 121.92 -157.734) (xy 125.857 -157.734) (xy 125.984 -157.607) (xy 125.984 -156.845) (xy 125.857 -156.718)
				(xy 122.555 -156.718) (xy 115.57 -149.733)
			)
		)
	)
	(zone
		(net "P12V_B")
		(layer "F.Cu")
		(hatch none 0.5)
		(connect_pads
			(clearance 0.5)
		)
		(min_thickness 0.25)
		(fill yes
			(thermal_gap 0.5)
			(thermal_bridge_width 0.5)
			(island_removal_mode 0)
		)
		(polygon
			(pts
				(xy 108.839 -255.143) (xy 107.823 -256.159) (xy 107.188 -256.159) (xy 106.807 -256.54) (xy 106.807 -259.08)
				(xy 107.061 -259.334) (xy 110.363 -259.334) (xy 110.617 -259.08) (xy 110.617 -256.794) (xy 109.982 -256.159)
				(xy 109.601 -256.159) (xy 109.347 -255.905) (xy 109.347 -255.27) (xy 109.22 -255.143)
			)
		)
		(polygon
			(pts
				(xy 108.8136 -255.7272) (xy 108.6104 -255.7272) (xy 108.6104 -255.9304) (xy 108.8136 -255.9304)
			)
		)
	)
	(zone
		(net "P12V_HDD25")
		(layer "F.Cu")
		(hatch none 0.5)
		(connect_pads
			(clearance 0.5)
		)
		(min_thickness 0.25)
		(fill yes
			(thermal_gap 0.5)
			(thermal_bridge_width 0.5)
			(island_removal_mode 0)
		)
		(polygon
			(pts
				(xy 43.561 -26.035) (xy 43.307 -26.289) (xy 43.307 -27.813) (xy 45.72 -30.226) (xy 45.72 -33.782)
				(xy 46.482 -34.544) (xy 46.482 -37.465) (xy 54.229 -45.212) (xy 62.738 -45.212) (xy 62.865 -45.085)
				(xy 62.865 -43.307) (xy 62.738 -43.18) (xy 56.769 -43.18) (xy 56.134 -42.545) (xy 54.483 -42.545)
				(xy 50.165 -38.227) (xy 50.165 -34.79927) (xy 48.514 -33.14827) (xy 48.514 -26.289) (xy 48.26 -26.035)
			)
		)
		(polygon
			(pts
				(xy 56.2864 -44.2214) (xy 56.0832 -44.2214) (xy 56.0832 -44.4246) (xy 56.2864 -44.4246)
			)
		)
		(polygon
			(pts
				(xy 55.4228 -44.2214) (xy 55.2196 -44.2214) (xy 55.2196 -44.4246) (xy 55.4228 -44.4246)
			)
		)
	)
	(zone
		(net "GPIO_VCC_U10")
		(layer "F.Cu")
		(hatch none 0.5)
		(connect_pads
			(clearance 0.5)
		)
		(min_thickness 0.25)
		(fill yes
			(thermal_gap 0.5)
			(thermal_bridge_width 0.5)
			(island_removal_mode 0)
		)
		(polygon
			(pts
				(xy 239.70361 -223.4184) (xy 239.409732 -223.712278) (xy 239.409732 -229.449376) (xy 240.08461 -230.124254)
				(xy 241.41176 -230.124254) (xy 241.791998 -229.744016) (xy 241.791998 -226.497896) (xy 240.6396 -225.345498)
				(xy 240.6396 -223.65081) (xy 240.40719 -223.4184)
			)
		)
		(polygon
			(pts
				(xy 240.2078 -228.3968) (xy 240.0046 -228.3968) (xy 240.0046 -228.6) (xy 240.2078 -228.6)
			)
		)
		(polygon
			(pts
				(xy 240.2078 -227.838) (xy 240.0046 -227.838) (xy 240.0046 -228.0412) (xy 240.2078 -228.0412)
			)
		)
		(polygon
			(pts
				(xy 240.5126 -227.4062) (xy 240.3094 -227.4062) (xy 240.3094 -227.6094) (xy 240.5126 -227.6094)
			)
		)
		(polygon
			(pts
				(xy 240.5126 -226.5426) (xy 240.3094 -226.5426) (xy 240.3094 -226.7458) (xy 240.5126 -226.7458)
			)
		)
		(polygon
			(pts
				(xy 240.1316 -226.2632) (xy 239.9284 -226.2632) (xy 239.9284 -226.4664) (xy 240.1316 -226.4664)
			)
		)
		(polygon
			(pts
				(xy 240.1316 -225.6536) (xy 239.9284 -225.6536) (xy 239.9284 -225.8568) (xy 240.1316 -225.8568)
			)
		)
	)
	(zone
		(net "5V_PRE_18")
		(layer "F.Cu")
		(hatch none 0.5)
		(connect_pads
			(clearance 0.5)
		)
		(min_thickness 0.25)
		(fill yes
			(thermal_gap 0.5)
			(thermal_bridge_width 0.5)
			(island_removal_mode 0)
		)
		(polygon
			(pts
				(xy 329.438 -146.05) (xy 329.184 -146.304) (xy 329.184 -148.844) (xy 328.803 -149.225) (xy 326.263 -149.225)
				(xy 326.009 -149.479) (xy 326.009 -149.86) (xy 326.263 -150.114) (xy 329.565 -150.114) (xy 330.835 -148.844)
				(xy 330.835 -146.304) (xy 330.581 -146.05)
			)
		)
	)
	(zone
		(net "5V_PRE_29")
		(layer "F.Cu")
		(hatch none 0.5)
		(connect_pads
			(clearance 0.5)
		)
		(min_thickness 0.25)
		(fill yes
			(thermal_gap 0.5)
			(thermal_bridge_width 0.5)
			(island_removal_mode 0)
		)
		(polygon
			(pts
				(xy 180.708554 -30.9626) (xy 180.556154 -31.115) (xy 180.556154 -32.512) (xy 181.140354 -33.0962)
				(xy 182.410354 -33.0962) (xy 184.493154 -35.179) (xy 188.938154 -35.179) (xy 189.065154 -35.052)
				(xy 189.065154 -34.29) (xy 188.938154 -34.163) (xy 185.915554 -34.163) (xy 182.715154 -30.9626)
			)
		)
	)
	(zone
		(net "P12V_IN")
		(layer "F.Cu")
		(hatch none 0.5)
		(connect_pads
			(clearance 0.5)
		)
		(min_thickness 0.25)
		(fill yes
			(thermal_gap 0.5)
			(thermal_bridge_width 0.5)
			(island_removal_mode 0)
		)
		(polygon
			(pts
				(xy 39.116 -312.166) (xy 33.782 -317.5) (xy 33.782 -351.917) (xy 34.036 -352.171) (xy 43.071542 -352.171)
				(xy 47.498 -356.597458) (xy 47.498 -358.648) (xy 48.387 -359.537) (xy 48.387 -360.045) (xy 48.006 -360.426)
				(xy 45.593 -360.426) (xy 45.339 -360.68) (xy 45.339 -363.982) (xy 45.72 -364.363) (xy 46.609 -364.363)
				(xy 48.768 -362.204) (xy 52.07 -362.204) (xy 52.451 -361.823) (xy 52.451 -329.612498) (xy 55.924196 -326.139302)
				(xy 203.41082 -326.139302) (xy 204.761846 -327.490328) (xy 204.761846 -334.363568) (xy 204.916278 -334.518)
				(xy 206.629 -334.518) (xy 207.01 -334.899) (xy 207.01 -336.931) (xy 207.264 -337.185) (xy 209.169 -337.185)
				(xy 209.677 -337.693) (xy 209.677 -339.344) (xy 209.169 -339.852) (xy 205.664308 -339.852) (xy 204.863954 -340.652354)
				(xy 204.863954 -345.17203) (xy 204.957172 -345.265248) (xy 206.708248 -345.265248) (xy 207.01 -345.567)
				(xy 207.01 -346.71) (xy 207.391 -347.091) (xy 209.296 -347.091) (xy 209.677 -347.472) (xy 209.677 -349.123)
				(xy 209.169 -349.631) (xy 207.264 -349.631) (xy 206.375 -350.52) (xy 205.74 -350.52) (xy 204.860652 -351.399348)
				(xy 204.860652 -354.764848) (xy 205.01483 -354.919026) (xy 210.230974 -354.919026) (xy 212.5472 -352.6028)
				(xy 241.8842 -352.6028) (xy 242.1382 -352.3488) (xy 242.1382 -346.4814) (xy 241.7826 -346.1258)
				(xy 239.4712 -346.1258) (xy 238.7346 -345.3892) (xy 238.7346 -343.7128) (xy 239.1156 -343.3318)
				(xy 241.9858 -343.3318) (xy 241.9858 -337.7692) (xy 242.443 -337.312) (xy 244.6274 -337.312) (xy 245.3386 -336.6008)
				(xy 245.3386 -327.875646) (xy 247.348248 -325.865998) (xy 329.32751 -325.865998) (xy 330.372466 -326.910954)
				(xy 330.372466 -349.84055) (xy 336.867754 -356.335838) (xy 336.867754 -358.184196) (xy 337.8708 -359.187242)
				(xy 337.8708 -360.172) (xy 337.654646 -360.388154) (xy 335.96961 -360.388154) (xy 335.905856 -360.451908)
				(xy 334.858106 -360.451908) (xy 334.7466 -360.563414) (xy 334.7466 -363.9312) (xy 334.7974 -363.982)
				(xy 337.7438 -363.982) (xy 337.8708 -363.855) (xy 337.8708 -362.331) (xy 339.0392 -361.1626) (xy 341.249 -361.1626)
				(xy 341.757 -360.6546) (xy 341.757 -357.0478) (xy 342.392 -356.4128) (xy 342.392 -326.918828) (xy 343.49309 -325.817738)
				(xy 427.779942 -325.817738) (xy 429.612552 -327.650348) (xy 429.612552 -350.079818) (xy 435.483 -355.950266)
				(xy 435.483 -358.521) (xy 436.4736 -359.5116) (xy 436.4736 -360.0704) (xy 436.1688 -360.3752) (xy 434.213 -360.3752)
				(xy 434.1368 -360.4514) (xy 433.5018 -360.4514) (xy 433.451 -360.5022) (xy 433.451 -361.188) (xy 433.578 -361.315)
				(xy 439.166 -361.315) (xy 440.309 -360.172) (xy 440.309 -357.124) (xy 442.33592 -355.09708) (xy 442.33592 -318.63792)
				(xy 437.515 -313.817) (xy 159.131 -313.817) (xy 157.48 -312.166)
			)
		)
		(polygon
			(pts
				(xy 434.118004 -360.9086) (xy 433.914804 -360.9086) (xy 433.914804 -361.1118) (xy 434.118004 -361.1118)
			)
		)
		(polygon
			(pts
				(xy 335.534 -360.9086) (xy 335.3308 -360.9086) (xy 335.3308 -361.1118) (xy 335.534 -361.1118)
			)
		)
		(polygon
			(pts
				(xy 46.195996 -360.9086) (xy 45.992796 -360.9086) (xy 45.992796 -361.1118) (xy 46.195996 -361.1118)
			)
		)
		(polygon
			(pts
				(xy 435.286404 -360.8959) (xy 435.083204 -360.8959) (xy 435.083204 -361.0991) (xy 435.286404 -361.0991)
			)
		)
		(polygon
			(pts
				(xy 434.676804 -360.8959) (xy 434.473604 -360.8959) (xy 434.473604 -361.0991) (xy 434.676804 -361.0991)
			)
		)
		(polygon
			(pts
				(xy 336.7024 -360.8959) (xy 336.4992 -360.8959) (xy 336.4992 -361.0991) (xy 336.7024 -361.0991)
			)
		)
		(polygon
			(pts
				(xy 336.0928 -360.8959) (xy 335.8896 -360.8959) (xy 335.8896 -361.0991) (xy 336.0928 -361.0991)
			)
		)
		(polygon
			(pts
				(xy 47.364396 -360.8959) (xy 47.161196 -360.8959) (xy 47.161196 -361.0991) (xy 47.364396 -361.0991)
			)
		)
		(polygon
			(pts
				(xy 46.754796 -360.8959) (xy 46.551596 -360.8959) (xy 46.551596 -361.0991) (xy 46.754796 -361.0991)
			)
		)
		(polygon
			(pts
				(xy 48.215296 -358.013) (xy 48.012096 -358.013) (xy 48.012096 -358.2162) (xy 48.215296 -358.2162)
			)
		)
		(polygon
			(pts
				(xy 436.137304 -357.9876) (xy 435.934104 -357.9876) (xy 435.934104 -358.1908) (xy 436.137304 -358.1908)
			)
		)
		(polygon
			(pts
				(xy 337.5279 -357.9114) (xy 337.3247 -357.9114) (xy 337.3247 -358.1146) (xy 337.5279 -358.1146)
			)
		)
		(polygon
			(pts
				(xy 48.215296 -357.4542) (xy 48.012096 -357.4542) (xy 48.012096 -357.6574) (xy 48.215296 -357.6574)
			)
		)
		(polygon
			(pts
				(xy 436.137304 -357.4288) (xy 435.934104 -357.4288) (xy 435.934104 -357.632) (xy 436.137304 -357.632)
			)
		)
		(polygon
			(pts
				(xy 337.5279 -357.3526) (xy 337.3247 -357.3526) (xy 337.3247 -357.5558) (xy 337.5279 -357.5558)
			)
		)
		(polygon
			(pts
				(xy 221.344998 -351.898966) (xy 221.141798 -351.898966) (xy 221.141798 -352.102166) (xy 221.344998 -352.102166)
			)
		)
		(polygon
			(pts
				(xy 220.786198 -351.898966) (xy 220.582998 -351.898966) (xy 220.582998 -352.102166) (xy 220.786198 -352.102166)
			)
		)
		(polygon
			(pts
				(xy 241.792506 -351.892362) (xy 241.589306 -351.892362) (xy 241.589306 -352.095562) (xy 241.792506 -352.095562)
			)
		)
		(polygon
			(pts
				(xy 241.182906 -351.892362) (xy 240.979706 -351.892362) (xy 240.979706 -352.095562) (xy 241.182906 -352.095562)
			)
		)
	)
	(zone
		(net "5V_PRE_9")
		(layer "F.Cu")
		(hatch none 0.5)
		(connect_pads
			(clearance 0.5)
		)
		(min_thickness 0.25)
		(fill yes
			(thermal_gap 0.5)
			(thermal_bridge_width 0.5)
			(island_removal_mode 0)
		)
		(polygon
			(pts
				(xy 424.053 -260.985) (xy 423.799 -261.239) (xy 423.799 -263.779) (xy 423.418 -264.16) (xy 420.878 -264.16)
				(xy 420.624 -264.414) (xy 420.624 -264.795) (xy 420.878 -265.049) (xy 424.18 -265.049) (xy 425.45 -263.779)
				(xy 425.45 -261.239) (xy 425.196 -260.985)
			)
		)
	)
	(zone
		(layer "F.Cu")
		(hatch none 0.5)
		(connect_pads
			(clearance 0)
		)
		(min_thickness 0.25)
		(keepout
			(tracks not_allowed)
			(vias allowed)
			(pads allowed)
			(copperpour not_allowed)
			(footprints allowed)
		)
		(placement
			(enabled no)
			(sheetname "")
		)
		(fill
			(thermal_gap 0.5)
			(thermal_bridge_width 0.5)
			(island_removal_mode 0)
		)
		(polygon
			(pts
				(arc
					(start 96.094042 -18.11528)
					(mid 95.609029 -17.629886)
					(end 95.123762 -18.115026)
				)
				(xy 95.123762 -18.527776)
				(arc
					(start 95.481902 -18.527776)
					(mid 95.517823 -18.512897)
					(end 95.532702 -18.476976)
				)
				(arc
					(start 95.532702 -18.37055)
					(mid 95.608902 -17.848382)
					(end 95.685102 -18.37055)
				)
				(xy 95.685102 -18.508472)
				(arc
					(start 95.682054 -18.51152)
					(mid 95.625523 -18.620597)
					(end 95.516446 -18.677128)
				)
				(xy 95.513398 -18.680176) (xy 95.123762 -18.680176) (xy 95.123762 -18.819876) (xy 95.513398 -18.819876)
				(arc
					(start 95.516446 -18.822924)
					(mid 95.625523 -18.879455)
					(end 95.682054 -18.988532)
				)
				(xy 95.685102 -18.99158)
				(arc
					(start 95.685102 -19.129502)
					(mid 95.608902 -19.65167)
					(end 95.532702 -19.129502)
				)
				(arc
					(start 95.532702 -19.023076)
					(mid 95.517823 -18.987155)
					(end 95.481902 -18.972276)
				)
				(xy 95.123762 -18.972276)
				(arc
					(start 95.123762 -19.385026)
					(mid 95.608902 -19.870166)
					(end 96.094042 -19.385026)
				)
			)
		)
	)
	(zone
		(net "GND")
		(layer "F.Cu")
		(hatch none 0.5)
		(connect_pads
			(clearance 0.5)
		)
		(min_thickness 0.25)
		(fill yes
			(thermal_gap 0.5)
			(thermal_bridge_width 0.5)
			(island_removal_mode 0)
		)
		(polygon
			(pts
				(xy 43.437556 -173.43501) (xy 43.117262 -173.755304)
				(arc
					(start 43.117262 -174.195232)
					(mid 43.250203 -174.489351)
					(end 43.37431 -174.787306)
				)
				(xy 43.767756 -175.180752)
				(arc
					(start 44.62272 -175.180752)
					(mid 45.752191 -174.578536)
					(end 47.015146 -174.370492)
				)
				(arc
					(start 49.301654 -174.370492)
					(mid 50.743426 -174.64395)
					(end 51.98491 -175.42637)
				)
				(xy 54.093618 -175.42637) (xy 54.093618 -185.373518) (xy 53.788056 -185.373518)
				(arc
					(start 53.788056 -203.912978)
					(mid 53.991391 -205.194662)
					(end 53.788056 -206.476346)
				)
				(xy 53.788056 -209.294476) (xy 54.027324 -209.294476) (xy 54.027324 -216.764108) (xy 56.731408 -219.468192)
				(xy 67.315334 -219.468192) (xy 68.526406 -218.25712)
				(arc
					(start 68.526406 -214.682578)
					(mid 68.639203 -213.737951)
					(end 68.97116 -212.846412)
				)
				(arc
					(start 68.97116 -209.793078)
					(mid 69.270851 -208.286342)
					(end 70.12432 -207.008984)
				)
				(arc
					(start 70.98538 -206.147924)
					(mid 71.700696 -205.145824)
					(end 72.679052 -204.398372)
				)
				(arc
					(start 72.679052 -180.558186)
					(mid 72.978743 -179.05145)
					(end 73.832212 -177.774092)
				)
				(xy 76.156312 -175.449992) (xy 76.156312 -175.42637) (xy 76.179934 -175.42637)
				(arc
					(start 76.311252 -175.295052)
					(mid 77.588619 -174.441606)
					(end 79.095346 -174.141892)
				)
				(arc
					(start 80.848454 -174.141892)
					(mid 82.35519 -174.441583)
					(end 83.632548 -175.295052)
				)
				(xy 83.749896 -175.4124) (xy 85.42782 -175.4124) (xy 85.97646 -174.86376) (xy 85.97646 -173.830742)
				(xy 85.580728 -173.43501)
			)
		)
	)
	(zone
		(layer "F.Cu")
		(hatch none 0.5)
		(connect_pads
			(clearance 0)
		)
		(min_thickness 0.25)
		(keepout
			(tracks allowed)
			(vias allowed)
			(pads allowed)
			(copperpour allowed)
			(footprints allowed)
		)
		(placement
			(enabled no)
			(sheetname "")
		)
		(fill
			(thermal_gap 0.5)
			(thermal_bridge_width 0.5)
			(island_removal_mode 0)
		)
		(polygon
			(pts
				(xy 284.189424 -351.205546) (xy 284.189424 -349.579946) (xy 286.704024 -349.579946) (xy 286.704024 -351.205546)
			)
		)
	)
	(zone
		(net "P12V_B")
		(layer "F.Cu")
		(hatch none 0.5)
		(connect_pads
			(clearance 0.5)
		)
		(min_thickness 0.25)
		(fill yes
			(thermal_gap 0.5)
			(thermal_bridge_width 0.5)
			(island_removal_mode 0)
		)
		(polygon
			(pts
				(xy 14.224 -25.146) (xy 13.208 -26.162) (xy 12.573 -26.162) (xy 12.192 -26.543) (xy 12.192 -29.083)
				(xy 12.446 -29.337) (xy 15.748 -29.337) (xy 16.002 -29.083) (xy 16.002 -27.08275) (xy 15.08125 -26.162)
				(xy 14.96314 -26.162) (xy 14.704822 -25.903682) (xy 14.704822 -25.245822) (xy 14.605 -25.146)
			)
		)
		(polygon
			(pts
				(xy 14.1986 -25.7302) (xy 13.9954 -25.7302) (xy 13.9954 -25.9334) (xy 14.1986 -25.9334)
			)
		)
	)
	(zone
		(layer "F.Cu")
		(hatch none 0.5)
		(connect_pads
			(clearance 0)
		)
		(min_thickness 0.25)
		(keepout
			(tracks allowed)
			(vias allowed)
			(pads allowed)
			(copperpour allowed)
			(footprints allowed)
		)
		(placement
			(enabled no)
			(sheetname "")
		)
		(fill
			(thermal_gap 0.5)
			(thermal_bridge_width 0.5)
			(island_removal_mode 0)
		)
		(polygon
			(pts
				(xy 174.371 -367.0554) (xy 174.371 -365.4298) (xy 175.1584 -365.4298) (xy 175.1584 -367.0554)
			)
		)
	)
	(zone
		(layer "F.Cu")
		(hatch none 0.5)
		(connect_pads
			(clearance 0)
		)
		(min_thickness 0.25)
		(keepout
			(tracks not_allowed)
			(vias allowed)
			(pads allowed)
			(copperpour not_allowed)
			(footprints allowed)
		)
		(placement
			(enabled no)
			(sheetname "")
		)
		(fill
			(thermal_gap 0.5)
			(thermal_bridge_width 0.5)
			(island_removal_mode 0)
		)
		(polygon
			(pts
				(arc
					(start 322.6816 -131.951984)
					(mid 322.19646 -132.437124)
					(end 322.6816 -132.922264)
				)
				(xy 323.09435 -132.922264)
				(arc
					(start 323.09435 -132.61975)
					(mid 323.063179 -132.544495)
					(end 322.987924 -132.513324)
				)
				(arc
					(start 322.937124 -132.513324)
					(mid 322.414956 -132.437124)
					(end 322.937124 -132.360924)
				)
				(xy 323.01942 -132.360924)
				(arc
					(start 323.021706 -132.36321)
					(mid 323.170891 -132.436783)
					(end 323.244464 -132.585968)
				)
				(xy 323.24675 -132.588254) (xy 323.24675 -132.922264) (xy 323.38645 -132.922264) (xy 323.38645 -132.588254)
				(arc
					(start 323.388736 -132.585968)
					(mid 323.462309 -132.436783)
					(end 323.611494 -132.36321)
				)
				(xy 323.61378 -132.360924)
				(arc
					(start 323.696076 -132.360924)
					(mid 324.218244 -132.437124)
					(end 323.696076 -132.513324)
				)
				(arc
					(start 323.645276 -132.513324)
					(mid 323.570021 -132.544495)
					(end 323.53885 -132.61975)
				)
				(xy 323.53885 -132.922264)
				(arc
					(start 323.951346 -132.922264)
					(mid 324.43674 -132.437251)
					(end 323.9516 -131.951984)
				)
			)
		)
	)
	(zone
		(net "GND")
		(layer "F.Cu")
		(hatch none 0.5)
		(connect_pads
			(clearance 0.5)
		)
		(min_thickness 0.25)
		(fill yes
			(thermal_gap 0.5)
			(thermal_bridge_width 0.5)
			(island_removal_mode 0)
		)
		(polygon
			(pts
				(xy 45.126148 -109.649006) (xy 44.618148 -110.157006) (xy 44.618148 -115.244118) (xy 45.41393 -116.0399)
				(xy 47.874936 -116.0399) (xy 48.063658 -115.851178) (xy 48.063658 -109.826806) (xy 47.885858 -109.649006)
			)
		)
	)
	(zone
		(layer "F.Cu")
		(hatch none 0.5)
		(connect_pads
			(clearance 0)
		)
		(min_thickness 0.25)
		(keepout
			(tracks allowed)
			(vias allowed)
			(pads allowed)
			(copperpour allowed)
			(footprints not_allowed)
		)
		(placement
			(enabled no)
			(sheetname "")
		)
		(fill
			(thermal_gap 0.5)
			(thermal_bridge_width 0.5)
			(island_removal_mode 0)
		)
		(polygon
			(pts
				(xy 256.199894 -165.800024) (xy 256.199894 -191.799972) (xy 231.199944 -191.799972) (xy 231.199944 -165.800024)
			)
		)
	)
	(zone
		(layer "F.Cu")
		(hatch none 0.5)
		(connect_pads
			(clearance 0)
		)
		(min_thickness 0.25)
		(keepout
			(tracks allowed)
			(vias allowed)
			(pads allowed)
			(copperpour allowed)
			(footprints allowed)
		)
		(placement
			(enabled no)
			(sheetname "")
		)
		(fill
			(thermal_gap 0.5)
			(thermal_bridge_width 0.5)
			(island_removal_mode 0)
		)
		(polygon
			(pts
				(xy 94.6404 -249.6058) (xy 95.758 -249.6058) (xy 95.8596 -249.5042) (xy 95.8596 -248.0564) (xy 95.5548 -247.7516)
				(xy 94.6658 -247.7516) (xy 94.3356 -248.0818) (xy 94.3356 -249.301)
			)
		)
	)
	(zone
		(layer "F.Cu")
		(hatch none 0.5)
		(connect_pads
			(clearance 0)
		)
		(min_thickness 0.25)
		(keepout
			(tracks allowed)
			(vias allowed)
			(pads allowed)
			(copperpour allowed)
			(footprints allowed)
		)
		(placement
			(enabled no)
			(sheetname "")
		)
		(fill
			(thermal_gap 0.5)
			(thermal_bridge_width 0.5)
			(island_removal_mode 0)
		)
		(polygon
			(pts
				(xy 443.954662 -364.782354) (xy 443.954662 -362.631482) (xy 446.376298 -362.631482) (xy 446.376298 -364.782354)
			)
		)
	)
	(zone
		(net "P12V_B")
		(layer "F.Cu")
		(hatch none 0.5)
		(connect_pads
			(clearance 0.5)
		)
		(min_thickness 0.25)
		(fill yes
			(thermal_gap 0.5)
			(thermal_bridge_width 0.5)
			(island_removal_mode 0)
		)
		(polygon
			(pts
				(xy 14.224 -140.081) (xy 13.208 -141.097) (xy 12.573 -141.097) (xy 12.192 -141.478) (xy 12.192 -144.018)
				(xy 12.446 -144.272) (xy 15.748 -144.272) (xy 16.002 -144.018) (xy 16.002 -142.032228) (xy 15.066772 -141.097)
				(xy 14.969998 -141.097) (xy 14.703298 -140.8303) (xy 14.703298 -140.179298) (xy 14.605 -140.081)
			)
		)
		(polygon
			(pts
				(xy 14.1986 -140.6652) (xy 13.9954 -140.6652) (xy 13.9954 -140.8684) (xy 14.1986 -140.8684)
			)
		)
	)
	(zone
		(layer "F.Cu")
		(hatch none 0.5)
		(connect_pads
			(clearance 0)
		)
		(min_thickness 0.25)
		(keepout
			(tracks allowed)
			(vias allowed)
			(pads allowed)
			(copperpour allowed)
			(footprints allowed)
		)
		(placement
			(enabled no)
			(sheetname "")
		)
		(fill
			(thermal_gap 0.5)
			(thermal_bridge_width 0.5)
			(island_removal_mode 0)
		)
		(polygon
			(pts
				(xy 63.0174 -19.5834) (xy 64.1096 -19.5834) (xy 64.3636 -19.3294) (xy 64.3636 -18.1864) (xy 64.0588 -17.8816)
				(xy 63.0682 -17.8816) (xy 62.8904 -18.0594) (xy 62.8904 -19.4564)
			)
		)
	)
	(zone
		(net "GND")
		(layer "F.Cu")
		(hatch none 0.5)
		(connect_pads
			(clearance 0.5)
		)
		(min_thickness 0.25)
		(fill yes
			(thermal_gap 0.5)
			(thermal_bridge_width 0.5)
			(island_removal_mode 0)
		)
		(polygon
			(pts
				(xy 135.698484 -270.3322) (xy 134.96036 -271.070324) (xy 134.96036 -280.049478) (xy 135.881872 -280.97099)
				(xy 145.203164 -280.97099) (xy 146.2278 -279.946354) (xy 146.2278 -277.85441) (xy 146.136614 -277.763224)
				(xy 145.603976 -277.763224) (xy 145.603976 -277.230586) (xy 138.70559 -270.3322)
			)
		)
	)
	(zone
		(net "12V_PRE_19")
		(layer "F.Cu")
		(hatch none 0.5)
		(connect_pads
			(clearance 0.5)
		)
		(min_thickness 0.25)
		(fill yes
			(thermal_gap 0.5)
			(thermal_bridge_width 0.5)
			(island_removal_mode 0)
		)
		(polygon
			(pts
				(xy 362.57865 -154.686) (xy 360.64825 -156.6164) (xy 357.65105 -156.6164) (xy 357.39705 -156.8704)
				(xy 357.39705 -157.5816) (xy 357.53675 -157.7213) (xy 359.82275 -157.7213) (xy 359.83545 -157.734)
				(xy 363.51845 -157.734) (xy 364.53445 -156.718) (xy 364.53445 -154.813) (xy 364.40745 -154.686)
			)
		)
	)
	(zone
		(net "GND")
		(layer "F.Cu")
		(hatch none 0.5)
		(connect_pads
			(clearance 0.5)
		)
		(min_thickness 0.25)
		(fill yes
			(thermal_gap 0.5)
			(thermal_bridge_width 0.5)
			(island_removal_mode 0)
		)
		(polygon
			(pts
				(xy 446.376806 -189.228984) (xy 445.78778 -189.81801) (xy 445.78778 -208.084166) (xy 446.203324 -208.49971)
				(xy 446.203324 -215.752172) (xy 446.806828 -216.355676) (xy 459.569058 -216.355676) (xy 460.215996 -215.708738)
				(xy 460.215996 -199.442324)
				(arc
					(start 456.385168 -195.611496)
					(mid 450.67559 -193.800002)
					(end 446.804288 -189.228984)
				)
			)
		)
	)
	(zone
		(layer "F.Cu")
		(hatch none 0.5)
		(connect_pads
			(clearance 0)
		)
		(min_thickness 0.25)
		(keepout
			(tracks allowed)
			(vias allowed)
			(pads allowed)
			(copperpour allowed)
			(footprints not_allowed)
		)
		(placement
			(enabled no)
			(sheetname "")
		)
		(fill
			(thermal_gap 0.5)
			(thermal_bridge_width 0.5)
			(island_removal_mode 0)
		)
		(polygon
			(pts
				(arc
					(start 409.150058 -23.999952)
					(mid 404.400004 -28.750006)
					(end 399.64995 -23.999952)
				)
				(arc
					(start 399.64995 -23.999952)
					(mid 404.400004 -19.249898)
					(end 409.150058 -23.999952)
				)
			)
		)
	)
	(zone
		(net "12V_PRE_17")
		(layer "F.Cu")
		(hatch none 0.5)
		(connect_pads
			(clearance 0.5)
		)
		(min_thickness 0.25)
		(fill yes
			(thermal_gap 0.5)
			(thermal_bridge_width 0.5)
			(island_removal_mode 0)
		)
		(polygon
			(pts
				(xy 177.419 -149.733) (xy 177.292 -149.86) (xy 177.292 -151.384) (xy 178.689 -152.781) (xy 180.086 -152.781)
				(xy 185.039 -157.734) (xy 188.976 -157.734) (xy 189.103 -157.607) (xy 189.103 -156.845) (xy 188.976 -156.718)
				(xy 185.674 -156.718) (xy 178.689 -149.733)
			)
		)
	)
	(zone
		(net "P5V_B_2")
		(layer "F.Cu")
		(hatch none 0.5)
		(connect_pads
			(clearance 0.5)
		)
		(min_thickness 0.25)
		(fill yes
			(thermal_gap 0.5)
			(thermal_bridge_width 0.5)
			(island_removal_mode 0)
		)
		(polygon
			(pts
				(xy 144.653 -136.779) (xy 144.399 -137.033) (xy 144.399 -139.319) (xy 144.653 -139.573) (xy 149.352 -139.573)
				(xy 149.606 -139.319) (xy 149.606 -137.033) (xy 149.352 -136.779)
			)
		)
	)
	(zone
		(layer "F.Cu")
		(hatch none 0.5)
		(connect_pads
			(clearance 0)
		)
		(min_thickness 0.25)
		(keepout
			(tracks allowed)
			(vias allowed)
			(pads allowed)
			(copperpour allowed)
			(footprints not_allowed)
		)
		(placement
			(enabled no)
			(sheetname "")
		)
		(fill
			(thermal_gap 0.5)
			(thermal_bridge_width 0.5)
			(island_removal_mode 0)
		)
		(polygon
			(pts
				(arc
					(start 39.250112 -13.999972)
					(mid 44.000166 -9.249918)
					(end 48.749966 -13.999972)
				)
				(arc
					(start 48.749966 -13.999972)
					(mid 44.000166 -18.749772)
					(end 39.250112 -13.999972)
				)
			)
		)
	)
	(zone
		(layer "F.Cu")
		(hatch none 0.5)
		(connect_pads
			(clearance 0)
		)
		(min_thickness 0.25)
		(keepout
			(tracks not_allowed)
			(vias allowed)
			(pads allowed)
			(copperpour not_allowed)
			(footprints allowed)
		)
		(placement
			(enabled no)
			(sheetname "")
		)
		(fill
			(thermal_gap 0.5)
			(thermal_bridge_width 0.5)
			(island_removal_mode 0)
		)
		(polygon
			(pts
				(arc
					(start 96.094042 -248.115328)
					(mid 95.609029 -247.629934)
					(end 95.123762 -248.115074)
				)
				(xy 95.123762 -248.527824)
				(arc
					(start 95.481902 -248.527824)
					(mid 95.517823 -248.512945)
					(end 95.532702 -248.477024)
				)
				(arc
					(start 95.532702 -248.370598)
					(mid 95.608902 -247.84843)
					(end 95.685102 -248.370598)
				)
				(xy 95.685102 -248.50852)
				(arc
					(start 95.682054 -248.511568)
					(mid 95.625523 -248.620645)
					(end 95.516446 -248.677176)
				)
				(xy 95.513398 -248.680224) (xy 95.123762 -248.680224) (xy 95.123762 -248.819924) (xy 95.513398 -248.819924)
				(arc
					(start 95.516446 -248.822972)
					(mid 95.625523 -248.879503)
					(end 95.682054 -248.98858)
				)
				(xy 95.685102 -248.991628)
				(arc
					(start 95.685102 -249.12955)
					(mid 95.608902 -249.651718)
					(end 95.532702 -249.12955)
				)
				(arc
					(start 95.532702 -249.023124)
					(mid 95.517823 -248.987203)
					(end 95.481902 -248.972324)
				)
				(xy 95.123762 -248.972324)
				(arc
					(start 95.123762 -249.385074)
					(mid 95.608902 -249.870214)
					(end 96.094042 -249.385074)
				)
			)
		)
	)
	(zone
		(layer "F.Cu")
		(hatch none 0.5)
		(connect_pads
			(clearance 0)
		)
		(min_thickness 0.25)
		(keepout
			(tracks not_allowed)
			(vias allowed)
			(pads allowed)
			(copperpour not_allowed)
			(footprints allowed)
		)
		(placement
			(enabled no)
			(sheetname "")
		)
		(fill
			(thermal_gap 0.5)
			(thermal_bridge_width 0.5)
			(island_removal_mode 0)
		)
		(polygon
			(pts
				(arc
					(start 182.79999 -94.000066)
					(mid 189.799976 -87.00008)
					(end 196.799962 -94.000066)
				)
				(arc
					(start 196.799962 -100.000054)
					(mid 189.799976 -107.00004)
					(end 182.79999 -100.000054)
				)
			)
		)
	)
	(zone
		(net "AGND_CURRENT_DPB")
		(layer "F.Cu")
		(hatch none 0.5)
		(connect_pads
			(clearance 0.5)
		)
		(min_thickness 0.25)
		(fill yes
			(thermal_gap 0.5)
			(thermal_bridge_width 0.5)
			(island_removal_mode 0)
		)
		(polygon
			(pts
				(xy 241.86134 -359.76306) (xy 241.6302 -359.9942) (xy 241.6302 -361.9754) (xy 241.812572 -362.157772)
				(xy 245.241064 -362.157772) (xy 245.385844 -362.012992) (xy 245.385844 -360.002074) (xy 245.153942 -359.770172)
				(xy 243.138452 -359.770172) (xy 243.13134 -359.76306)
			)
		)
		(polygon
			(pts
				(xy 245.043452 -361.471972) (xy 244.840252 -361.471972) (xy 244.840252 -361.675172) (xy 245.043452 -361.675172)
			)
		)
		(polygon
			(pts
				(xy 244.484652 -361.471972) (xy 244.281452 -361.471972) (xy 244.281452 -361.675172) (xy 244.484652 -361.675172)
			)
		)
		(polygon
			(pts
				(xy 244.052852 -361.040172) (xy 243.849652 -361.040172) (xy 243.849652 -361.243372) (xy 244.052852 -361.243372)
			)
		)
		(polygon
			(pts
				(xy 243.189252 -361.040172) (xy 242.986052 -361.040172) (xy 242.986052 -361.243372) (xy 243.189252 -361.243372)
			)
		)
		(polygon
			(pts
				(xy 244.052852 -360.659172) (xy 243.849652 -360.659172) (xy 243.849652 -360.862372) (xy 244.052852 -360.862372)
			)
		)
		(polygon
			(pts
				(xy 243.189252 -360.659172) (xy 242.986052 -360.659172) (xy 242.986052 -360.862372) (xy 243.189252 -360.862372)
			)
		)
		(polygon
			(pts
				(xy 245.043452 -360.227372) (xy 244.840252 -360.227372) (xy 244.840252 -360.430572) (xy 245.043452 -360.430572)
			)
		)
		(polygon
			(pts
				(xy 244.484652 -360.227372) (xy 244.281452 -360.227372) (xy 244.281452 -360.430572) (xy 244.484652 -360.430572)
			)
		)
	)
	(zone
		(layer "F.Cu")
		(hatch none 0.5)
		(connect_pads
			(clearance 0)
		)
		(min_thickness 0.25)
		(keepout
			(tracks allowed)
			(vias allowed)
			(pads allowed)
			(copperpour allowed)
			(footprints allowed)
		)
		(placement
			(enabled no)
			(sheetname "")
		)
		(fill
			(thermal_gap 0.5)
			(thermal_bridge_width 0.5)
			(island_removal_mode 0)
		)
		(polygon
			(pts
				(xy 361.437936 -249.110246) (xy 363.029246 -249.110246) (xy 363.029246 -251.018294) (xy 361.437936 -251.018294)
			)
		)
	)
	(zone
		(layer "F.Cu")
		(hatch none 0.5)
		(connect_pads
			(clearance 0)
		)
		(min_thickness 0.25)
		(keepout
			(tracks allowed)
			(vias allowed)
			(pads allowed)
			(copperpour allowed)
			(footprints allowed)
		)
		(placement
			(enabled no)
			(sheetname "")
		)
		(fill
			(thermal_gap 0.5)
			(thermal_bridge_width 0.5)
			(island_removal_mode 0)
		)
		(polygon
			(pts
				(xy 232.6005 -221.635828) (xy 232.6005 -223.735392) (xy 230.346758 -223.735392) (xy 230.346758 -221.635828)
			)
		)
	)
	(zone
		(net "P5V_B_4")
		(layer "F.Cu")
		(hatch none 0.5)
		(connect_pads
			(clearance 0.5)
		)
		(min_thickness 0.25)
		(fill yes
			(thermal_gap 0.5)
			(thermal_bridge_width 0.5)
			(island_removal_mode 0)
		)
		(polygon
			(pts
				(xy 431.419 -136.398) (xy 431.165 -136.652) (xy 431.165 -141.351) (xy 431.419 -141.605) (xy 433.705 -141.605)
				(xy 433.959 -141.351) (xy 433.959 -136.652) (xy 433.705 -136.398)
			)
		)
	)
	(zone
		(net "GND")
		(layer "F.Cu")
		(hatch none 0.5)
		(connect_pads
			(clearance 0.5)
		)
		(min_thickness 0.25)
		(fill yes
			(thermal_gap 0.5)
			(thermal_bridge_width 0.5)
			(island_removal_mode 0)
		)
		(polygon
			(pts
				(arc
					(start 198.230998 -106.77779)
					(mid 196.596595 -108.414676)
					(end 194.65163 -109.666786)
				)
				(xy 194.65163 -110.295944) (xy 197.029324 -112.673638)
				(arc
					(start 198.178674 -112.673638)
					(mid 198.758442 -112.412256)
					(end 199.371712 -112.24387)
				)
				(xy 199.603868 -112.011714) (xy 199.603868 -107.517438) (xy 198.86422 -106.77779)
			)
		)
	)
	(zone
		(layer "F.Cu")
		(hatch none 0.5)
		(connect_pads
			(clearance 0)
		)
		(min_thickness 0.25)
		(keepout
			(tracks allowed)
			(vias allowed)
			(pads allowed)
			(copperpour allowed)
			(footprints allowed)
		)
		(placement
			(enabled no)
			(sheetname "")
		)
		(fill
			(thermal_gap 0.5)
			(thermal_bridge_width 0.5)
			(island_removal_mode 0)
		)
		(polygon
			(pts
				(xy 141.605 -98.3234) (xy 140.5382 -98.3234) (xy 140.5382 -96.9772) (xy 141.605 -96.9772)
			)
		)
	)
	(zone
		(net "5V_PRE_6")
		(layer "F.Cu")
		(hatch none 0.5)
		(connect_pads
			(clearance 0.5)
		)
		(min_thickness 0.25)
		(fill yes
			(thermal_gap 0.5)
			(thermal_bridge_width 0.5)
			(island_removal_mode 0)
		)
		(polygon
			(pts
				(xy 329.438 -260.985) (xy 329.184 -261.239) (xy 329.184 -263.779) (xy 328.803 -264.16) (xy 326.263 -264.16)
				(xy 326.009 -264.414) (xy 326.009 -264.795) (xy 326.263 -265.049) (xy 329.565 -265.049) (xy 330.835 -263.779)
				(xy 330.835 -261.239) (xy 330.581 -260.985)
			)
		)
	)
	(zone
		(net "P5V_HDD13")
		(layer "F.Cu")
		(hatch none 0.5)
		(connect_pads
			(clearance 0.5)
		)
		(min_thickness 0.25)
		(fill yes
			(thermal_gap 0.5)
			(thermal_bridge_width 0.5)
			(island_removal_mode 0)
		)
		(polygon
			(pts
				(xy 51.181 -142.621) (xy 50.927 -142.875) (xy 50.927 -145.161) (xy 51.181 -145.415) (xy 51.181 -147.447)
				(xy 51.943 -148.209) (xy 51.943 -148.971) (xy 52.324 -149.352) (xy 52.705 -149.352) (xy 55.88 -152.527)
				(xy 62.738 -152.527) (xy 62.865 -152.4) (xy 62.865 -150.622) (xy 62.738 -150.495) (xy 57.658 -150.495)
				(xy 55.753 -148.59) (xy 54.864 -148.59) (xy 53.975 -147.701) (xy 53.975 -145.161) (xy 54.61 -144.526)
				(xy 54.61 -142.875) (xy 54.356 -142.621)
			)
		)
		(polygon
			(pts
				(xy 53.0098 -149.0472) (xy 52.8066 -149.0472) (xy 52.8066 -149.2504) (xy 53.0098 -149.2504)
			)
		)
		(polygon
			(pts
				(xy 53.0098 -148.1836) (xy 52.8066 -148.1836) (xy 52.8066 -148.3868) (xy 53.0098 -148.3868)
			)
		)
	)
	(zone
		(layer "F.Cu")
		(hatch none 0.5)
		(connect_pads
			(clearance 0)
		)
		(min_thickness 0.25)
		(keepout
			(tracks allowed)
			(vias allowed)
			(pads allowed)
			(copperpour allowed)
			(footprints not_allowed)
		)
		(placement
			(enabled no)
			(sheetname "")
		)
		(fill
			(thermal_gap 0.5)
			(thermal_bridge_width 0.5)
			(island_removal_mode 0)
		)
		(polygon
			(pts
				(xy 207.339946 -303.159922) (xy 199.719946 -303.159922) (xy 199.719946 -312.529982) (xy 207.339946 -312.529982)
			)
		)
	)
	(zone
		(net "5V_PRE_0")
		(layer "F.Cu")
		(hatch none 0.5)
		(connect_pads
			(clearance 0.5)
		)
		(min_thickness 0.25)
		(fill yes
			(thermal_gap 0.5)
			(thermal_bridge_width 0.5)
			(island_removal_mode 0)
		)
		(polygon
			(pts
				(xy 22.958552 -260.962648) (xy 22.806152 -261.115048) (xy 22.806152 -262.512048) (xy 23.390352 -263.096248)
				(xy 24.660352 -263.096248) (xy 26.743152 -265.179048) (xy 31.188152 -265.179048) (xy 31.315152 -265.052048)
				(xy 31.315152 -264.290048) (xy 31.188152 -264.163048) (xy 28.165552 -264.163048) (xy 24.965152 -260.962648)
			)
		)
	)
	(zone
		(net "GND")
		(layer "F.Cu")
		(hatch none 0.5)
		(connect_pads
			(clearance 0.5)
		)
		(min_thickness 0.25)
		(fill yes
			(thermal_gap 0.5)
			(thermal_bridge_width 0.5)
			(island_removal_mode 0)
		)
		(polygon
			(pts
				(xy 94.547182 -357.246428) (xy 94.265242 -357.528368) (xy 94.265242 -365.559848) (xy 94.554548 -365.849154)
				(xy 100.44684 -365.849154) (xy 100.852732 -365.443262) (xy 100.852732 -357.31831) (xy 100.78085 -357.246428)
			)
		)
	)
	(zone
		(net "P5V_HDD21")
		(layer "F.Cu")
		(hatch none 0.5)
		(connect_pads
			(clearance 0.5)
		)
		(min_thickness 0.25)
		(fill yes
			(thermal_gap 0.5)
			(thermal_bridge_width 0.5)
			(island_removal_mode 0)
		)
		(polygon
			(pts
				(xy 426.212 -137.795) (xy 425.958 -138.049) (xy 425.958 -148.844) (xy 424.307 -150.495) (xy 420.878 -150.495)
				(xy 420.624 -150.749) (xy 420.624 -152.4) (xy 420.878 -152.654) (xy 425.45 -152.654) (xy 426.085 -152.019)
				(xy 427.863 -152.019) (xy 428.371 -151.511) (xy 428.371 -138.049) (xy 428.117 -137.795)
			)
		)
		(polygon
			(pts
				(xy 424.9674 -151.6634) (xy 424.7642 -151.6634) (xy 424.7642 -151.8666) (xy 424.9674 -151.8666)
			)
		)
		(polygon
			(pts
				(xy 424.1038 -151.6634) (xy 423.9006 -151.6634) (xy 423.9006 -151.8666) (xy 424.1038 -151.8666)
			)
		)
	)
	(zone
		(net "P5V_B_2")
		(layer "F.Cu")
		(hatch none 0.5)
		(connect_pads
			(clearance 0.5)
		)
		(min_thickness 0.25)
		(fill yes
			(thermal_gap 0.5)
			(thermal_bridge_width 0.5)
			(island_removal_mode 0)
		)
		(polygon
			(pts
				(xy 176.149 -21.844) (xy 175.895 -22.098) (xy 175.895 -24.384) (xy 176.149 -24.638) (xy 180.848 -24.638)
				(xy 181.102 -24.384) (xy 181.102 -22.098) (xy 180.848 -21.844)
			)
		)
	)
	(zone
		(net "GND")
		(layer "F.Cu")
		(hatch none 0.5)
		(connect_pads
			(clearance 0.5)
		)
		(min_thickness 0.25)
		(fill yes
			(thermal_gap 0.5)
			(thermal_bridge_width 0.5)
			(island_removal_mode 0)
		)
		(polygon
			(pts
				(xy 402.311616 -81.257394) (xy 400.68754 -79.633318)
				(arc
					(start 398.179544 -79.633318)
					(mid 389.752656 -79.879681)
					(end 383.70637 -74.004678)
				)
				(xy 383.48158 -73.779888) (xy 382.911096 -73.779888) (xy 382.688084 -74.0029) (xy 382.688084 -75.504294)
				(xy 383.211324 -76.027534) (xy 383.211324 -104.265476) (xy 380.646432 -106.830368)
				(arc
					(start 378.865892 -106.830368)
					(mid 378.805408 -106.8952)
					(end 378.743464 -106.958638)
				)
				(xy 376.498104 -109.203998) (xy 376.498104 -109.902752) (xy 376.732292 -110.13694) (xy 394.856208 -110.13694)
				(arc
					(start 397.150082 -107.843066)
					(mid 397.806657 -106.850209)
					(end 398.718532 -106.085132)
				)
				(arc
					(start 398.718532 -102.909878)
					(mid 397.823687 -101.596188)
					(end 397.508984 -100.038154)
				)
				(arc
					(start 397.508984 -99.6823)
					(mid 397.621684 -98.737818)
					(end 397.953484 -97.846388)
				)
				(arc
					(start 397.953484 -94.793308)
					(mid 398.253243 -93.286406)
					(end 399.106898 -92.00896)
				)
				(arc
					(start 399.967958 -91.1479)
					(mid 400.730452 -90.09785)
					(end 401.780502 -89.335356)
				)
				(xy 402.311616 -88.804242)
			)
		)
	)
	(zone
		(layer "F.Cu")
		(hatch none 0.5)
		(connect_pads
			(clearance 0)
		)
		(min_thickness 0.25)
		(keepout
			(tracks allowed)
			(vias allowed)
			(pads allowed)
			(copperpour allowed)
			(footprints allowed)
		)
		(placement
			(enabled no)
			(sheetname "")
		)
		(fill
			(thermal_gap 0.5)
			(thermal_bridge_width 0.5)
			(island_removal_mode 0)
		)
		(polygon
			(pts
				(xy 282.51658 -351.548954) (xy 284.14218 -351.548954) (xy 284.14218 -354.063554) (xy 282.51658 -354.063554)
			)
		)
	)
	(zone
		(net "P5V_HDD9")
		(layer "F.Cu")
		(hatch none 0.5)
		(connect_pads
			(clearance 0.5)
		)
		(min_thickness 0.25)
		(fill yes
			(thermal_gap 0.5)
			(thermal_bridge_width 0.5)
			(island_removal_mode 0)
		)
		(polygon
			(pts
				(xy 426.212 -252.73) (xy 425.958 -252.984) (xy 425.958 -263.779) (xy 424.307 -265.43) (xy 420.878 -265.43)
				(xy 420.624 -265.684) (xy 420.624 -267.335) (xy 420.878 -267.589) (xy 425.45 -267.589) (xy 426.085 -266.954)
				(xy 427.863 -266.954) (xy 428.371 -266.446) (xy 428.371 -252.984) (xy 428.117 -252.73)
			)
		)
		(polygon
			(pts
				(xy 424.9674 -266.5984) (xy 424.7642 -266.5984) (xy 424.7642 -266.8016) (xy 424.9674 -266.8016)
			)
		)
		(polygon
			(pts
				(xy 424.1038 -266.5984) (xy 423.9006 -266.5984) (xy 423.9006 -266.8016) (xy 424.1038 -266.8016)
			)
		)
	)
	(zone
		(layer "F.Cu")
		(hatch none 0.5)
		(connect_pads
			(clearance 0)
		)
		(min_thickness 0.25)
		(keepout
			(tracks not_allowed)
			(vias allowed)
			(pads allowed)
			(copperpour not_allowed)
			(footprints allowed)
		)
		(placement
			(enabled no)
			(sheetname "")
		)
		(fill
			(thermal_gap 0.5)
			(thermal_bridge_width 0.5)
			(island_removal_mode 0)
		)
		(polygon
			(pts
				(arc
					(start 237.199932 -244.00002)
					(mid 244.199918 -237.000034)
					(end 251.199904 -244.00002)
				)
				(arc
					(start 251.199904 -250.000008)
					(mid 244.199918 -256.999994)
					(end 237.199932 -250.000008)
				)
			)
		)
	)
	(zone
		(layer "F.Cu")
		(hatch none 0.5)
		(connect_pads
			(clearance 0)
		)
		(min_thickness 0.25)
		(keepout
			(tracks allowed)
			(vias allowed)
			(pads allowed)
			(copperpour allowed)
			(footprints not_allowed)
		)
		(placement
			(enabled no)
			(sheetname "")
		)
		(fill
			(thermal_gap 0.5)
			(thermal_bridge_width 0.5)
			(island_removal_mode 0)
		)
		(polygon
			(pts
				(xy 191.799972 -110.000034) (xy 198.399908 -110.000034) (xy 198.399908 -194.00012) (xy 191.799972 -194.00012)
			)
		)
	)
	(zone
		(net "12V_PRE_13")
		(layer "F.Cu")
		(hatch none 0.5)
		(connect_pads
			(clearance 0.5)
		)
		(min_thickness 0.25)
		(fill yes
			(thermal_gap 0.5)
			(thermal_bridge_width 0.5)
			(island_removal_mode 0)
		)
		(polygon
			(pts
				(xy 51.181 -149.733) (xy 51.054 -149.86) (xy 51.054 -151.384) (xy 52.451 -152.781) (xy 53.848 -152.781)
				(xy 58.801 -157.734) (xy 62.738 -157.734) (xy 62.865 -157.607) (xy 62.865 -156.845) (xy 62.738 -156.718)
				(xy 59.436 -156.718) (xy 52.451 -149.733)
			)
		)
	)
	(zone
		(net "12V_PRE_28")
		(layer "F.Cu")
		(hatch none 0.5)
		(connect_pads
			(clearance 0.5)
		)
		(min_thickness 0.25)
		(fill yes
			(thermal_gap 0.5)
			(thermal_bridge_width 0.5)
			(island_removal_mode 0)
		)
		(polygon
			(pts
				(xy 145.923 -34.798) (xy 145.796 -34.925) (xy 145.796 -36.449) (xy 147.193 -37.846) (xy 148.59 -37.846)
				(xy 153.543 -42.799) (xy 157.48 -42.799) (xy 157.607 -42.672) (xy 157.607 -41.91) (xy 157.48 -41.783)
				(xy 154.178 -41.783) (xy 147.193 -34.798)
			)
		)
	)
	(zone
		(net "GND")
		(layer "F.Cu")
		(hatch none 0.5)
		(connect_pads
			(clearance 0.5)
		)
		(min_thickness 0.25)
		(fill yes
			(thermal_gap 0.5)
			(thermal_bridge_width 0.5)
			(island_removal_mode 0)
		)
		(polygon
			(pts
				(xy 104.095296 -270.3322) (xy 103.46436 -270.963136) (xy 103.46436 -280.931874) (xy 104.017826 -281.48534)
				(xy 114.010694 -281.48534) (xy 114.6048 -280.891234) (xy 114.6048 -277.85441) (xy 114.513614 -277.763224)
				(xy 114.107976 -277.763224) (xy 114.107976 -277.357586) (xy 107.08259 -270.3322)
			)
		)
	)
	(zone
		(net "5V_PRE_2")
		(layer "F.Cu")
		(hatch none 0.5)
		(connect_pads
			(clearance 0.5)
		)
		(min_thickness 0.25)
		(fill yes
			(thermal_gap 0.5)
			(thermal_bridge_width 0.5)
			(island_removal_mode 0)
		)
		(polygon
			(pts
				(xy 86.058502 -260.962648) (xy 85.906102 -261.115048) (xy 85.906102 -262.512048) (xy 86.490302 -263.096248)
				(xy 87.760302 -263.096248) (xy 89.843102 -265.179048) (xy 94.288102 -265.179048) (xy 94.415102 -265.052048)
				(xy 94.415102 -264.290048) (xy 94.288102 -264.163048) (xy 91.265502 -264.163048) (xy 88.065102 -260.962648)
			)
		)
	)
	(zone
		(layer "F.Cu")
		(hatch none 0.5)
		(connect_pads
			(clearance 0)
		)
		(min_thickness 0.25)
		(keepout
			(tracks allowed)
			(vias allowed)
			(pads allowed)
			(copperpour allowed)
			(footprints not_allowed)
		)
		(placement
			(enabled no)
			(sheetname "")
		)
		(fill
			(thermal_gap 0.5)
			(thermal_bridge_width 0.5)
			(island_removal_mode 0)
		)
		(polygon
			(pts
				(arc
					(start 48.749966 -13.999972)
					(mid 44.000166 -18.749772)
					(end 39.250112 -13.999972)
				)
				(arc
					(start 39.250112 -13.999972)
					(mid 44.000166 -9.249918)
					(end 48.749966 -13.999972)
				)
			)
		)
	)
	(zone
		(layer "F.Cu")
		(hatch none 0.5)
		(connect_pads
			(clearance 0)
		)
		(min_thickness 0.25)
		(keepout
			(tracks allowed)
			(vias allowed)
			(pads allowed)
			(copperpour allowed)
			(footprints allowed)
		)
		(placement
			(enabled no)
			(sheetname "")
		)
		(fill
			(thermal_gap 0.5)
			(thermal_bridge_width 0.5)
			(island_removal_mode 0)
		)
		(polygon
			(pts
				(xy 157.7594 -249.682) (xy 158.877 -249.682) (xy 158.9786 -249.5804) (xy 158.9786 -248.1326) (xy 158.6738 -247.8278)
				(xy 157.7848 -247.8278) (xy 157.4546 -248.158) (xy 157.4546 -249.3772)
			)
		)
	)
	(zone
		(net "GND")
		(layer "F.Cu")
		(hatch none 0.5)
		(connect_pads
			(clearance 0.5)
		)
		(min_thickness 0.25)
		(fill yes
			(thermal_gap 0.5)
			(thermal_bridge_width 0.5)
			(island_removal_mode 0)
		)
		(polygon
			(pts
				(xy 170.911266 -290.34232) (xy 170.145964 -291.107622) (xy 170.145964 -303.018952) (xy 169.746422 -303.418494)
				(xy 169.746422 -306.87264) (xy 172.880528 -310.006746) (xy 190.630048 -310.006746) (xy 192.14973 -308.487064)
				(arc
					(start 192.14973 -308.485794)
					(mid 193.020777 -305.962294)
					(end 195.263008 -304.513488)
				)
				(arc
					(start 195.263008 -304.513488)
					(mid 195.498246 -304.150425)
					(end 195.7705 -303.814226)
				)
				(xy 195.7705 -301.212758)
				(arc
					(start 195.114164 -300.556422)
					(mid 193.727596 -299.0828)
					(end 193.217038 -297.124882)
				)
				(arc
					(start 193.217038 -297.124882)
					(mid 191.816412 -295.466919)
					(end 191.46139 -293.325804)
				)
				(arc
					(start 190.828168 -292.692582)
					(mid 189.711949 -291.685086)
					(end 189.035182 -290.34232)
				)
			)
		)
	)
	(zone
		(layer "F.Cu")
		(hatch none 0.5)
		(connect_pads
			(clearance 0)
		)
		(min_thickness 0.25)
		(keepout
			(tracks not_allowed)
			(vias allowed)
			(pads allowed)
			(copperpour not_allowed)
			(footprints allowed)
		)
		(placement
			(enabled no)
			(sheetname "")
		)
		(fill
			(thermal_gap 0.5)
			(thermal_bridge_width 0.5)
			(island_removal_mode 0)
		)
		(polygon
			(pts
				(arc
					(start 34.770822 -129.419604)
					(mid 34.285809 -128.93421)
					(end 33.800542 -129.41935)
				)
				(xy 33.800542 -129.7686)
				(arc
					(start 34.126678 -129.7686)
					(mid 34.185229 -129.744347)
					(end 34.209482 -129.685796)
				)
				(arc
					(start 34.209482 -129.674874)
					(mid 34.285682 -129.152706)
					(end 34.361882 -129.674874)
				)
				(xy 34.361882 -129.717292)
				(arc
					(start 34.359342 -129.719832)
					(mid 34.292947 -129.852065)
					(end 34.160714 -129.91846)
				)
				(xy 34.158174 -129.921) (xy 33.800542 -129.921) (xy 33.800542 -130.0607) (xy 34.158174 -130.0607)
				(arc
					(start 34.160714 -130.06324)
					(mid 34.292947 -130.129635)
					(end 34.359342 -130.261868)
				)
				(xy 34.361882 -130.264408)
				(arc
					(start 34.361882 -130.306826)
					(mid 34.285682 -130.828994)
					(end 34.209482 -130.306826)
				)
				(arc
					(start 34.209482 -130.295904)
					(mid 34.185229 -130.237353)
					(end 34.126678 -130.2131)
				)
				(xy 33.800542 -130.2131)
				(arc
					(start 33.800542 -130.56235)
					(mid 34.285682 -131.04749)
					(end 34.770822 -130.56235)
				)
			)
		)
	)
	(zone
		(net "GND")
		(layer "F.Cu")
		(hatch none 0.5)
		(connect_pads
			(clearance 0.5)
		)
		(min_thickness 0.25)
		(fill yes
			(thermal_gap 0.5)
			(thermal_bridge_width 0.5)
			(island_removal_mode 0)
		)
		(polygon
			(pts
				(xy 72.110854 -40.2082) (xy 71.785226 -40.533828) (xy 71.785226 -49.22647) (xy 73.090278 -50.531522)
				(xy 82.646266 -50.531522) (xy 83.1088 -50.068988) (xy 83.1088 -47.85741) (xy 83.017614 -47.766224)
				(xy 82.484976 -47.766224) (xy 82.484976 -47.233586) (xy 75.45959 -40.2082)
			)
		)
	)
	(zone
		(net "GND")
		(layer "F.Cu")
		(hatch none 0.5)
		(connect_pads
			(clearance 0.5)
		)
		(min_thickness 0.25)
		(fill yes
			(thermal_gap 0.5)
			(thermal_bridge_width 0.5)
			(island_removal_mode 0)
		)
		(polygon
			(pts
				(xy 287.89376 -253.44755) (xy 278.674576 -253.44755) (xy 278.394668 -253.167642) (xy 278.384254 -253.167642)
				(xy 278.384254 -251.424186) (xy 278.982932 -250.825508) (xy 287.434274 -250.825508) (xy 288.047176 -251.43841)
				(xy 288.047176 -253.294134)
			)
		)
	)
	(zone
		(net "P12V_B")
		(layer "F.Cu")
		(hatch none 0.5)
		(connect_pads
			(clearance 0.5)
		)
		(min_thickness 0.25)
		(fill yes
			(thermal_gap 0.5)
			(thermal_bridge_width 0.5)
			(island_removal_mode 0)
		)
		(polygon
			(pts
				(xy 281.5844 -308.0766) (xy 281.3304 -308.3306) (xy 281.3304 -312.0136) (xy 281.5844 -312.2676)
				(xy 288.1884 -312.2676) (xy 288.4424 -312.0136) (xy 288.4424 -308.3306) (xy 288.1884 -308.0766)
			)
		)
	)
	(zone
		(net "P5V_B_4")
		(layer "F.Cu")
		(hatch none 0.5)
		(connect_pads
			(clearance 0.5)
		)
		(min_thickness 0.25)
		(fill yes
			(thermal_gap 0.5)
			(thermal_bridge_width 0.5)
			(island_removal_mode 0)
		)
		(polygon
			(pts
				(xy 429.895 -21.336) (xy 429.3616 -21.8694) (xy 429.3616 -26.0604) (xy 429.8442 -26.543) (xy 433.705 -26.543)
				(xy 433.959 -26.289) (xy 433.959 -21.59) (xy 433.705 -21.336)
			)
		)
	)
	(zone
		(layer "F.Cu")
		(hatch none 0.5)
		(connect_pads
			(clearance 0)
		)
		(min_thickness 0.25)
		(keepout
			(tracks allowed)
			(vias allowed)
			(pads allowed)
			(copperpour allowed)
			(footprints not_allowed)
		)
		(placement
			(enabled no)
			(sheetname "")
		)
		(fill
			(thermal_gap 0.5)
			(thermal_bridge_width 0.5)
			(island_removal_mode 0)
		)
		(polygon
			(pts
				(arc
					(start 276.800056 -295.209976)
					(mid 280.550112 -291.45992)
					(end 284.299914 -295.209976)
				)
				(arc
					(start 284.299914 -295.209976)
					(mid 280.550112 -298.959778)
					(end 276.800056 -295.209976)
				)
			)
		)
	)
	(zone
		(net "P5V_HDD6")
		(layer "F.Cu")
		(hatch none 0.5)
		(connect_pads
			(clearance 0.5)
		)
		(min_thickness 0.25)
		(fill yes
			(thermal_gap 0.5)
			(thermal_bridge_width 0.5)
			(island_removal_mode 0)
		)
		(polygon
			(pts
				(xy 331.597 -252.73) (xy 331.343 -252.984) (xy 331.343 -263.779) (xy 329.692 -265.43) (xy 326.263 -265.43)
				(xy 326.009 -265.684) (xy 326.009 -267.335) (xy 326.263 -267.589) (xy 330.835 -267.589) (xy 331.47 -266.954)
				(xy 333.248 -266.954) (xy 333.756 -266.446) (xy 333.756 -252.984) (xy 333.502 -252.73)
			)
		)
		(polygon
			(pts
				(xy 330.3524 -266.5984) (xy 330.1492 -266.5984) (xy 330.1492 -266.8016) (xy 330.3524 -266.8016)
			)
		)
		(polygon
			(pts
				(xy 329.4888 -266.5984) (xy 329.2856 -266.5984) (xy 329.2856 -266.8016) (xy 329.4888 -266.8016)
			)
		)
	)
	(zone
		(layer "F.Cu")
		(hatch none 0.5)
		(connect_pads
			(clearance 0)
		)
		(min_thickness 0.25)
		(keepout
			(tracks allowed)
			(vias allowed)
			(pads allowed)
			(copperpour allowed)
			(footprints allowed)
		)
		(placement
			(enabled no)
			(sheetname "")
		)
		(fill
			(thermal_gap 0.5)
			(thermal_bridge_width 0.5)
			(island_removal_mode 0)
		)
		(polygon
			(pts
				(xy 209.0928 -239.4458) (xy 208.026 -239.4458) (xy 208.026 -237.7948) (xy 209.0928 -237.7948)
			)
		)
	)
	(zone
		(net "P12V_HDD27")
		(layer "F.Cu")
		(hatch none 0.5)
		(connect_pads
			(clearance 0.5)
		)
		(min_thickness 0.25)
		(fill yes
			(thermal_gap 0.5)
			(thermal_bridge_width 0.5)
			(island_removal_mode 0)
		)
		(polygon
			(pts
				(xy 109.855 -33.528) (xy 109.601 -33.782) (xy 109.601 -37.465) (xy 117.348 -45.212) (xy 125.857 -45.212)
				(xy 125.984 -45.085) (xy 125.984 -43.307) (xy 125.857 -43.18) (xy 119.888 -43.18) (xy 119.253 -42.545)
				(xy 117.602 -42.545) (xy 113.284 -38.227) (xy 113.284 -34.671) (xy 112.141 -33.528)
			)
		)
		(polygon
			(pts
				(xy 119.4054 -44.2214) (xy 119.2022 -44.2214) (xy 119.2022 -44.4246) (xy 119.4054 -44.4246)
			)
		)
		(polygon
			(pts
				(xy 118.5418 -44.2214) (xy 118.3386 -44.2214) (xy 118.3386 -44.4246) (xy 118.5418 -44.4246)
			)
		)
	)
	(zone
		(net "P5V_B_4")
		(layer "F.Cu")
		(hatch none 0.5)
		(connect_pads
			(clearance 0.5)
		)
		(min_thickness 0.25)
		(fill yes
			(thermal_gap 0.5)
			(thermal_bridge_width 0.5)
			(island_removal_mode 0)
		)
		(polygon
			(pts
				(xy 455.8792 -21.3614) (xy 455.6252 -21.6154) (xy 455.6252 -23.9014) (xy 455.8792 -24.1554) (xy 460.5782 -24.1554)
				(xy 460.8322 -23.9014) (xy 460.8322 -21.6154) (xy 460.5782 -21.3614)
			)
		)
	)
	(zone
		(layer "F.Cu")
		(hatch none 0.5)
		(connect_pads
			(clearance 0)
		)
		(min_thickness 0.25)
		(keepout
			(tracks allowed)
			(vias allowed)
			(pads allowed)
			(copperpour allowed)
			(footprints not_allowed)
		)
		(placement
			(enabled no)
			(sheetname "")
		)
		(fill
			(thermal_gap 0.5)
			(thermal_bridge_width 0.5)
			(island_removal_mode 0)
		)
		(polygon
			(pts
				(arc
					(start 342.700102 -30.999938)
					(mid 341.300054 -32.399986)
					(end 339.900006 -30.999938)
				)
				(arc
					(start 339.900006 -30.999938)
					(mid 341.300054 -29.59989)
					(end 342.700102 -30.999938)
				)
			)
		)
	)
	(zone
		(layer "F.Cu")
		(hatch none 0.5)
		(connect_pads
			(clearance 0)
		)
		(min_thickness 0.25)
		(keepout
			(tracks allowed)
			(vias allowed)
			(pads allowed)
			(copperpour allowed)
			(footprints allowed)
		)
		(placement
			(enabled no)
			(sheetname "")
		)
		(fill
			(thermal_gap 0.5)
			(thermal_bridge_width 0.5)
			(island_removal_mode 0)
		)
		(polygon
			(pts
				(xy 456.078844 -249.026172) (xy 457.670154 -249.026172) (xy 457.670154 -250.93422) (xy 456.078844 -250.93422)
			)
		)
	)
	(zone
		(layer "F.Cu")
		(hatch none 0.5)
		(connect_pads
			(clearance 0)
		)
		(min_thickness 0.25)
		(keepout
			(tracks not_allowed)
			(vias allowed)
			(pads allowed)
			(copperpour not_allowed)
			(footprints allowed)
		)
		(placement
			(enabled no)
			(sheetname "")
		)
		(fill
			(thermal_gap 0.5)
			(thermal_bridge_width 0.5)
			(island_removal_mode 0)
		)
		(polygon
			(pts
				(arc
					(start 319.8876 -244.312694)
					(mid 319.40246 -243.827554)
					(end 318.91732 -244.312694)
				)
				(arc
					(start 318.91732 -245.45544)
					(mid 319.402333 -245.940834)
					(end 319.8876 -245.455694)
				)
				(xy 319.8876 -245.106444)
				(arc
					(start 319.58026 -245.106444)
					(mid 319.511256 -245.133471)
					(end 319.478914 -245.20017)
				)
				(arc
					(start 319.478914 -245.20017)
					(mid 319.402836 -245.722338)
					(end 319.32626 -245.20017)
				)
				(xy 319.32626 -245.176548)
				(arc
					(start 319.328546 -245.174262)
					(mid 319.400676 -245.02846)
					(end 319.546478 -244.95633)
				)
				(xy 319.548764 -244.954044) (xy 319.8876 -244.954044) (xy 319.8876 -244.814344) (xy 319.548764 -244.814344)
				(arc
					(start 319.546478 -244.812058)
					(mid 319.400676 -244.739928)
					(end 319.328546 -244.594126)
				)
				(xy 319.32626 -244.59184)
				(arc
					(start 319.32626 -244.568218)
					(mid 319.402836 -244.045977)
					(end 319.478914 -244.568218)
				)
				(arc
					(start 319.478914 -244.568218)
					(mid 319.511222 -244.634954)
					(end 319.58026 -244.661944)
				)
				(xy 319.8876 -244.661944)
			)
		)
	)
	(zone
		(net "GATE_FAN0")
		(layer "F.Cu")
		(hatch none 0.5)
		(connect_pads
			(clearance 0.5)
		)
		(min_thickness 0.25)
		(fill yes
			(thermal_gap 0.5)
			(thermal_bridge_width 0.5)
			(island_removal_mode 0)
		)
		(polygon
			(pts
				(xy 42.614596 -357.8352) (xy 42.385996 -358.0638) (xy 42.385996 -359.664) (xy 43.071796 -360.3498)
				(xy 43.071796 -361.6452) (xy 43.147996 -361.7214) (xy 44.671996 -361.7214) (xy 45.052996 -361.3404)
				(xy 45.052996 -360.5022) (xy 45.42282 -360.132376) (xy 46.12894 -360.132376) (xy 46.195996 -360.06532)
				(xy 46.195996 -358.4448) (xy 46.119796 -358.3686) (xy 45.357796 -358.3686) (xy 44.824396 -357.8352)
			)
		)
		(polygon
			(pts
				(xy 45.637196 -359.4862) (xy 45.433996 -359.4862) (xy 45.433996 -359.6894) (xy 45.637196 -359.6894)
			)
		)
		(polygon
			(pts
				(xy 45.637196 -358.9655) (xy 45.433996 -358.9655) (xy 45.433996 -359.1687) (xy 45.637196 -359.1687)
			)
		)
	)
	(zone
		(net "P5V_HDD35")
		(layer "F.Cu")
		(hatch none 0.5)
		(connect_pads
			(clearance 0.5)
		)
		(min_thickness 0.25)
		(fill yes
			(thermal_gap 0.5)
			(thermal_bridge_width 0.5)
			(island_removal_mode 0)
		)
		(polygon
			(pts
				(xy 474.726 -27.559) (xy 474.472 -27.813) (xy 474.472 -30.099) (xy 474.726 -30.353) (xy 474.726 -32.385)
				(xy 475.488 -33.147) (xy 475.488 -33.909) (xy 475.869 -34.29) (xy 476.25 -34.29) (xy 479.425 -37.465)
				(xy 486.283 -37.465) (xy 486.41 -37.338) (xy 486.41 -35.56) (xy 486.283 -35.433) (xy 481.203 -35.433)
				(xy 479.298 -33.528) (xy 478.409 -33.528) (xy 477.52 -32.639) (xy 477.52 -30.099) (xy 478.155 -29.464)
				(xy 478.155 -27.813) (xy 477.901 -27.559)
			)
		)
		(polygon
			(pts
				(xy 476.5802 -33.9852) (xy 476.377 -33.9852) (xy 476.377 -34.1884) (xy 476.5802 -34.1884)
			)
		)
		(polygon
			(pts
				(xy 476.5802 -33.1216) (xy 476.377 -33.1216) (xy 476.377 -33.3248) (xy 476.5802 -33.3248)
			)
		)
	)
	(zone
		(net "P5V_B_4")
		(layer "F.Cu")
		(hatch none 0.5)
		(connect_pads
			(clearance 0.5)
		)
		(min_thickness 0.25)
		(fill yes
			(thermal_gap 0.5)
			(thermal_bridge_width 0.5)
			(island_removal_mode 0)
		)
		(polygon
			(pts
				(xy 393.065 -19.05) (xy 392.811 -19.304) (xy 392.811 -21.59) (xy 393.065 -21.844) (xy 397.764 -21.844)
				(xy 398.018 -21.59) (xy 398.018 -19.304) (xy 397.764 -19.05)
			)
		)
	)
	(zone
		(layer "F.Cu")
		(hatch none 0.5)
		(connect_pads
			(clearance 0)
		)
		(min_thickness 0.25)
		(keepout
			(tracks allowed)
			(vias allowed)
			(pads allowed)
			(copperpour allowed)
			(footprints allowed)
		)
		(placement
			(enabled no)
			(sheetname "")
		)
		(fill
			(thermal_gap 0.5)
			(thermal_bridge_width 0.5)
			(island_removal_mode 0)
		)
		(polygon
			(pts
				(xy 186.591956 -375.326656) (xy 186.591956 -374.336056) (xy 186.591956 -373.421656) (xy 187.811156 -373.421656)
				(xy 187.811156 -375.326656) (xy 187.379356 -375.326656)
			)
		)
	)
	(zone
		(net "GND")
		(layer "F.Cu")
		(hatch none 0.5)
		(connect_pads
			(clearance 0.5)
		)
		(min_thickness 0.25)
		(fill yes
			(thermal_gap 0.5)
			(thermal_bridge_width 0.5)
			(island_removal_mode 0)
		)
		(polygon
			(pts
				(xy 438.65038 -139.418568) (xy 438.36336 -139.705588)
				(arc
					(start 438.36336 -142.1765)
					(mid 438.261445 -143.061861)
					(end 437.961024 -143.900906)
				)
				(xy 437.961024 -160.263586) (xy 434.648356 -163.576254) (xy 433.01158 -163.576254) (xy 432.627024 -163.96081)
				(xy 432.627024 -164.643054) (xy 432.94681 -164.96284) (xy 446.130172 -164.96284) (xy 446.64376 -164.449252)
				(xy 446.64376 -160.678876) (xy 447.32067 -160.678876) (xy 447.93154 -160.068006) (xy 447.93154 -159.32023)
				(xy 447.587116 -158.975806) (xy 443.465712 -158.975806) (xy 440.228736 -155.73883) (xy 440.228736 -139.993878)
				(xy 439.653426 -139.418568)
			)
		)
	)
	(zone
		(net "GND")
		(layer "F.Cu")
		(hatch none 0.5)
		(connect_pads
			(clearance 0.5)
		)
		(min_thickness 0.25)
		(fill yes
			(thermal_gap 0.5)
			(thermal_bridge_width 0.5)
			(island_removal_mode 0)
		)
		(polygon
			(pts
				(xy 20.27809 -220.83395) (xy 19.77009 -221.34195) (xy 19.77009 -226.429062) (xy 20.565872 -227.224844)
				(xy 23.026878 -227.224844) (xy 23.2156 -227.036122) (xy 23.2156 -221.01175) (xy 23.0378 -220.83395)
			)
		)
	)
	(zone
		(net "P12V_B")
		(layer "F.Cu")
		(hatch none 0.5)
		(connect_pads
			(clearance 0.5)
		)
		(min_thickness 0.25)
		(fill yes
			(thermal_gap 0.5)
			(thermal_bridge_width 0.5)
			(island_removal_mode 0)
		)
		(polygon
			(pts
				(xy 397.764 -142.494) (xy 397.256 -143.002) (xy 397.256 -146.431) (xy 397.51 -146.685) (xy 400.812 -146.685)
				(xy 401.066 -146.431) (xy 401.066 -144.399) (xy 401.193 -144.272) (xy 401.574 -144.272) (xy 401.701 -144.145)
				(xy 401.701 -142.621) (xy 401.574 -142.494)
			)
		)
		(polygon
			(pts
				(xy 401.1676 -143.4846) (xy 400.9644 -143.4846) (xy 400.9644 -143.6878) (xy 401.1676 -143.6878)
			)
		)
		(polygon
			(pts
				(xy 401.2184 -143.0528) (xy 401.0152 -143.0528) (xy 401.0152 -143.256) (xy 401.2184 -143.256)
			)
		)
	)
	(zone
		(net "P12V_B")
		(layer "F.Cu")
		(hatch none 0.5)
		(connect_pads
			(clearance 0.5)
		)
		(min_thickness 0.25)
		(fill yes
			(thermal_gap 0.5)
			(thermal_bridge_width 0.5)
			(island_removal_mode 0)
		)
		(polygon
			(pts
				(xy 200.453498 -308.407308) (xy 199.9742 -308.886606) (xy 199.9742 -312.1406) (xy 200.2282 -312.3946)
				(xy 206.8322 -312.3946) (xy 207.0862 -312.1406) (xy 207.0862 -308.90464) (xy 206.588868 -308.407308)
			)
		)
	)
	(zone
		(net "AGND_CURRENT_MON")
		(layer "F.Cu")
		(hatch none 0.5)
		(connect_pads
			(clearance 0.5)
		)
		(min_thickness 0.25)
		(fill yes
			(thermal_gap 0.5)
			(thermal_bridge_width 0.5)
			(island_removal_mode 0)
		)
		(polygon
			(pts
				(xy 164.003482 -362.843318) (xy 163.83 -363.0168) (xy 163.83 -364.9726) (xy 164.06368 -365.20628)
				(xy 166.851076 -365.20628) (xy 167.226488 -364.830868) (xy 167.226488 -363.244384) (xy 166.825422 -362.843318)
			)
		)
		(polygon
			(pts
				(xy 166.95293 -364.545626) (xy 166.74973 -364.545626) (xy 166.74973 -364.748826) (xy 166.95293 -364.748826)
			)
		)
		(polygon
			(pts
				(xy 166.39413 -364.545626) (xy 166.19093 -364.545626) (xy 166.19093 -364.748826) (xy 166.39413 -364.748826)
			)
		)
		(polygon
			(pts
				(xy 165.96233 -364.113826) (xy 165.75913 -364.113826) (xy 165.75913 -364.317026) (xy 165.96233 -364.317026)
			)
		)
		(polygon
			(pts
				(xy 165.09873 -364.113826) (xy 164.89553 -364.113826) (xy 164.89553 -364.317026) (xy 165.09873 -364.317026)
			)
		)
		(polygon
			(pts
				(xy 165.96233 -363.732826) (xy 165.75913 -363.732826) (xy 165.75913 -363.936026) (xy 165.96233 -363.936026)
			)
		)
		(polygon
			(pts
				(xy 165.09873 -363.732826) (xy 164.89553 -363.732826) (xy 164.89553 -363.936026) (xy 165.09873 -363.936026)
			)
		)
		(polygon
			(pts
				(xy 166.95293 -363.301026) (xy 166.74973 -363.301026) (xy 166.74973 -363.504226) (xy 166.95293 -363.504226)
			)
		)
		(polygon
			(pts
				(xy 166.39413 -363.301026) (xy 166.19093 -363.301026) (xy 166.19093 -363.504226) (xy 166.39413 -363.504226)
			)
		)
	)
	(zone
		(net "5V_PRE_27")
		(layer "F.Cu")
		(hatch none 0.5)
		(connect_pads
			(clearance 0.5)
		)
		(min_thickness 0.25)
		(fill yes
			(thermal_gap 0.5)
			(thermal_bridge_width 0.5)
			(island_removal_mode 0)
		)
		(polygon
			(pts
				(xy 117.60835 -30.9626) (xy 117.45595 -31.115) (xy 117.45595 -32.512) (xy 118.04015 -33.0962) (xy 119.31015 -33.0962)
				(xy 121.39295 -35.179) (xy 125.83795 -35.179) (xy 125.96495 -35.052) (xy 125.96495 -34.29) (xy 125.83795 -34.163)
				(xy 122.81535 -34.163) (xy 119.61495 -30.9626)
			)
		)
	)
	(zone
		(net "GND")
		(layer "F.Cu")
		(hatch none 0.5)
		(connect_pads
			(clearance 0.5)
		)
		(min_thickness 0.25)
		(fill yes
			(thermal_gap 0.5)
			(thermal_bridge_width 0.5)
			(island_removal_mode 0)
		)
		(polygon
			(pts
				(xy 117.500146 -192.625218) (xy 116.88826 -193.237104)
				(arc
					(start 116.88826 -203.864464)
					(mid 117.091595 -205.146148)
					(end 116.88826 -206.427832)
				)
				(xy 116.88826 -209.294476) (xy 117.273324 -209.294476) (xy 117.273324 -217.340942) (xy 118.371874 -218.439492)
				(xy 137.61974 -218.439492) (xy 139.012676 -217.046556) (xy 139.012676 -209.294476)
				(arc
					(start 139.443714 -209.294476)
					(mid 139.498029 -209.104271)
					(end 139.561824 -208.917032)
				)
				(arc
					(start 139.561824 -202.387454)
					(mid 139.358489 -201.10577)
					(end 139.561824 -199.824086)
				)
				(xy 139.561824 -194.112388) (xy 138.454892 -193.005456)
				(arc
					(start 136.217914 -193.005456)
					(mid 132.247988 -195.083129)
					(end 127.824992 -195.800218)
				)
				(arc
					(start 127.824738 -195.800218)
					(mid 123.110387 -194.982587)
					(end 118.946676 -192.625218)
				)
			)
		)
	)
	(zone
		(layer "F.Cu")
		(hatch none 0.5)
		(connect_pads
			(clearance 0)
		)
		(min_thickness 0.25)
		(keepout
			(tracks allowed)
			(vias allowed)
			(pads allowed)
			(copperpour allowed)
			(footprints not_allowed)
		)
		(placement
			(enabled no)
			(sheetname "")
		)
		(fill
			(thermal_gap 0.5)
			(thermal_bridge_width 0.5)
			(island_removal_mode 0)
		)
		(polygon
			(pts
				(xy 491.450122 -96.799908) (xy 491.450122 -161.800032) (xy 478.00006 -161.800032) (xy 478.00006 -151.800052)
				(xy 463.449924 -151.800052) (xy 463.449924 -161.800032) (xy 446.449958 -161.800032) (xy 446.449958 -151.800052)
				(xy 431.900076 -151.800052) (xy 431.900076 -161.800032) (xy 414.90011 -161.800032) (xy 414.90011 -151.800052)
				(xy 400.349974 -151.800052) (xy 400.349974 -161.800032) (xy 383.350008 -161.800032) (xy 383.350008 -151.800052)
				(xy 368.800126 -151.800052) (xy 368.800126 -161.800032) (xy 351.799906 -161.800032) (xy 351.799906 -151.800052)
				(xy 337.250024 -151.800052) (xy 337.250024 -161.800032) (xy 320.250058 -161.800032) (xy 320.250058 -151.800052)
				(xy 305.699922 -151.800052) (xy 305.699922 -161.800032) (xy 298.200064 -161.800032) (xy 298.200064 -110.000034)
				(xy 312.699908 -110.000034) (xy 312.699908 -96.799908)
			)
		)
	)
	(zone
		(net "AGND_P5V_B_2")
		(layer "F.Cu")
		(hatch none 0.5)
		(connect_pads
			(clearance 0.5)
		)
		(min_thickness 0.25)
		(fill yes
			(thermal_gap 0.5)
			(thermal_bridge_width 0.5)
			(island_removal_mode 0)
		)
		(polygon
			(pts
				(xy 44.11726 -118.437406) (xy 43.60926 -118.945406) (xy 43.60926 -120.164606) (xy 43.76166 -120.317006)
				(xy 46.12386 -120.317006) (xy 46.55566 -119.885206) (xy 46.55566 -119.428006) (xy 46.98746 -118.996206)
				(xy 46.98746 -118.539006) (xy 46.88586 -118.437406)
			)
		)
		(polygon
			(pts
				(xy 44.21886 -119.961406) (xy 44.01566 -119.961406) (xy 44.01566 -120.164606) (xy 44.21886 -120.164606)
			)
		)
		(polygon
			(pts
				(xy 44.21886 -119.402606) (xy 44.01566 -119.402606) (xy 44.01566 -119.605806) (xy 44.21886 -119.605806)
			)
		)
		(polygon
			(pts
				(xy 46.563788 -118.956074) (xy 46.360588 -118.956074) (xy 46.360588 -119.159274) (xy 46.563788 -119.159274)
			)
		)
		(polygon
			(pts
				(xy 45.980858 -118.933976) (xy 45.777658 -118.933976) (xy 45.777658 -119.137176) (xy 45.980858 -119.137176)
			)
		)
		(polygon
			(pts
				(xy 45.422058 -118.933976) (xy 45.218858 -118.933976) (xy 45.218858 -119.137176) (xy 45.422058 -119.137176)
			)
		)
		(polygon
			(pts
				(xy 44.93006 -118.920006) (xy 44.72686 -118.920006) (xy 44.72686 -119.123206) (xy 44.93006 -119.123206)
			)
		)
		(polygon
			(pts
				(xy 44.37126 -118.920006) (xy 44.16806 -118.920006) (xy 44.16806 -119.123206) (xy 44.37126 -119.123206)
			)
		)
	)
	(zone
		(layer "F.Cu")
		(hatch none 0.5)
		(connect_pads
			(clearance 0)
		)
		(min_thickness 0.25)
		(keepout
			(tracks allowed)
			(vias allowed)
			(pads allowed)
			(copperpour allowed)
			(footprints not_allowed)
		)
		(placement
			(enabled no)
			(sheetname "")
		)
		(fill
			(thermal_gap 0.5)
			(thermal_bridge_width 0.5)
			(island_removal_mode 0)
		)
		(polygon
			(pts
				(xy 251.000006 -336.00009) (xy 239.00003 -336.00009) (xy 239.00003 -345.000072) (xy 251.000006 -345.000072)
			)
		)
	)
	(zone
		(net "GND")
		(layer "F.Cu")
		(hatch none 0.5)
		(connect_pads
			(clearance 0.5)
		)
		(min_thickness 0.25)
		(fill yes
			(thermal_gap 0.5)
			(thermal_bridge_width 0.5)
			(island_removal_mode 0)
		)
		(polygon
			(pts
				(xy 62.60973 -59.867546) (xy 62.49416 -59.983116) (xy 62.49416 -98.256852) (xy 63.375032 -99.137724)
				(xy 67.59321 -99.137724) (xy 68.97116 -97.759774)
				(arc
					(start 68.97116 -94.807278)
					(mid 69.270851 -93.300542)
					(end 70.12432 -92.023184)
				)
				(arc
					(start 70.98538 -91.162124)
					(mid 71.700696 -90.160024)
					(end 72.679052 -89.412572)
				)
				(arc
					(start 72.679052 -65.572386)
					(mid 72.978743 -64.06565)
					(end 73.832212 -62.788292)
				)
				(xy 75.11923 -61.501274) (xy 75.11923 -60.711334) (xy 74.275442 -59.867546)
			)
		)
	)
	(zone
		(net "5V_PRE_4")
		(layer "F.Cu")
		(hatch none 0.5)
		(connect_pads
			(clearance 0.5)
		)
		(min_thickness 0.25)
		(fill yes
			(thermal_gap 0.5)
			(thermal_bridge_width 0.5)
			(island_removal_mode 0)
		)
		(polygon
			(pts
				(xy 149.158452 -260.962648) (xy 149.006052 -261.115048) (xy 149.006052 -262.512048) (xy 149.590252 -263.096248)
				(xy 150.860252 -263.096248) (xy 152.943052 -265.179048) (xy 157.388052 -265.179048) (xy 157.515052 -265.052048)
				(xy 157.515052 -264.290048) (xy 157.388052 -264.163048) (xy 154.365452 -264.163048) (xy 151.165052 -260.962648)
			)
		)
	)
	(zone
		(net "AGND_P5V_B_1")
		(layer "F.Cu")
		(hatch none 0.5)
		(connect_pads
			(clearance 0.5)
		)
		(min_thickness 0.25)
		(fill yes
			(thermal_gap 0.5)
			(thermal_bridge_width 0.5)
			(island_removal_mode 0)
		)
		(polygon
			(pts
				(xy 19.269202 -229.62235) (xy 18.761202 -230.13035) (xy 18.761202 -231.34955) (xy 18.913602 -231.50195)
				(xy 21.275802 -231.50195) (xy 21.707602 -231.07015) (xy 21.707602 -230.61295) (xy 22.139402 -230.18115)
				(xy 22.139402 -229.72395) (xy 22.037802 -229.62235)
			)
		)
		(polygon
			(pts
				(xy 19.370802 -231.14635) (xy 19.167602 -231.14635) (xy 19.167602 -231.34955) (xy 19.370802 -231.34955)
			)
		)
		(polygon
			(pts
				(xy 19.370802 -230.58755) (xy 19.167602 -230.58755) (xy 19.167602 -230.79075) (xy 19.370802 -230.79075)
			)
		)
		(polygon
			(pts
				(xy 21.71573 -230.141018) (xy 21.51253 -230.141018) (xy 21.51253 -230.344218) (xy 21.71573 -230.344218)
			)
		)
		(polygon
			(pts
				(xy 21.1328 -230.11892) (xy 20.9296 -230.11892) (xy 20.9296 -230.32212) (xy 21.1328 -230.32212)
			)
		)
		(polygon
			(pts
				(xy 20.574 -230.11892) (xy 20.3708 -230.11892) (xy 20.3708 -230.32212) (xy 20.574 -230.32212)
			)
		)
		(polygon
			(pts
				(xy 20.082002 -230.10495) (xy 19.878802 -230.10495) (xy 19.878802 -230.30815) (xy 20.082002 -230.30815)
			)
		)
		(polygon
			(pts
				(xy 19.523202 -230.10495) (xy 19.320002 -230.10495) (xy 19.320002 -230.30815) (xy 19.523202 -230.30815)
			)
		)
	)
	(zone
		(layer "F.Cu")
		(hatch none 0.5)
		(connect_pads
			(clearance 0)
		)
		(min_thickness 0.25)
		(keepout
			(tracks allowed)
			(vias allowed)
			(pads allowed)
			(copperpour allowed)
			(footprints allowed)
		)
		(placement
			(enabled no)
			(sheetname "")
		)
		(fill
			(thermal_gap 0.5)
			(thermal_bridge_width 0.5)
			(island_removal_mode 0)
		)
		(polygon
			(pts
				(xy 37.991796 -361.3404) (xy 39.337996 -361.3404) (xy 39.337996 -362.1278) (xy 37.991796 -362.1278)
			)
		)
	)
	(zone
		(net "P3V3_STBY_B")
		(layer "F.Cu")
		(hatch none 0.5)
		(connect_pads
			(clearance 0.5)
		)
		(min_thickness 0.25)
		(fill yes
			(thermal_gap 0.5)
			(thermal_bridge_width 0.5)
			(island_removal_mode 0)
		)
		(polygon
			(pts
				(xy 458.343 -5.08) (xy 458.2922 -5.1308) (xy 458.2922 -7.2136) (xy 459.74 -8.6614) (xy 460.4766 -8.6614)
				(xy 460.5782 -8.5598) (xy 460.5782 -6.1722) (xy 459.486 -5.08)
			)
		)
		(polygon
			(pts
				(xy 459.8416 -7.6708) (xy 459.6384 -7.6708) (xy 459.6384 -7.874) (xy 459.8416 -7.874)
			)
		)
		(polygon
			(pts
				(xy 459.867 -6.5024) (xy 459.6638 -6.5024) (xy 459.6638 -6.7056) (xy 459.6384 -6.8072) (xy 459.6384 -7.0104)
				(xy 459.8416 -7.0104) (xy 459.8416 -6.8072) (xy 459.867 -6.7056)
			)
		)
		(polygon
			(pts
				(xy 459.867 -5.8928) (xy 459.6638 -5.8928) (xy 459.6638 -6.096) (xy 459.867 -6.096)
			)
		)
	)
	(zone
		(layer "F.Cu")
		(hatch none 0.5)
		(connect_pads
			(clearance 0)
		)
		(min_thickness 0.25)
		(keepout
			(tracks not_allowed)
			(vias allowed)
			(pads allowed)
			(copperpour not_allowed)
			(footprints allowed)
		)
		(placement
			(enabled no)
			(sheetname "")
		)
		(fill
			(thermal_gap 0.5)
			(thermal_bridge_width 0.5)
			(island_removal_mode 0)
		)
		(polygon
			(pts
				(arc
					(start 476.964756 -13.14196)
					(mid 476.479362 -13.626973)
					(end 476.964502 -14.11224)
				)
				(xy 477.313752 -14.11224)
				(arc
					(start 477.313752 -13.7922)
					(mid 477.287714 -13.729338)
					(end 477.224852 -13.7033)
				)
				(arc
					(start 477.220026 -13.7033)
					(mid 476.697858 -13.6271)
					(end 477.220026 -13.5509)
				)
				(xy 477.256348 -13.5509)
				(arc
					(start 477.258888 -13.553186)
					(mid 477.395565 -13.621487)
					(end 477.463866 -13.758164)
				)
				(xy 477.466152 -13.760704) (xy 477.466152 -14.11224) (xy 477.605852 -14.11224) (xy 477.605852 -13.760704)
				(arc
					(start 477.608138 -13.758164)
					(mid 477.676439 -13.621487)
					(end 477.813116 -13.553186)
				)
				(xy 477.815656 -13.5509)
				(arc
					(start 477.851978 -13.5509)
					(mid 478.374146 -13.6271)
					(end 477.851978 -13.7033)
				)
				(arc
					(start 477.847152 -13.7033)
					(mid 477.78429 -13.729338)
					(end 477.758252 -13.7922)
				)
				(xy 477.758252 -14.11224)
				(arc
					(start 478.107502 -14.11224)
					(mid 478.592642 -13.6271)
					(end 478.107502 -13.14196)
				)
			)
		)
	)
	(zone
		(net "P3V3_STBY_A")
		(layer "F.Cu")
		(hatch none 0.5)
		(connect_pads
			(clearance 0.5)
		)
		(min_thickness 0.25)
		(fill yes
			(thermal_gap 0.5)
			(thermal_bridge_width 0.5)
			(island_removal_mode 0)
		)
		(polygon
			(pts
				(xy 34.925 -5.1054) (xy 34.7599 -5.2705) (xy 34.7599 -8.4963) (xy 35.0393 -8.7757) (xy 37.1475 -8.7757)
				(xy 37.3634 -8.5598) (xy 37.3634 -7.112) (xy 37.3507 -7.112) (xy 37.0713 -6.8326) (xy 37.0713 -6.1595)
				(xy 36.0172 -5.1054)
			)
		)
		(polygon
			(pts
				(xy 36.4744 -7.7724) (xy 36.2712 -7.7724) (xy 36.2712 -7.9756) (xy 36.4744 -7.9756)
			)
		)
		(polygon
			(pts
				(xy 36.4998 -6.604) (xy 36.2966 -6.604) (xy 36.2966 -6.8072) (xy 36.2712 -6.9088) (xy 36.2712 -7.112)
				(xy 36.4744 -7.112) (xy 36.4744 -6.9088) (xy 36.4998 -6.8072)
			)
		)
		(polygon
			(pts
				(xy 36.4998 -5.9944) (xy 36.2966 -5.9944) (xy 36.2966 -6.1976) (xy 36.4998 -6.1976)
			)
		)
	)
	(zone
		(net "P12V_HDD2")
		(layer "F.Cu")
		(hatch none 0.5)
		(connect_pads
			(clearance 0.5)
		)
		(min_thickness 0.25)
		(fill yes
			(thermal_gap 0.5)
			(thermal_bridge_width 0.5)
			(island_removal_mode 0)
		)
		(polygon
			(pts
				(xy 75.438 -262.255) (xy 75.184 -262.509) (xy 75.184 -264.16) (xy 75.438 -264.414) (xy 77.597 -264.414)
				(xy 78.105 -264.922) (xy 78.105 -267.462) (xy 85.852 -275.209) (xy 94.361 -275.209) (xy 94.488 -275.082)
				(xy 94.488 -273.304) (xy 94.361 -273.177) (xy 88.392 -273.177) (xy 87.757 -272.542) (xy 86.106 -272.542)
				(xy 81.788 -268.224) (xy 81.788 -264.668) (xy 80.645 -263.525) (xy 80.645 -262.509) (xy 80.391 -262.255)
			)
		)
		(polygon
			(pts
				(xy 87.9094 -274.2184) (xy 87.7062 -274.2184) (xy 87.7062 -274.4216) (xy 87.9094 -274.4216)
			)
		)
		(polygon
			(pts
				(xy 87.0458 -274.2184) (xy 86.8426 -274.2184) (xy 86.8426 -274.4216) (xy 87.0458 -274.4216)
			)
		)
	)
	(zone
		(layer "F.Cu")
		(hatch none 0.5)
		(connect_pads
			(clearance 0)
		)
		(min_thickness 0.25)
		(keepout
			(tracks not_allowed)
			(vias allowed)
			(pads allowed)
			(copperpour not_allowed)
			(footprints allowed)
		)
		(placement
			(enabled no)
			(sheetname "")
		)
		(fill
			(thermal_gap 0.5)
			(thermal_bridge_width 0.5)
			(island_removal_mode 0)
		)
		(polygon
			(pts
				(arc
					(start 159.193992 -18.11528)
					(mid 158.708979 -17.629886)
					(end 158.223712 -18.115026)
				)
				(xy 158.223712 -18.527776)
				(arc
					(start 158.581852 -18.527776)
					(mid 158.617773 -18.512897)
					(end 158.632652 -18.476976)
				)
				(arc
					(start 158.632652 -18.37055)
					(mid 158.708852 -17.848382)
					(end 158.785052 -18.37055)
				)
				(xy 158.785052 -18.508472)
				(arc
					(start 158.782004 -18.51152)
					(mid 158.725473 -18.620597)
					(end 158.616396 -18.677128)
				)
				(xy 158.613348 -18.680176) (xy 158.223712 -18.680176) (xy 158.223712 -18.819876) (xy 158.613348 -18.819876)
				(arc
					(start 158.616396 -18.822924)
					(mid 158.725473 -18.879455)
					(end 158.782004 -18.988532)
				)
				(xy 158.785052 -18.99158)
				(arc
					(start 158.785052 -19.129502)
					(mid 158.708852 -19.65167)
					(end 158.632652 -19.129502)
				)
				(arc
					(start 158.632652 -19.023076)
					(mid 158.617773 -18.987155)
					(end 158.581852 -18.972276)
				)
				(xy 158.223712 -18.972276)
				(arc
					(start 158.223712 -19.385026)
					(mid 158.708852 -19.870166)
					(end 159.193992 -19.385026)
				)
			)
		)
	)
	(zone
		(net "P5V_HDD1")
		(layer "F.Cu")
		(hatch none 0.5)
		(connect_pads
			(clearance 0.5)
		)
		(min_thickness 0.25)
		(fill yes
			(thermal_gap 0.5)
			(thermal_bridge_width 0.5)
			(island_removal_mode 0)
		)
		(polygon
			(pts
				(xy 51.308 -257.683) (xy 51.054 -257.937) (xy 51.054 -260.223) (xy 51.308 -260.477) (xy 51.308 -262.509)
				(xy 52.07 -263.271) (xy 52.07 -264.033) (xy 52.451 -264.414) (xy 52.832 -264.414) (xy 56.007 -267.589)
				(xy 62.865 -267.589) (xy 62.992 -267.462) (xy 62.992 -265.684) (xy 62.865 -265.557) (xy 57.785 -265.557)
				(xy 55.88 -263.652) (xy 54.991 -263.652) (xy 54.102 -262.763) (xy 54.102 -260.223) (xy 54.737 -259.588)
				(xy 54.737 -257.937) (xy 54.483 -257.683)
			)
		)
		(polygon
			(pts
				(xy 53.0352 -263.2456) (xy 52.832 -263.2456) (xy 52.832 -263.4488) (xy 53.0352 -263.4488)
			)
		)
	)
	(zone
		(net "GND")
		(layer "F.Cu")
		(hatch none 0.5)
		(connect_pads
			(clearance 0.5)
		)
		(min_thickness 0.25)
		(fill yes
			(thermal_gap 0.5)
			(thermal_bridge_width 0.5)
			(island_removal_mode 0)
		)
		(polygon
			(pts
				(xy 86.036404 -191.16167) (xy 85.337904 -191.86017)
				(arc
					(start 85.337904 -205.136242)
					(mid 85.541251 -206.417926)
					(end 85.337904 -207.69961)
				)
				(xy 85.337904 -209.291428) (xy 85.338158 -209.294476) (xy 85.650324 -209.294476) (xy 85.650324 -217.97772)
				(xy 86.626446 -218.953842) (xy 98.582734 -218.953842) (xy 100.073206 -217.46337)
				(arc
					(start 100.073206 -214.606378)
					(mid 100.186003 -213.661751)
					(end 100.51796 -212.770212)
				)
				(arc
					(start 100.51796 -208.980278)
					(mid 100.817651 -207.473542)
					(end 101.67112 -206.196184)
				)
				(arc
					(start 101.71938 -206.147924)
					(mid 102.481874 -205.097874)
					(end 103.531924 -204.33538)
				)
				(xy 104.225598 -203.641706) (xy 104.225598 -196.459348) (xy 102.515162 -194.748912)
				(arc
					(start 100.567744 -194.748912)
					(mid 93.444891 -195.225085)
					(end 87.57539 -191.16167)
				)
			)
		)
	)
	(zone
		(net "P12V_HDD24")
		(layer "F.Cu")
		(hatch none 0.5)
		(connect_pads
			(clearance 0.5)
		)
		(min_thickness 0.25)
		(fill yes
			(thermal_gap 0.5)
			(thermal_bridge_width 0.5)
			(island_removal_mode 0)
		)
		(polygon
			(pts
				(xy 12.319 -32.258) (xy 12.065 -32.512) (xy 12.065 -34.163) (xy 12.319 -34.417) (xy 14.478 -34.417)
				(xy 14.986 -34.925) (xy 14.986 -37.465) (xy 22.733 -45.212) (xy 31.242 -45.212) (xy 31.369 -45.085)
				(xy 31.369 -43.307) (xy 31.242 -43.18) (xy 25.273 -43.18) (xy 24.638 -42.545) (xy 22.987 -42.545)
				(xy 18.669 -38.227) (xy 18.669 -34.831782) (xy 17.526 -33.688782) (xy 17.526 -32.512) (xy 17.272 -32.258)
			)
		)
		(polygon
			(pts
				(xy 24.7904 -44.2214) (xy 24.5872 -44.2214) (xy 24.5872 -44.4246) (xy 24.7904 -44.4246)
			)
		)
		(polygon
			(pts
				(xy 23.9268 -44.2214) (xy 23.7236 -44.2214) (xy 23.7236 -44.4246) (xy 23.9268 -44.4246)
			)
		)
	)
	(zone
		(net "P12V_B")
		(layer "F.Cu")
		(hatch none 0.5)
		(connect_pads
			(clearance 0.5)
		)
		(min_thickness 0.25)
		(fill yes
			(thermal_gap 0.5)
			(thermal_bridge_width 0.5)
			(island_removal_mode 0)
		)
		(polygon
			(pts
				(xy 460.756 -257.429) (xy 460.248 -257.937) (xy 460.248 -261.366) (xy 460.502 -261.62) (xy 463.804 -261.62)
				(xy 464.058 -261.366) (xy 464.058 -259.334) (xy 464.185 -259.207) (xy 464.566 -259.207) (xy 464.666076 -259.106924)
				(xy 464.666076 -257.529076) (xy 464.566 -257.429)
			)
		)
		(polygon
			(pts
				(xy 464.1596 -258.4196) (xy 463.9564 -258.4196) (xy 463.9564 -258.6228) (xy 464.1596 -258.6228)
			)
		)
		(polygon
			(pts
				(xy 464.2104 -257.9878) (xy 464.0072 -257.9878) (xy 464.0072 -258.191) (xy 464.2104 -258.191)
			)
		)
	)
	(zone
		(net "P5V_B_2")
		(layer "F.Cu")
		(hatch none 0.5)
		(connect_pads
			(clearance 0.5)
		)
		(min_thickness 0.25)
		(fill yes
			(thermal_gap 0.5)
			(thermal_bridge_width 0.5)
			(island_removal_mode 0)
		)
		(polygon
			(pts
				(xy 81.534 -21.844) (xy 81.28 -22.098) (xy 81.28 -24.384) (xy 81.534 -24.638) (xy 86.233 -24.638)
				(xy 86.487 -24.384) (xy 86.487 -22.098) (xy 86.233 -21.844)
			)
		)
	)
	(zone
		(layer "F.Cu")
		(hatch none 0.5)
		(connect_pads
			(clearance 0)
		)
		(min_thickness 0.25)
		(keepout
			(tracks not_allowed)
			(vias allowed)
			(pads allowed)
			(copperpour not_allowed)
			(footprints allowed)
		)
		(placement
			(enabled no)
			(sheetname "")
		)
		(fill
			(thermal_gap 0.5)
			(thermal_bridge_width 0.5)
			(island_removal_mode 0)
		)
		(polygon
			(pts
				(arc
					(start 385.78155 -131.951984)
					(mid 385.29641 -132.437124)
					(end 385.78155 -132.922264)
				)
				(xy 386.1943 -132.922264)
				(arc
					(start 386.1943 -132.6007)
					(mid 386.168708 -132.538916)
					(end 386.106924 -132.513324)
				)
				(arc
					(start 386.037074 -132.513324)
					(mid 385.514906 -132.437124)
					(end 386.037074 -132.360924)
				)
				(xy 386.13842 -132.360924)
				(arc
					(start 386.14096 -132.363464)
					(mid 386.276393 -132.431231)
					(end 386.34416 -132.566664)
				)
				(xy 386.3467 -132.569204) (xy 386.3467 -132.922264) (xy 386.4864 -132.922264) (xy 386.4864 -132.569204)
				(arc
					(start 386.48894 -132.566664)
					(mid 386.556707 -132.431231)
					(end 386.69214 -132.363464)
				)
				(xy 386.69468 -132.360924)
				(arc
					(start 386.796026 -132.360924)
					(mid 387.318194 -132.437124)
					(end 386.796026 -132.513324)
				)
				(arc
					(start 386.726176 -132.513324)
					(mid 386.664392 -132.538916)
					(end 386.6388 -132.6007)
				)
				(xy 386.6388 -132.922264)
				(arc
					(start 387.051296 -132.922264)
					(mid 387.53669 -132.437251)
					(end 387.05155 -131.951984)
				)
			)
		)
	)
	(zone
		(net "P12V_B")
		(layer "F.Cu")
		(hatch none 0.5)
		(connect_pads
			(clearance 0.5)
		)
		(min_thickness 0.25)
		(fill yes
			(thermal_gap 0.5)
			(thermal_bridge_width 0.5)
			(island_removal_mode 0)
		)
		(polygon
			(pts
				(xy 469.265 -140.081) (xy 468.249 -141.097) (xy 467.614 -141.097) (xy 467.233 -141.478) (xy 467.233 -144.018)
				(xy 467.487 -144.272) (xy 470.789 -144.272) (xy 471.043 -144.018) (xy 471.043 -141.732) (xy 470.408 -141.097)
				(xy 470.027 -141.097) (xy 469.746838 -140.816838) (xy 469.746838 -140.181838) (xy 469.646 -140.081)
			)
		)
		(polygon
			(pts
				(xy 469.2396 -140.6652) (xy 469.0364 -140.6652) (xy 469.0364 -140.8684) (xy 469.2396 -140.8684)
			)
		)
	)
	(zone
		(layer "F.Cu")
		(hatch none 0.5)
		(connect_pads
			(clearance 0)
		)
		(min_thickness 0.25)
		(keepout
			(tracks allowed)
			(vias allowed)
			(pads allowed)
			(copperpour allowed)
			(footprints not_allowed)
		)
		(placement
			(enabled no)
			(sheetname "")
		)
		(fill
			(thermal_gap 0.5)
			(thermal_bridge_width 0.5)
			(island_removal_mode 0)
		)
		(polygon
			(pts
				(arc
					(start 386.675122 -293.800022)
					(mid 393.675108 -286.800036)
					(end 400.675094 -293.800022)
				)
				(arc
					(start 400.675094 -299.80001)
					(mid 393.675108 -306.799996)
					(end 386.675122 -299.80001)
				)
			)
		)
	)
	(zone
		(net "GND")
		(layer "F.Cu")
		(hatch none 0.5)
		(connect_pads
			(clearance 0.5)
		)
		(min_thickness 0.25)
		(fill yes
			(thermal_gap 0.5)
			(thermal_bridge_width 0.5)
			(island_removal_mode 0)
		)
		(polygon
			(pts
				(xy 311.088024 -93.339666)
				(arc
					(start 311.005474 -93.422216)
					(mid 311.017077 -93.710911)
					(end 311.020968 -93.999812)
				)
				(arc
					(start 311.020968 -99.994212)
					(mid 309.687903 -105.197307)
					(end 306.017168 -109.1184)
				)
				(arc
					(start 306.017168 -109.562646)
					(mid 306.582558 -109.744023)
					(end 307.115718 -110.005368)
				)
				(xy 307.691282 -110.005368) (xy 311.605676 -106.090974) (xy 311.605676 -93.527372) (xy 311.41797 -93.339666)
			)
		)
	)
	(zone
		(layer "F.Cu")
		(hatch none 0.5)
		(connect_pads
			(clearance 0)
		)
		(min_thickness 0.25)
		(keepout
			(tracks allowed)
			(vias allowed)
			(pads allowed)
			(copperpour allowed)
			(footprints allowed)
		)
		(placement
			(enabled no)
			(sheetname "")
		)
		(fill
			(thermal_gap 0.5)
			(thermal_bridge_width 0.5)
			(island_removal_mode 0)
		)
		(polygon
			(pts
				(xy 262.052308 -220.144594) (xy 262.052308 -221.211394) (xy 260.401308 -221.211394) (xy 260.401308 -220.144594)
			)
		)
	)
	(zone
		(net "P5V_HDD27")
		(layer "F.Cu")
		(hatch none 0.5)
		(connect_pads
			(clearance 0.5)
		)
		(min_thickness 0.25)
		(fill yes
			(thermal_gap 0.5)
			(thermal_bridge_width 0.5)
			(island_removal_mode 0)
		)
		(polygon
			(pts
				(xy 114.3 -27.686) (xy 114.046 -27.94) (xy 114.046 -30.226) (xy 114.3 -30.48) (xy 114.3 -32.512)
				(xy 115.062 -33.274) (xy 115.062 -34.204402) (xy 115.376198 -34.5186) (xy 115.9256 -34.5186) (xy 118.999 -37.592)
				(xy 125.857 -37.592) (xy 125.984 -37.465) (xy 125.984 -35.687) (xy 125.857 -35.56) (xy 120.777 -35.56)
				(xy 118.872 -33.655) (xy 117.983 -33.655) (xy 117.094 -32.766) (xy 117.094 -31.1658) (xy 117.729 -30.5308)
				(xy 117.729 -27.94) (xy 117.475 -27.686)
			)
		)
		(polygon
			(pts
				(xy 116.078 -34.1122) (xy 115.8748 -34.1122) (xy 115.8748 -34.3154) (xy 116.078 -34.3154)
			)
		)
		(polygon
			(pts
				(xy 116.078 -33.2486) (xy 115.8748 -33.2486) (xy 115.8748 -33.4518) (xy 116.078 -33.4518)
			)
		)
	)
	(zone
		(net "P5V_B_2")
		(layer "F.Cu")
		(hatch none 0.5)
		(connect_pads
			(clearance 0.5)
		)
		(min_thickness 0.25)
		(fill yes
			(thermal_gap 0.5)
			(thermal_bridge_width 0.5)
			(island_removal_mode 0)
		)
		(polygon
			(pts
				(xy 18.415 -21.844) (xy 18.161 -22.098) (xy 18.161 -24.384) (xy 18.415 -24.638) (xy 23.114 -24.638)
				(xy 23.368 -24.384) (xy 23.368 -22.098) (xy 23.114 -21.844)
			)
		)
	)
	(zone
		(net "GND")
		(layer "F.Cu")
		(hatch none 0.5)
		(connect_pads
			(clearance 0.5)
		)
		(min_thickness 0.25)
		(fill yes
			(thermal_gap 0.5)
			(thermal_bridge_width 0.5)
			(island_removal_mode 0)
		)
		(polygon
			(pts
				(arc
					(start 428.939706 -238.369348)
					(mid 429.675404 -238.648482)
					(end 430.344072 -239.063276)
				)
				(arc
					(start 430.979834 -239.063276)
					(mid 431.292 -239.051346)
					(end 431.604166 -239.063276)
				)
				(xy 434.493924 -239.063276) (xy 434.493924 -240.390934) (xy 435.636924 -241.533934) (xy 435.636924 -242.238276)
				(xy 435.636924 -244.171724) (xy 435.938676 -244.473476) (xy 436.654448 -244.473476) (xy 436.92064 -244.207284)
				(xy 436.92064 -238.280448) (xy 436.520336 -237.880144) (xy 428.944786 -237.880144) (xy 428.792132 -238.032798)
				(xy 428.783242 -238.032798) (xy 428.783242 -238.212884)
			)
		)
	)
	(zone
		(net "MB3_12V_CTRL_GATE3")
		(layer "F.Cu")
		(hatch none 0.5)
		(connect_pads
			(clearance 0.5)
		)
		(min_thickness 0.25)
		(fill yes
			(thermal_gap 0.5)
			(thermal_bridge_width 0.5)
			(island_removal_mode 0)
		)
		(polygon
			(pts
				(xy 263.256776 -336.521552) (xy 263.031986 -336.746342) (xy 260.425184 -336.746342) (xy 260.317996 -336.85353)
				(xy 260.317996 -338.052918) (xy 260.550152 -338.285074) (xy 265.327638 -338.285074) (xy 265.464036 -338.148676)
				(xy 265.464036 -336.666078) (xy 265.31951 -336.521552)
			)
		)
	)
	(zone
		(net "GND")
		(layer "F.Cu")
		(hatch none 0.5)
		(connect_pads
			(clearance 0.5)
		)
		(min_thickness 0.25)
		(fill yes
			(thermal_gap 0.5)
			(thermal_bridge_width 0.5)
			(island_removal_mode 0)
		)
		(polygon
			(pts
				(xy 168.78554 -155.132024) (xy 168.15308 -155.764484)
				(arc
					(start 168.15308 -162.970972)
					(mid 168.319645 -163.572614)
					(end 168.393872 -164.192458)
				)
				(arc
					(start 169.131234 -164.92982)
					(mid 173.418268 -168.285242)
					(end 170.574462 -172.927518)
				)
				(xy 170.24731 -173.25467) (xy 170.24731 -173.954694) (xy 170.929808 -174.637192) (xy 175.71339 -174.637192)
				(arc
					(start 176.220882 -174.1297)
					(mid 177.389084 -171.440489)
					(end 180.05679 -170.223942)
				)
				(xy 180.843936 -169.436796) (xy 180.843936 -166.79672) (xy 179.40274 -165.355524) (xy 177.747676 -165.355524)
				(arc
					(start 177.747676 -164.491416)
					(mid 176.698992 -163.09813)
					(end 176.326038 -161.394648)
				)
				(xy 170.063414 -155.132024)
			)
		)
	)
	(zone
		(net "P12V_B")
		(layer "F.Cu")
		(hatch none 0.5)
		(connect_pads
			(clearance 0.5)
		)
		(min_thickness 0.25)
		(fill yes
			(thermal_gap 0.5)
			(thermal_bridge_width 0.5)
			(island_removal_mode 0)
		)
		(polygon
			(pts
				(xy 334.518 -27.432) (xy 334.137 -27.813) (xy 334.137 -31.369) (xy 334.391 -31.623) (xy 337.566 -31.623)
				(xy 337.82 -31.369) (xy 337.82 -29.337) (xy 337.947 -29.21) (xy 338.328 -29.21) (xy 338.455 -29.083)
				(xy 338.455 -27.559) (xy 338.328 -27.432)
			)
		)
		(polygon
			(pts
				(xy 337.7946 -28.4226) (xy 337.5914 -28.4226) (xy 337.5914 -28.6258) (xy 337.7946 -28.6258)
			)
		)
		(polygon
			(pts
				(xy 337.8454 -27.9908) (xy 337.6422 -27.9908) (xy 337.6422 -28.194) (xy 337.8454 -28.194)
			)
		)
	)
	(zone
		(net "P12V_B")
		(layer "F.Cu")
		(hatch none 0.5)
		(connect_pads
			(clearance 0.5)
		)
		(min_thickness 0.25)
		(fill yes
			(thermal_gap 0.5)
			(thermal_bridge_width 0.5)
			(island_removal_mode 0)
		)
		(polygon
			(pts
				(xy 256.780538 -92.342208) (xy 256.49809 -92.624656) (xy 256.49809 -94.639384) (xy 256.71653 -94.857824)
				(xy 258.173474 -94.857824) (xy 258.468622 -94.562676) (xy 261.022084 -94.562676) (xy 261.644892 -93.939868)
				(xy 261.644892 -92.342208)
			)
		)
	)
	(zone
		(layer "F.Cu")
		(hatch none 0.5)
		(connect_pads
			(clearance 0)
		)
		(min_thickness 0.25)
		(keepout
			(tracks not_allowed)
			(vias allowed)
			(pads allowed)
			(copperpour not_allowed)
			(footprints allowed)
		)
		(placement
			(enabled no)
			(sheetname "")
		)
		(fill
			(thermal_gap 0.5)
			(thermal_bridge_width 0.5)
			(island_removal_mode 0)
		)
		(polygon
			(pts
				(arc
					(start 417.331906 -131.951984)
					(mid 416.846512 -132.436997)
					(end 417.331652 -132.922264)
				)
				(xy 417.744402 -132.922264)
				(arc
					(start 417.744402 -132.588)
					(mid 417.72253 -132.535196)
					(end 417.669726 -132.513324)
				)
				(arc
					(start 417.587176 -132.513324)
					(mid 417.065008 -132.437124)
					(end 417.587176 -132.360924)
				)
				(xy 417.701222 -132.360924)
				(arc
					(start 417.703762 -132.363464)
					(mid 417.830311 -132.427415)
					(end 417.894262 -132.553964)
				)
				(xy 417.896802 -132.556504) (xy 417.896802 -132.922264) (xy 418.036502 -132.922264) (xy 418.036502 -132.553202)
				(arc
					(start 418.039804 -132.5499)
					(mid 418.104536 -132.426036)
					(end 418.229542 -132.363464)
				)
				(xy 418.232082 -132.360924)
				(arc
					(start 418.346128 -132.360924)
					(mid 418.868296 -132.437124)
					(end 418.346128 -132.513324)
				)
				(arc
					(start 418.263578 -132.513324)
					(mid 418.210774 -132.535196)
					(end 418.188902 -132.588)
				)
				(xy 418.188902 -132.922264)
				(arc
					(start 418.601652 -132.922264)
					(mid 419.086792 -132.437124)
					(end 418.601652 -131.951984)
				)
			)
		)
	)
	(zone
		(layer "F.Cu")
		(hatch none 0.5)
		(connect_pads
			(clearance 0)
		)
		(min_thickness 0.25)
		(keepout
			(tracks allowed)
			(vias allowed)
			(pads allowed)
			(copperpour allowed)
			(footprints allowed)
		)
		(placement
			(enabled no)
			(sheetname "")
		)
		(fill
			(thermal_gap 0.5)
			(thermal_bridge_width 0.5)
			(island_removal_mode 0)
		)
		(polygon
			(pts
				(xy 460.267304 -374.4214) (xy 461.257904 -374.4214) (xy 462.172304 -374.4214) (xy 462.172304 -375.6406)
				(xy 460.267304 -375.6406) (xy 460.267304 -375.2088)
			)
		)
	)
	(zone
		(net "GATE_FAN3")
		(layer "F.Cu")
		(hatch none 0.5)
		(connect_pads
			(clearance 0.5)
		)
		(min_thickness 0.25)
		(fill yes
			(thermal_gap 0.5)
			(thermal_bridge_width 0.5)
			(island_removal_mode 0)
		)
		(polygon
			(pts
				(xy 430.282604 -357.8352) (xy 430.054004 -358.0638) (xy 430.054004 -361.2642) (xy 430.511204 -361.7214)
				(xy 431.75682 -361.7214) (xy 433.332382 -360.145838) (xy 433.991766 -360.145838) (xy 434.092604 -360.045)
				(xy 434.092604 -358.619552) (xy 433.982114 -358.509062) (xy 433.166266 -358.509062) (xy 432.492404 -357.8352)
			)
		)
		(polygon
			(pts
				(xy 433.559204 -359.4862) (xy 433.356004 -359.4862) (xy 433.356004 -359.6894) (xy 433.559204 -359.6894)
			)
		)
		(polygon
			(pts
				(xy 433.559204 -358.9655) (xy 433.356004 -358.9655) (xy 433.356004 -359.1687) (xy 433.559204 -359.1687)
			)
		)
	)
	(zone
		(layer "F.Cu")
		(hatch none 0.5)
		(connect_pads
			(clearance 0)
		)
		(min_thickness 0.25)
		(keepout
			(tracks allowed)
			(vias allowed)
			(pads allowed)
			(copperpour allowed)
			(footprints not_allowed)
		)
		(placement
			(enabled no)
			(sheetname "")
		)
		(fill
			(thermal_gap 0.5)
			(thermal_bridge_width 0.5)
			(island_removal_mode 0)
		)
		(polygon
			(pts
				(xy 180.64988 -266.800076) (xy 180.64988 -276.800056) (xy 191.799972 -276.800056) (xy 191.799972 -326.799956)
				(xy 0 -326.799956) (xy 0 -276.800056) (xy 8.349996 -276.800056) (xy 8.349996 -266.800076) (xy 22.899878 -266.800076)
				(xy 22.899878 -276.800056) (xy 39.900098 -276.800056) (xy 39.900098 -266.800076) (xy 54.44998 -266.800076)
				(xy 54.44998 -276.800056) (xy 71.449946 -276.800056) (xy 71.449946 -266.800076) (xy 86.000082 -266.800076)
				(xy 86.000082 -276.800056) (xy 103.000048 -276.800056) (xy 103.000048 -266.800076) (xy 117.54993 -266.800076)
				(xy 117.54993 -276.800056) (xy 134.549896 -276.800056) (xy 134.549896 -266.800076) (xy 149.100032 -266.800076)
				(xy 149.100032 -276.800056) (xy 166.099998 -276.800056) (xy 166.099998 -266.800076)
			)
		)
	)
	(zone
		(net "12V_PRE_25")
		(layer "F.Cu")
		(hatch none 0.5)
		(connect_pads
			(clearance 0.5)
		)
		(min_thickness 0.25)
		(fill yes
			(thermal_gap 0.5)
			(thermal_bridge_width 0.5)
			(island_removal_mode 0)
		)
		(polygon
			(pts
				(xy 51.181 -34.798) (xy 51.054 -34.925) (xy 51.054 -36.449) (xy 52.451 -37.846) (xy 53.848 -37.846)
				(xy 58.801 -42.799) (xy 62.738 -42.799) (xy 62.865 -42.672) (xy 62.865 -41.91) (xy 62.738 -41.783)
				(xy 59.436 -41.783) (xy 52.451 -34.798)
			)
		)
	)
	(zone
		(net "P5V_B_1")
		(layer "F.Cu")
		(hatch none 0.5)
		(connect_pads
			(clearance 0.5)
		)
		(min_thickness 0.25)
		(fill yes
			(thermal_gap 0.5)
			(thermal_bridge_width 0.5)
			(island_removal_mode 0)
		)
		(polygon
			(pts
				(xy 113.03 -251.841) (xy 112.776 -252.095) (xy 112.776 -254.381) (xy 113.03 -254.635) (xy 117.729 -254.635)
				(xy 117.983 -254.381) (xy 117.983 -252.095) (xy 117.729 -251.841)
			)
		)
	)
	(zone
		(net "P12V_HDD9")
		(layer "F.Cu")
		(hatch none 0.5)
		(connect_pads
			(clearance 0.5)
		)
		(min_thickness 0.25)
		(fill yes
			(thermal_gap 0.5)
			(thermal_bridge_width 0.5)
			(island_removal_mode 0)
		)
		(polygon
			(pts
				(xy 429.26 -264.541) (xy 429.006 -264.795) (xy 429.006 -268.859) (xy 428.6123 -269.2527) (xy 428.6123 -271.7927)
				(xy 427.355 -273.05) (xy 420.878 -273.05) (xy 420.624 -273.304) (xy 420.624 -274.955) (xy 420.878 -275.209)
				(xy 424.815 -275.209) (xy 425.323 -274.701) (xy 433.07 -274.701) (xy 433.959 -273.812) (xy 433.959 -264.795)
				(xy 433.705 -264.541)
			)
		)
		(polygon
			(pts
				(xy 424.9674 -274.0914) (xy 424.7642 -274.0914) (xy 424.7642 -274.2946) (xy 424.9674 -274.2946)
			)
		)
		(polygon
			(pts
				(xy 424.1038 -274.0914) (xy 423.9006 -274.0914) (xy 423.9006 -274.2946) (xy 424.1038 -274.2946)
			)
		)
	)
	(zone
		(net "P5V_HDD25")
		(layer "F.Cu")
		(hatch none 0.5)
		(connect_pads
			(clearance 0.5)
		)
		(min_thickness 0.25)
		(fill yes
			(thermal_gap 0.5)
			(thermal_bridge_width 0.5)
			(island_removal_mode 0)
		)
		(polygon
			(pts
				(xy 51.3842 -27.686) (xy 51.1683 -27.9019) (xy 51.1683 -30.4673) (xy 51.181 -30.48) (xy 51.181 -32.512)
				(xy 51.943 -33.274) (xy 51.943 -34.170366) (xy 52.189634 -34.417) (xy 52.705 -34.417) (xy 55.88 -37.592)
				(xy 62.738 -37.592) (xy 62.865 -37.465) (xy 62.865 -35.687) (xy 62.738 -35.56) (xy 57.658 -35.56)
				(xy 55.753 -33.655) (xy 54.864 -33.655) (xy 53.975 -32.766) (xy 53.975 -30.226) (xy 54.61 -29.591)
				(xy 54.61 -27.94) (xy 54.356 -27.686)
			)
		)
		(polygon
			(pts
				(xy 53.0098 -34.1122) (xy 52.8066 -34.1122) (xy 52.8066 -34.3154) (xy 53.0098 -34.3154)
			)
		)
		(polygon
			(pts
				(xy 53.0098 -33.2486) (xy 52.8066 -33.2486) (xy 52.8066 -33.4518) (xy 53.0098 -33.4518)
			)
		)
	)
	(zone
		(net "VCCP_IN")
		(layer "F.Cu")
		(hatch none 0.5)
		(connect_pads
			(clearance 0.5)
		)
		(min_thickness 0.25)
		(fill yes
			(thermal_gap 0.5)
			(thermal_bridge_width 0.5)
			(island_removal_mode 0)
		)
		(polygon
			(pts
				(xy 266.119356 -357.546656) (xy 265.9888 -357.676958) (xy 265.9888 -358.6734) (xy 266.3952 -359.0798)
				(xy 266.3952 -360.4006) (xy 266.573 -360.5784) (xy 266.573 -362.585) (xy 266.065 -363.093) (xy 266.065 -364.363)
				(xy 266.192 -364.49) (xy 267.97 -364.49) (xy 268.097 -364.363) (xy 268.097 -357.759) (xy 267.884656 -357.546656)
			)
		)
		(polygon
			(pts
				(xy 267.3604 -360.2482) (xy 267.1572 -360.2482) (xy 267.1572 -360.4514) (xy 267.3604 -360.4514)
			)
		)
		(polygon
			(pts
				(xy 267.3604 -359.3846) (xy 267.1572 -359.3846) (xy 267.1572 -359.5878) (xy 267.3604 -359.5878)
			)
		)
	)
	(zone
		(layer "F.Cu")
		(hatch none 0.5)
		(connect_pads
			(clearance 0)
		)
		(min_thickness 0.25)
		(keepout
			(tracks allowed)
			(vias allowed)
			(pads allowed)
			(copperpour allowed)
			(footprints allowed)
		)
		(placement
			(enabled no)
			(sheetname "")
		)
		(fill
			(thermal_gap 0.5)
			(thermal_bridge_width 0.5)
			(island_removal_mode 0)
		)
		(polygon
			(pts
				(xy 189.2808 -249.6058) (xy 190.3984 -249.6058) (xy 190.5 -249.5042) (xy 190.5 -248.0564) (xy 190.1952 -247.7516)
				(xy 189.3062 -247.7516) (xy 188.976 -248.0818) (xy 188.976 -249.301)
			)
		)
	)
	(zone
		(net "P5V_HDD20")
		(layer "F.Cu")
		(hatch none 0.5)
		(connect_pads
			(clearance 0.5)
		)
		(min_thickness 0.25)
		(fill yes
			(thermal_gap 0.5)
			(thermal_bridge_width 0.5)
			(island_removal_mode 0)
		)
		(polygon
			(pts
				(xy 394.716 -137.795) (xy 394.462 -138.049) (xy 394.462 -148.844) (xy 392.811 -150.495) (xy 389.382 -150.495)
				(xy 389.128 -150.749) (xy 389.128 -152.4) (xy 389.382 -152.654) (xy 393.954 -152.654) (xy 394.589 -152.019)
				(xy 396.367 -152.019) (xy 396.875 -151.511) (xy 396.875 -138.049) (xy 396.621 -137.795)
			)
		)
		(polygon
			(pts
				(xy 393.4714 -151.6634) (xy 393.2682 -151.6634) (xy 393.2682 -151.8666) (xy 393.4714 -151.8666)
			)
		)
		(polygon
			(pts
				(xy 392.6078 -151.6634) (xy 392.4046 -151.6634) (xy 392.4046 -151.8666) (xy 392.6078 -151.8666)
			)
		)
	)
	(zone
		(layer "F.Cu")
		(hatch none 0.5)
		(connect_pads
			(clearance 0)
		)
		(min_thickness 0.25)
		(keepout
			(tracks not_allowed)
			(vias allowed)
			(pads allowed)
			(copperpour not_allowed)
			(footprints allowed)
		)
		(placement
			(enabled no)
			(sheetname "")
		)
		(fill
			(thermal_gap 0.5)
			(thermal_bridge_width 0.5)
			(island_removal_mode 0)
		)
		(polygon
			(pts
				(arc
					(start 159.193992 -248.115074)
					(mid 158.708852 -247.629934)
					(end 158.223712 -248.115074)
				)
				(xy 158.223712 -248.527824)
				(arc
					(start 158.581852 -248.527824)
					(mid 158.617773 -248.512945)
					(end 158.632652 -248.477024)
				)
				(arc
					(start 158.632652 -248.370598)
					(mid 158.708852 -247.84843)
					(end 158.785052 -248.370598)
				)
				(xy 158.785052 -248.50852)
				(arc
					(start 158.782004 -248.511568)
					(mid 158.725473 -248.620645)
					(end 158.616396 -248.677176)
				)
				(xy 158.613348 -248.680224) (xy 158.223712 -248.680224) (xy 158.223712 -248.819924) (xy 158.613348 -248.819924)
				(arc
					(start 158.616396 -248.822972)
					(mid 158.725473 -248.879503)
					(end 158.782004 -248.98858)
				)
				(xy 158.785052 -248.991628)
				(arc
					(start 158.785052 -249.12955)
					(mid 158.708852 -249.651718)
					(end 158.632652 -249.12955)
				)
				(arc
					(start 158.632652 -249.023124)
					(mid 158.617773 -248.987203)
					(end 158.581852 -248.972324)
				)
				(xy 158.223712 -248.972324)
				(arc
					(start 158.223712 -249.38482)
					(mid 158.708725 -249.870214)
					(end 159.193992 -249.385074)
				)
			)
		)
	)
	(zone
		(net "P12V_HDD10")
		(layer "F.Cu")
		(hatch none 0.5)
		(connect_pads
			(clearance 0.5)
		)
		(min_thickness 0.25)
		(fill yes
			(thermal_gap 0.5)
			(thermal_bridge_width 0.5)
			(island_removal_mode 0)
		)
		(polygon
			(pts
				(xy 460.756 -264.541) (xy 460.502 -264.795) (xy 460.502 -268.859) (xy 460.0575 -269.3035) (xy 460.0575 -271.9451)
				(xy 458.9526 -273.05) (xy 452.374 -273.05) (xy 452.12 -273.304) (xy 452.12 -274.955) (xy 452.374 -275.209)
				(xy 456.311 -275.209) (xy 456.819 -274.701) (xy 464.566 -274.701) (xy 465.455 -273.812) (xy 465.455 -264.795)
				(xy 465.201 -264.541)
			)
		)
		(polygon
			(pts
				(xy 456.4634 -274.0914) (xy 456.2602 -274.0914) (xy 456.2602 -274.2946) (xy 456.4634 -274.2946)
			)
		)
		(polygon
			(pts
				(xy 455.5998 -274.0914) (xy 455.3966 -274.0914) (xy 455.3966 -274.2946) (xy 455.5998 -274.2946)
			)
		)
	)
	(zone
		(net "P3V3_IN")
		(layer "F.Cu")
		(hatch none 0.5)
		(connect_pads
			(clearance 0.5)
		)
		(min_thickness 0.25)
		(fill yes
			(thermal_gap 0.5)
			(thermal_bridge_width 0.5)
			(island_removal_mode 0)
		)
		(polygon
			(pts
				(xy 282.321 -336.55) (xy 282.067 -336.804) (xy 282.067 -339.725) (xy 282.194 -339.852) (xy 283.718 -339.852)
				(xy 284.099 -339.471) (xy 284.099 -336.804) (xy 283.845 -336.55)
			)
		)
		(polygon
			(pts
				(xy 283.1846 -337.5152) (xy 282.9814 -337.5152) (xy 282.9814 -337.7184) (xy 283.1846 -337.7184)
			)
		)
	)
	(zone
		(net "P5V_HDD18")
		(layer "F.Cu")
		(hatch none 0.5)
		(connect_pads
			(clearance 0.5)
		)
		(min_thickness 0.25)
		(fill yes
			(thermal_gap 0.5)
			(thermal_bridge_width 0.5)
			(island_removal_mode 0)
		)
		(polygon
			(pts
				(xy 331.597 -137.795) (xy 331.343 -138.049) (xy 331.343 -148.844) (xy 329.692 -150.495) (xy 326.263 -150.495)
				(xy 326.009 -150.749) (xy 326.009 -152.4) (xy 326.263 -152.654) (xy 330.835 -152.654) (xy 331.47 -152.019)
				(xy 333.248 -152.019) (xy 333.756 -151.511) (xy 333.756 -138.049) (xy 333.502 -137.795)
			)
		)
		(polygon
			(pts
				(xy 330.3524 -151.6634) (xy 330.1492 -151.6634) (xy 330.1492 -151.8666) (xy 330.3524 -151.8666)
			)
		)
		(polygon
			(pts
				(xy 329.4888 -151.6634) (xy 329.2856 -151.6634) (xy 329.2856 -151.8666) (xy 329.4888 -151.8666)
			)
		)
	)
	(zone
		(layer "F.Cu")
		(hatch none 0.5)
		(connect_pads
			(clearance 0)
		)
		(min_thickness 0.25)
		(keepout
			(tracks allowed)
			(vias allowed)
			(pads allowed)
			(copperpour allowed)
			(footprints allowed)
		)
		(placement
			(enabled no)
			(sheetname "")
		)
		(fill
			(thermal_gap 0.5)
			(thermal_bridge_width 0.5)
			(island_removal_mode 0)
		)
		(polygon
			(pts
				(xy 244.856 -139.065) (xy 244.856 -140.1318) (xy 243.205 -140.1318) (xy 243.205 -139.065)
			)
		)
	)
	(zone
		(layer "F.Cu")
		(hatch none 0.5)
		(connect_pads
			(clearance 0)
		)
		(min_thickness 0.25)
		(keepout
			(tracks not_allowed)
			(vias allowed)
			(pads allowed)
			(copperpour not_allowed)
			(footprints allowed)
		)
		(placement
			(enabled no)
			(sheetname "")
		)
		(fill
			(thermal_gap 0.5)
			(thermal_bridge_width 0.5)
			(island_removal_mode 0)
		)
		(polygon
			(pts
				(arc
					(start 34.770822 -14.41958)
					(mid 34.285809 -13.934186)
					(end 33.800542 -14.419326)
				)
				(xy 33.800542 -14.768576)
				(arc
					(start 34.126678 -14.768576)
					(mid 34.185229 -14.744323)
					(end 34.209482 -14.685772)
				)
				(arc
					(start 34.209482 -14.67485)
					(mid 34.285682 -14.152682)
					(end 34.361882 -14.67485)
				)
				(xy 34.361882 -14.717268)
				(arc
					(start 34.359342 -14.719808)
					(mid 34.292947 -14.852041)
					(end 34.160714 -14.918436)
				)
				(xy 34.158174 -14.920976) (xy 33.800542 -14.920976) (xy 33.800542 -15.060676) (xy 34.158174 -15.060676)
				(arc
					(start 34.160714 -15.063216)
					(mid 34.292947 -15.129611)
					(end 34.359342 -15.261844)
				)
				(xy 34.361882 -15.264384)
				(arc
					(start 34.361882 -15.306802)
					(mid 34.285682 -15.82897)
					(end 34.209482 -15.306802)
				)
				(arc
					(start 34.209482 -15.29588)
					(mid 34.185229 -15.237329)
					(end 34.126678 -15.213076)
				)
				(xy 33.800542 -15.213076)
				(arc
					(start 33.800542 -15.562326)
					(mid 34.285682 -16.047466)
					(end 34.770822 -15.562326)
				)
			)
		)
	)
	(zone
		(layer "F.Cu")
		(hatch none 0.5)
		(connect_pads
			(clearance 0)
		)
		(min_thickness 0.25)
		(keepout
			(tracks not_allowed)
			(vias allowed)
			(pads allowed)
			(copperpour not_allowed)
			(footprints allowed)
		)
		(placement
			(enabled no)
			(sheetname "")
		)
		(fill
			(thermal_gap 0.5)
			(thermal_bridge_width 0.5)
			(island_removal_mode 0)
		)
		(polygon
			(pts
				(arc
					(start 32.994092 -18.11528)
					(mid 32.509079 -17.629886)
					(end 32.023812 -18.115026)
				)
				(xy 32.023812 -18.527776)
				(arc
					(start 32.381952 -18.527776)
					(mid 32.417873 -18.512897)
					(end 32.432752 -18.476976)
				)
				(arc
					(start 32.432752 -18.37055)
					(mid 32.508952 -17.848382)
					(end 32.585152 -18.37055)
				)
				(xy 32.585152 -18.508472)
				(arc
					(start 32.582104 -18.51152)
					(mid 32.525573 -18.620597)
					(end 32.416496 -18.677128)
				)
				(xy 32.413448 -18.680176) (xy 32.023812 -18.680176) (xy 32.023812 -18.819876) (xy 32.413448 -18.819876)
				(arc
					(start 32.416496 -18.822924)
					(mid 32.525573 -18.879455)
					(end 32.582104 -18.988532)
				)
				(xy 32.585152 -18.99158)
				(arc
					(start 32.585152 -19.129502)
					(mid 32.508952 -19.65167)
					(end 32.432752 -19.129502)
				)
				(arc
					(start 32.432752 -19.023076)
					(mid 32.417873 -18.987155)
					(end 32.381952 -18.972276)
				)
				(xy 32.023812 -18.972276)
				(arc
					(start 32.023812 -19.385026)
					(mid 32.508952 -19.870166)
					(end 32.994092 -19.385026)
				)
			)
		)
	)
	(zone
		(layer "F.Cu")
		(hatch none 0.5)
		(connect_pads
			(clearance 0)
		)
		(min_thickness 0.25)
		(keepout
			(tracks allowed)
			(vias allowed)
			(pads allowed)
			(copperpour allowed)
			(footprints allowed)
		)
		(placement
			(enabled no)
			(sheetname "")
		)
		(fill
			(thermal_gap 0.5)
			(thermal_bridge_width 0.5)
			(island_removal_mode 0)
		)
		(polygon
			(pts
				(xy 244.729 -305.4858) (xy 246.1006 -305.4858) (xy 246.1006 -308.0004) (xy 244.729 -308.0004)
			)
		)
	)
	(zone
		(net "MB3_CM_GATE_C")
		(layer "F.Cu")
		(hatch none 0.5)
		(connect_pads
			(clearance 0.5)
		)
		(min_thickness 0.25)
		(fill yes
			(thermal_gap 0.5)
			(thermal_bridge_width 0.5)
			(island_removal_mode 0)
		)
		(polygon
			(pts
				(xy 261.954772 -352.701606) (xy 261.827772 -352.828606) (xy 261.827772 -354.022406) (xy 262.054086 -354.24872)
				(xy 265.074654 -354.24872) (xy 265.400028 -353.923346) (xy 265.400028 -353.009962) (xy 265.098276 -352.70821)
				(xy 262.659622 -352.70821) (xy 262.653018 -352.701606)
			)
		)
		(polygon
			(pts
				(xy 262.797036 -353.804728) (xy 262.593836 -353.804728) (xy 262.593836 -354.007928) (xy 262.797036 -354.007928)
			)
		)
		(polygon
			(pts
				(xy 262.797036 -352.941128) (xy 262.593836 -352.941128) (xy 262.593836 -353.144328) (xy 262.797036 -353.144328)
			)
		)
	)
	(zone
		(layer "F.Cu")
		(hatch none 0.5)
		(connect_pads
			(clearance 0)
		)
		(min_thickness 0.25)
		(keepout
			(tracks allowed)
			(vias allowed)
			(pads allowed)
			(copperpour allowed)
			(footprints allowed)
		)
		(placement
			(enabled no)
			(sheetname "")
		)
		(fill
			(thermal_gap 0.5)
			(thermal_bridge_width 0.5)
			(island_removal_mode 0)
		)
		(polygon
			(pts
				(xy 235.633768 -195.239894) (xy 235.633768 -197.754494) (xy 234.058968 -197.754494) (xy 234.058968 -195.239894)
			)
		)
	)
	(zone
		(layer "F.Cu")
		(hatch none 0.5)
		(connect_pads
			(clearance 0)
		)
		(min_thickness 0.25)
		(keepout
			(tracks allowed)
			(vias allowed)
			(pads allowed)
			(copperpour allowed)
			(footprints not_allowed)
		)
		(placement
			(enabled no)
			(sheetname "")
		)
		(fill
			(thermal_gap 0.5)
			(thermal_bridge_width 0.5)
			(island_removal_mode 0)
		)
		(polygon
			(pts
				(xy 252.000004 -370.000022) (xy 252.000004 -380.000002) (xy 198.000112 -380.000002) (xy 198.000112 -370.000022)
			)
		)
	)
	(zone
		(net "P12V_B")
		(layer "F.Cu")
		(hatch none 0.5)
		(connect_pads
			(clearance 0.5)
		)
		(min_thickness 0.25)
		(fill yes
			(thermal_gap 0.5)
			(thermal_bridge_width 0.5)
			(island_removal_mode 0)
		)
		(polygon
			(pts
				(xy 170.148758 -139.54887) (xy 169.926 -139.771628) (xy 169.926 -144.018) (xy 170.18 -144.272) (xy 173.482 -144.272)
				(xy 173.736 -144.018) (xy 173.736 -141.732) (xy 173.101 -141.097) (xy 172.72 -141.097) (xy 172.466 -140.843)
				(xy 172.466 -140.208) (xy 172.339 -140.081) (xy 171.652184 -140.081) (xy 171.120054 -139.54887)
			)
		)
		(polygon
			(pts
				(xy 171.9326 -140.6652) (xy 171.7294 -140.6652) (xy 171.7294 -140.8684) (xy 171.9326 -140.8684)
			)
		)
	)
	(zone
		(net "GND")
		(layer "F.Cu")
		(hatch none 0.5)
		(connect_pads
			(clearance 0.5)
		)
		(min_thickness 0.25)
		(fill yes
			(thermal_gap 0.5)
			(thermal_bridge_width 0.5)
			(island_removal_mode 0)
		)
		(polygon
			(pts
				(xy 33.84169 -230.226108) (xy 33.63722 -230.430578)
				(arc
					(start 33.63722 -230.566976)
					(mid 33.719596 -232.015468)
					(end 33.306258 -233.406188)
				)
				(arc
					(start 33.306258 -234.517184)
					(mid 33.9757 -235.779399)
					(end 34.170112 -237.194852)
				)
				(xy 35.01771 -238.04245) (xy 35.01771 -239.009682)
				(arc
					(start 35.546284 -239.538256)
					(mid 37.576064 -241.015563)
					(end 38.351206 -243.403374)
				)
				(arc
					(start 38.351206 -246.578374)
					(mid 37.879683 -248.478869)
					(end 36.574476 -249.93854)
				)
				(arc
					(start 36.574476 -250.401328)
					(mid 36.411987 -251.53897)
					(end 35.937698 -252.585728)
				)
				(arc
					(start 35.937698 -252.585728)
					(mid 35.63185 -253.717092)
					(end 35.01771 -254.715264)
				)
				(xy 35.01771 -256.549398)
				(arc
					(start 35.619436 -257.151124)
					(mid 37.01673 -257.349877)
					(end 38.263322 -258.011676)
				)
				(xy 39.17696 -258.011676) (xy 39.939976 -257.24866) (xy 39.939976 -253.680976) (xy 41.285414 -253.680976)
				(xy 41.908476 -253.057914) (xy 41.908476 -251.407676) (xy 41.959276 -251.407676)
				(arc
					(start 41.959276 -250.74753)
					(mid 41.309552 -249.385013)
					(end 41.198292 -247.879616)
				)
				(arc
					(start 41.198292 -247.167146)
					(mid 41.393198 -245.923601)
					(end 41.959276 -244.799358)
				)
				(xy 41.959276 -242.543076) (xy 43.838876 -242.543076) (xy 44.194476 -242.187476) (xy 45.870876 -242.187476)
				(xy 45.947076 -242.111276)
				(arc
					(start 49.713134 -242.111276)
					(mid 51.2064 -241.832659)
					(end 52.699666 -242.111276)
				)
				(xy 54.278784 -242.111276) (xy 54.643782 -241.746278) (xy 54.643782 -232.568242) (xy 53.95341 -231.87787)
				(arc
					(start 53.071776 -231.87787)
					(mid 51.576474 -233.852479)
					(end 49.215802 -234.602274)
				)
				(arc
					(start 46.900338 -234.602274)
					(mid 46.166945 -236.238454)
					(end 44.80433 -237.403894)
				)
				(arc
					(start 44.80433 -237.403894)
					(mid 43.384966 -238.525969)
					(end 41.62044 -238.926116)
				)
				(arc
					(start 40.60444 -238.926116)
					(mid 38.865494 -238.538153)
					(end 37.456364 -237.447836)
				)
				(arc
					(start 37.456364 -237.447836)
					(mid 35.804914 -235.939417)
					(end 35.193478 -233.78795)
				)
				(arc
					(start 35.193478 -232.771442)
					(mid 35.265121 -232.009436)
					(end 35.47745 -231.274112)
				)
				(xy 35.47745 -230.87203) (xy 34.831528 -230.226108)
			)
		)
	)
	(zone
		(layer "F.Cu")
		(hatch none 0.5)
		(connect_pads
			(clearance 0)
		)
		(min_thickness 0.25)
		(keepout
			(tracks allowed)
			(vias allowed)
			(pads allowed)
			(copperpour allowed)
			(footprints allowed)
		)
		(placement
			(enabled no)
			(sheetname "")
		)
		(fill
			(thermal_gap 0.5)
			(thermal_bridge_width 0.5)
			(island_removal_mode 0)
		)
		(polygon
			(pts
				(xy 29.863796 -378.2695) (xy 29.863796 -377.2789) (xy 29.863796 -376.3645) (xy 31.082996 -376.3645)
				(xy 31.082996 -378.2695) (xy 30.651196 -378.2695)
			)
		)
	)
	(zone
		(net "MB0_12V_CTRL_GATE6")
		(layer "F.Cu")
		(hatch none 0.5)
		(connect_pads
			(clearance 0.5)
		)
		(min_thickness 0.25)
		(fill yes
			(thermal_gap 0.5)
			(thermal_bridge_width 0.5)
			(island_removal_mode 0)
		)
		(polygon
			(pts
				(xy 204.97546 -355.219) (xy 204.908912 -355.285548) (xy 204.908912 -357.94696) (xy 205.155292 -358.19334)
				(xy 209.46618 -358.19334) (xy 209.658712 -358.000808) (xy 209.658712 -355.382068) (xy 209.495644 -355.219)
			)
		)
	)
	(zone
		(net "AGND_P5V_B_3")
		(layer "F.Cu")
		(hatch none 0.5)
		(connect_pads
			(clearance 0.5)
		)
		(min_thickness 0.25)
		(fill yes
			(thermal_gap 0.5)
			(thermal_bridge_width 0.5)
			(island_removal_mode 0)
		)
		(polygon
			(pts
				(xy 454.83907 -229.662482) (xy 454.31964 -230.181912) (xy 454.31964 -231.297988) (xy 454.523602 -231.50195)
				(xy 456.885802 -231.50195) (xy 457.317602 -231.07015) (xy 457.317602 -230.651812) (xy 457.783184 -230.18623)
				(xy 457.783184 -229.733094) (xy 457.712572 -229.662482)
			)
		)
		(polygon
			(pts
				(xy 454.980802 -231.14635) (xy 454.777602 -231.14635) (xy 454.777602 -231.34955) (xy 454.980802 -231.34955)
			)
		)
		(polygon
			(pts
				(xy 454.980802 -230.58755) (xy 454.777602 -230.58755) (xy 454.777602 -230.79075) (xy 454.980802 -230.79075)
			)
		)
		(polygon
			(pts
				(xy 457.32573 -230.141018) (xy 457.12253 -230.141018) (xy 457.12253 -230.344218) (xy 457.32573 -230.344218)
			)
		)
		(polygon
			(pts
				(xy 456.7428 -230.11892) (xy 456.5396 -230.11892) (xy 456.5396 -230.32212) (xy 456.7428 -230.32212)
			)
		)
		(polygon
			(pts
				(xy 456.184 -230.11892) (xy 455.9808 -230.11892) (xy 455.9808 -230.32212) (xy 456.184 -230.32212)
			)
		)
		(polygon
			(pts
				(xy 455.692002 -230.10495) (xy 455.488802 -230.10495) (xy 455.488802 -230.30815) (xy 455.692002 -230.30815)
			)
		)
		(polygon
			(pts
				(xy 455.133202 -230.10495) (xy 454.930002 -230.10495) (xy 454.930002 -230.30815) (xy 455.133202 -230.30815)
			)
		)
	)
	(zone
		(layer "F.Cu")
		(hatch none 0.5)
		(connect_pads
			(clearance 0)
		)
		(min_thickness 0.25)
		(keepout
			(tracks not_allowed)
			(vias allowed)
			(pads allowed)
			(copperpour not_allowed)
			(footprints allowed)
		)
		(placement
			(enabled no)
			(sheetname "")
		)
		(fill
			(thermal_gap 0.5)
			(thermal_bridge_width 0.5)
			(island_removal_mode 0)
		)
		(polygon
			(pts
				(arc
					(start 192.520824 -14.41958)
					(mid 192.035811 -13.934186)
					(end 191.550544 -14.419326)
				)
				(xy 191.550544 -14.768576)
				(arc
					(start 191.87668 -14.768576)
					(mid 191.935231 -14.744323)
					(end 191.959484 -14.685772)
				)
				(arc
					(start 191.959484 -14.67485)
					(mid 192.035684 -14.152682)
					(end 192.111884 -14.67485)
				)
				(xy 192.111884 -14.717268)
				(arc
					(start 192.109344 -14.719808)
					(mid 192.042949 -14.852041)
					(end 191.910716 -14.918436)
				)
				(xy 191.908176 -14.920976) (xy 191.550544 -14.920976) (xy 191.550544 -15.060676) (xy 191.908176 -15.060676)
				(arc
					(start 191.910716 -15.063216)
					(mid 192.042949 -15.129611)
					(end 192.109344 -15.261844)
				)
				(xy 192.111884 -15.264384)
				(arc
					(start 192.111884 -15.306802)
					(mid 192.035684 -15.82897)
					(end 191.959484 -15.306802)
				)
				(arc
					(start 191.959484 -15.29588)
					(mid 191.935231 -15.237329)
					(end 191.87668 -15.213076)
				)
				(xy 191.550544 -15.213076)
				(arc
					(start 191.550544 -15.562326)
					(mid 192.035684 -16.047466)
					(end 192.520824 -15.562326)
				)
			)
		)
	)
	(zone
		(layer "F.Cu")
		(hatch none 0.5)
		(connect_pads
			(clearance 0)
		)
		(min_thickness 0.25)
		(keepout
			(tracks not_allowed)
			(vias allowed)
			(pads allowed)
			(copperpour not_allowed)
			(footprints allowed)
		)
		(placement
			(enabled no)
			(sheetname "")
		)
		(fill
			(thermal_gap 0.5)
			(thermal_bridge_width 0.5)
			(island_removal_mode 0)
		)
		(polygon
			(pts
				(arc
					(start 127.64389 -18.11528)
					(mid 127.158877 -17.629886)
					(end 126.67361 -18.115026)
				)
				(xy 126.67361 -18.527776)
				(arc
					(start 127.03175 -18.527776)
					(mid 127.067671 -18.512897)
					(end 127.08255 -18.476976)
				)
				(arc
					(start 127.08255 -18.37055)
					(mid 127.15875 -17.848382)
					(end 127.23495 -18.37055)
				)
				(xy 127.23495 -18.508472)
				(arc
					(start 127.231902 -18.51152)
					(mid 127.175371 -18.620597)
					(end 127.066294 -18.677128)
				)
				(xy 127.063246 -18.680176) (xy 126.67361 -18.680176) (xy 126.67361 -18.819876) (xy 127.063246 -18.819876)
				(arc
					(start 127.066294 -18.822924)
					(mid 127.175371 -18.879455)
					(end 127.231902 -18.988532)
				)
				(xy 127.23495 -18.99158)
				(arc
					(start 127.23495 -19.129502)
					(mid 127.15875 -19.65167)
					(end 127.08255 -19.129502)
				)
				(arc
					(start 127.08255 -19.023076)
					(mid 127.067671 -18.987155)
					(end 127.03175 -18.972276)
				)
				(xy 126.67361 -18.972276)
				(arc
					(start 126.67361 -19.385026)
					(mid 127.15875 -19.870166)
					(end 127.64389 -19.385026)
				)
			)
		)
	)
	(zone
		(layer "F.Cu")
		(hatch none 0.5)
		(connect_pads
			(clearance 0)
		)
		(min_thickness 0.25)
		(keepout
			(tracks allowed)
			(vias allowed)
			(pads allowed)
			(copperpour allowed)
			(footprints allowed)
		)
		(placement
			(enabled no)
			(sheetname "")
		)
		(fill
			(thermal_gap 0.5)
			(thermal_bridge_width 0.5)
			(island_removal_mode 0)
		)
		(polygon
			(pts
				(xy 63.2206 -249.6058) (xy 64.3382 -249.6058) (xy 64.4398 -249.5042) (xy 64.4398 -248.0564) (xy 64.135 -247.7516)
				(xy 63.246 -247.7516) (xy 62.9158 -248.0818) (xy 62.9158 -249.301)
			)
		)
	)
	(zone
		(net "P5V_HDD23")
		(layer "F.Cu")
		(hatch none 0.5)
		(connect_pads
			(clearance 0.5)
		)
		(min_thickness 0.25)
		(fill yes
			(thermal_gap 0.5)
			(thermal_bridge_width 0.5)
			(island_removal_mode 0)
		)
		(polygon
			(pts
				(xy 474.726 -142.621) (xy 474.472 -142.875) (xy 474.472 -145.161) (xy 474.726 -145.415) (xy 474.726 -147.447)
				(xy 475.488 -148.209) (xy 475.488 -148.971) (xy 475.869 -149.352) (xy 476.25 -149.352) (xy 479.425 -152.527)
				(xy 486.283 -152.527) (xy 486.41 -152.4) (xy 486.41 -150.622) (xy 486.283 -150.495) (xy 481.203 -150.495)
				(xy 479.298 -148.59) (xy 478.409 -148.59) (xy 477.52 -147.701) (xy 477.52 -145.161) (xy 478.155 -144.526)
				(xy 478.155 -142.875) (xy 477.901 -142.621)
			)
		)
		(polygon
			(pts
				(xy 476.6056 -149.0472) (xy 476.4024 -149.0472) (xy 476.4024 -149.2504) (xy 476.6056 -149.2504)
			)
		)
		(polygon
			(pts
				(xy 476.6056 -148.1836) (xy 476.4024 -148.1836) (xy 476.4024 -148.3868) (xy 476.6056 -148.3868)
			)
		)
	)
	(zone
		(layer "F.Cu")
		(hatch none 0.5)
		(connect_pads
			(clearance 0)
		)
		(min_thickness 0.25)
		(keepout
			(tracks allowed)
			(vias allowed)
			(pads allowed)
			(copperpour allowed)
			(footprints not_allowed)
		)
		(placement
			(enabled no)
			(sheetname "")
		)
		(fill
			(thermal_gap 0.5)
			(thermal_bridge_width 0.5)
			(island_removal_mode 0)
		)
		(polygon
			(pts
				(arc
					(start 323.674994 -293.800022)
					(mid 330.67498 -286.800036)
					(end 337.674966 -293.800022)
				)
				(arc
					(start 337.674966 -299.80001)
					(mid 330.67498 -306.799996)
					(end 323.674994 -299.80001)
				)
			)
		)
	)
	(zone
		(layer "F.Cu")
		(hatch none 0.5)
		(connect_pads
			(clearance 0)
		)
		(min_thickness 0.25)
		(keepout
			(tracks allowed)
			(vias allowed)
			(pads allowed)
			(copperpour allowed)
			(footprints not_allowed)
		)
		(placement
			(enabled no)
			(sheetname "")
		)
		(fill
			(thermal_gap 0.5)
			(thermal_bridge_width 0.5)
			(island_removal_mode 0)
		)
		(polygon
			(pts
				(arc
					(start 102.350062 -23.999952)
					(mid 107.100116 -19.249898)
					(end 111.849916 -23.999952)
				)
				(arc
					(start 111.849916 -23.999952)
					(mid 107.100116 -28.749752)
					(end 102.350062 -23.999952)
				)
			)
		)
	)
	(zone
		(net "P12V_HDD34")
		(layer "F.Cu")
		(hatch none 0.5)
		(connect_pads
			(clearance 0.5)
		)
		(min_thickness 0.25)
		(fill yes
			(thermal_gap 0.5)
			(thermal_bridge_width 0.5)
			(island_removal_mode 0)
		)
		(polygon
			(pts
				(xy 460.756 -34.417) (xy 460.502 -34.671) (xy 460.502 -38.862) (xy 460.0702 -39.2938) (xy 460.0702 -41.5036)
				(xy 458.5208 -43.053) (xy 452.374 -43.053) (xy 452.12 -43.307) (xy 452.12 -44.958) (xy 452.374 -45.212)
				(xy 456.311 -45.212) (xy 456.819 -44.704) (xy 462.407 -44.704) (xy 465.455 -41.656) (xy 465.455 -34.671)
				(xy 465.201 -34.417)
			)
		)
		(polygon
			(pts
				(xy 456.4634 -44.0944) (xy 456.2602 -44.0944) (xy 456.2602 -44.2976) (xy 456.4634 -44.2976)
			)
		)
		(polygon
			(pts
				(xy 455.5998 -44.0944) (xy 455.3966 -44.0944) (xy 455.3966 -44.2976) (xy 455.5998 -44.2976)
			)
		)
	)
	(zone
		(net "GATE_FAN2")
		(layer "F.Cu")
		(hatch none 0.5)
		(connect_pads
			(clearance 0.5)
		)
		(min_thickness 0.25)
		(fill yes
			(thermal_gap 0.5)
			(thermal_bridge_width 0.5)
			(island_removal_mode 0)
		)
		(polygon
			(pts
				(xy 332.0034 -357.8352) (xy 331.343 -358.4956) (xy 331.343 -361.3658) (xy 331.6986 -361.7214) (xy 333.9084 -361.7214)
				(xy 334.2894 -361.3404) (xy 334.2894 -360.426) (xy 334.568038 -360.147362) (xy 335.406238 -360.147362)
				(xy 335.5086 -360.045) (xy 335.5086 -358.6734) (xy 335.3562 -358.521) (xy 334.518 -358.521) (xy 333.8322 -357.8352)
			)
		)
		(polygon
			(pts
				(xy 334.9752 -359.4862) (xy 334.772 -359.4862) (xy 334.772 -359.6894) (xy 334.9752 -359.6894)
			)
		)
		(polygon
			(pts
				(xy 334.9752 -358.9655) (xy 334.772 -358.9655) (xy 334.772 -359.1687) (xy 334.9752 -359.1687)
			)
		)
	)
	(zone
		(layer "F.Cu")
		(hatch none 0.5)
		(connect_pads
			(clearance 0)
		)
		(min_thickness 0.25)
		(keepout
			(tracks not_allowed)
			(vias allowed)
			(pads allowed)
			(copperpour not_allowed)
			(footprints allowed)
		)
		(placement
			(enabled no)
			(sheetname "")
		)
		(fill
			(thermal_gap 0.5)
			(thermal_bridge_width 0.5)
			(island_removal_mode 0)
		)
		(polygon
			(pts
				(arc
					(start 64.54394 -133.11505)
					(mid 64.0588 -132.62991)
					(end 63.57366 -133.11505)
				)
				(xy 63.57366 -133.5278)
				(arc
					(start 63.9318 -133.5278)
					(mid 63.967721 -133.512921)
					(end 63.9826 -133.477)
				)
				(arc
					(start 63.9826 -133.370574)
					(mid 64.0588 -132.848406)
					(end 64.135 -133.370574)
				)
				(xy 64.135 -133.508496)
				(arc
					(start 64.131952 -133.511544)
					(mid 64.075421 -133.620621)
					(end 63.966344 -133.677152)
				)
				(xy 63.963296 -133.6802) (xy 63.57366 -133.6802) (xy 63.57366 -133.8199) (xy 63.963296 -133.8199)
				(arc
					(start 63.966344 -133.822948)
					(mid 64.075421 -133.879479)
					(end 64.131952 -133.988556)
				)
				(xy 64.135 -133.991604)
				(arc
					(start 64.135 -134.129526)
					(mid 64.0588 -134.651694)
					(end 63.9826 -134.129526)
				)
				(arc
					(start 63.9826 -134.0231)
					(mid 63.967721 -133.987179)
					(end 63.9318 -133.9723)
				)
				(xy 63.57366 -133.9723)
				(arc
					(start 63.57366 -134.384796)
					(mid 64.058673 -134.87019)
					(end 64.54394 -134.38505)
				)
			)
		)
	)
	(zone
		(layer "F.Cu")
		(hatch none 0.5)
		(connect_pads
			(clearance 0)
		)
		(min_thickness 0.25)
		(keepout
			(tracks allowed)
			(vias allowed)
			(pads allowed)
			(copperpour allowed)
			(footprints allowed)
		)
		(placement
			(enabled no)
			(sheetname "")
		)
		(fill
			(thermal_gap 0.5)
			(thermal_bridge_width 0.5)
			(island_removal_mode 0)
		)
		(polygon
			(pts
				(xy 281.736292 -340.368636) (xy 283.775658 -340.368636) (xy 283.775658 -345.622118) (xy 281.736292 -345.622118)
			)
		)
	)
	(zone
		(net "12V_PRE_3")
		(layer "F.Cu")
		(hatch none 0.5)
		(connect_pads
			(clearance 0.5)
		)
		(min_thickness 0.25)
		(fill yes
			(thermal_gap 0.5)
			(thermal_bridge_width 0.5)
			(island_removal_mode 0)
		)
		(polygon
			(pts
				(xy 114.3 -264.795) (xy 114.173 -264.922) (xy 114.173 -266.446) (xy 115.57 -267.843) (xy 116.967 -267.843)
				(xy 121.92 -272.796) (xy 125.857 -272.796) (xy 125.984 -272.669) (xy 125.984 -271.907) (xy 125.857 -271.78)
				(xy 122.555 -271.78) (xy 115.57 -264.795)
			)
		)
	)
	(zone
		(net "GND")
		(layer "F.Cu")
		(hatch none 0.5)
		(connect_pads
			(clearance 0.5)
		)
		(min_thickness 0.25)
		(fill yes
			(thermal_gap 0.5)
			(thermal_bridge_width 0.5)
			(island_removal_mode 0)
		)
		(polygon
			(pts
				(arc
					(start 99.506786 -43.58894)
					(mid 98.914085 -43.789345)
					(end 98.298254 -43.899836)
				)
				(xy 98.298254 -46.663356) (xy 98.1202 -46.84141) (xy 98.1202 -49.914048) (xy 98.737674 -50.531522)
				(xy 105.589578 -50.531522) (xy 106.17454 -49.94656) (xy 106.17454 -49.548034) (xy 100.215446 -43.58894)
			)
		)
	)
	(zone
		(layer "F.Cu")
		(hatch none 0.5)
		(connect_pads
			(clearance 0)
		)
		(min_thickness 0.25)
		(keepout
			(tracks allowed)
			(vias allowed)
			(pads allowed)
			(copperpour allowed)
			(footprints allowed)
		)
		(placement
			(enabled no)
			(sheetname "")
		)
		(fill
			(thermal_gap 0.5)
			(thermal_bridge_width 0.5)
			(island_removal_mode 0)
		)
		(polygon
			(pts
				(xy 455.898504 -374.1166) (xy 456.889104 -374.1166) (xy 457.803504 -374.1166) (xy 457.803504 -375.3358)
				(xy 455.898504 -375.3358) (xy 455.898504 -374.904)
			)
		)
	)
	(zone
		(layer "F.Cu")
		(hatch none 0.5)
		(connect_pads
			(clearance 0)
		)
		(min_thickness 0.25)
		(keepout
			(tracks not_allowed)
			(vias allowed)
			(pads allowed)
			(copperpour not_allowed)
			(footprints allowed)
		)
		(placement
			(enabled no)
			(sheetname "")
		)
		(fill
			(thermal_gap 0.5)
			(thermal_bridge_width 0.5)
			(island_removal_mode 0)
		)
		(polygon
			(pts
				(arc
					(start 476.964756 -128.141984)
					(mid 476.479362 -128.626997)
					(end 476.964502 -129.112264)
				)
				(xy 477.313752 -129.112264)
				(arc
					(start 477.313752 -128.792224)
					(mid 477.287714 -128.729362)
					(end 477.224852 -128.703324)
				)
				(arc
					(start 477.220026 -128.703324)
					(mid 476.697858 -128.627124)
					(end 477.220026 -128.550924)
				)
				(xy 477.256348 -128.550924)
				(arc
					(start 477.258888 -128.55321)
					(mid 477.395565 -128.621511)
					(end 477.463866 -128.758188)
				)
				(xy 477.466152 -128.760728) (xy 477.466152 -129.112264) (xy 477.605852 -129.112264) (xy 477.605852 -128.760728)
				(arc
					(start 477.608138 -128.758188)
					(mid 477.676439 -128.621511)
					(end 477.813116 -128.55321)
				)
				(xy 477.815656 -128.550924)
				(arc
					(start 477.851978 -128.550924)
					(mid 478.374146 -128.627124)
					(end 477.851978 -128.703324)
				)
				(arc
					(start 477.847152 -128.703324)
					(mid 477.78429 -128.729362)
					(end 477.758252 -128.792224)
				)
				(xy 477.758252 -129.112264)
				(arc
					(start 478.107502 -129.112264)
					(mid 478.592642 -128.627124)
					(end 478.107502 -128.141984)
				)
			)
		)
	)
	(zone
		(layer "F.Cu")
		(hatch none 0.5)
		(connect_pads
			(clearance 0)
		)
		(min_thickness 0.25)
		(keepout
			(tracks not_allowed)
			(vias allowed)
			(pads allowed)
			(copperpour not_allowed)
			(footprints allowed)
		)
		(placement
			(enabled no)
			(sheetname "")
		)
		(fill
			(thermal_gap 0.5)
			(thermal_bridge_width 0.5)
			(island_removal_mode 0)
		)
		(polygon
			(pts
				(arc
					(start 66.32067 -244.419374)
					(mid 65.83553 -243.934234)
					(end 65.35039 -244.419374)
				)
				(xy 65.35039 -244.768624)
				(arc
					(start 65.676526 -244.768624)
					(mid 65.735077 -244.744371)
					(end 65.75933 -244.68582)
				)
				(arc
					(start 65.75933 -244.674898)
					(mid 65.83553 -244.15273)
					(end 65.91173 -244.674898)
				)
				(xy 65.91173 -244.717316)
				(arc
					(start 65.90919 -244.719856)
					(mid 65.842795 -244.852089)
					(end 65.710562 -244.918484)
				)
				(xy 65.708022 -244.921024) (xy 65.35039 -244.921024) (xy 65.35039 -245.060724) (xy 65.708022 -245.060724)
				(arc
					(start 65.710562 -245.063264)
					(mid 65.842795 -245.129659)
					(end 65.90919 -245.261892)
				)
				(xy 65.91173 -245.264432)
				(arc
					(start 65.91173 -245.30685)
					(mid 65.83553 -245.829018)
					(end 65.75933 -245.30685)
				)
				(arc
					(start 65.75933 -245.295928)
					(mid 65.735077 -245.237377)
					(end 65.676526 -245.213124)
				)
				(xy 65.35039 -245.213124)
				(arc
					(start 65.35039 -245.56212)
					(mid 65.835403 -246.047514)
					(end 66.32067 -245.562374)
				)
			)
		)
	)
	(zone
		(net "GND")
		(layer "F.Cu")
		(hatch none 0.5)
		(connect_pads
			(clearance 0.5)
		)
		(min_thickness 0.25)
		(fill yes
			(thermal_gap 0.5)
			(thermal_bridge_width 0.5)
			(island_removal_mode 0)
		)
		(polygon
			(pts
				(xy 108.425234 -290.34232) (xy 107.14609 -291.621464) (xy 107.14609 -304.853848) (xy 110.647988 -308.355746)
				(xy 147.37207 -308.355746) (xy 148.50364 -307.224176) (xy 148.50364 -292.49497) (xy 146.35099 -290.34232)
			)
		)
	)
	(zone
		(layer "F.Cu")
		(hatch none 0.5)
		(connect_pads
			(clearance 0)
		)
		(min_thickness 0.25)
		(keepout
			(tracks not_allowed)
			(vias allowed)
			(pads allowed)
			(copperpour not_allowed)
			(footprints allowed)
		)
		(placement
			(enabled no)
			(sheetname "")
		)
		(fill
			(thermal_gap 0.5)
			(thermal_bridge_width 0.5)
			(island_removal_mode 0)
		)
		(polygon
			(pts
				(arc
					(start 448.8815 -16.95196)
					(mid 448.39636 -17.4371)
					(end 448.8815 -17.92224)
				)
				(xy 449.29425 -17.92224)
				(arc
					(start 449.29425 -17.599152)
					(mid 449.269105 -17.538445)
					(end 449.208398 -17.5133)
				)
				(arc
					(start 449.137024 -17.5133)
					(mid 448.614856 -17.4371)
					(end 449.137024 -17.3609)
				)
				(xy 449.239894 -17.3609)
				(arc
					(start 449.242434 -17.36344)
					(mid 449.3768 -17.43075)
					(end 449.44411 -17.565116)
				)
				(xy 449.44665 -17.567656) (xy 449.44665 -17.92224) (xy 449.58635 -17.92224) (xy 449.58635 -17.567656)
				(arc
					(start 449.58889 -17.565116)
					(mid 449.6562 -17.43075)
					(end 449.790566 -17.36344)
				)
				(xy 449.793106 -17.3609)
				(arc
					(start 449.895976 -17.3609)
					(mid 450.418144 -17.4371)
					(end 449.895976 -17.5133)
				)
				(arc
					(start 449.824602 -17.5133)
					(mid 449.763895 -17.538445)
					(end 449.73875 -17.599152)
				)
				(xy 449.73875 -17.92224)
				(arc
					(start 450.151246 -17.92224)
					(mid 450.63664 -17.437227)
					(end 450.1515 -16.95196)
				)
			)
		)
	)
	(zone
		(layer "F.Cu")
		(hatch none 0.5)
		(connect_pads
			(clearance 0)
		)
		(min_thickness 0.25)
		(keepout
			(tracks allowed)
			(vias allowed)
			(pads allowed)
			(copperpour allowed)
			(footprints not_allowed)
		)
		(placement
			(enabled no)
			(sheetname "")
		)
		(fill
			(thermal_gap 0.5)
			(thermal_bridge_width 0.5)
			(island_removal_mode 0)
		)
		(polygon
			(pts
				(arc
					(start 89.324942 -178.799998)
					(mid 96.324928 -171.800012)
					(end 103.324914 -178.799998)
				)
				(arc
					(start 103.324914 -184.799986)
					(mid 96.324928 -191.799972)
					(end 89.324942 -184.799986)
				)
			)
		)
	)
	(zone
		(layer "F.Cu")
		(hatch none 0.5)
		(connect_pads
			(clearance 0)
		)
		(min_thickness 0.25)
		(keepout
			(tracks allowed)
			(vias allowed)
			(pads allowed)
			(copperpour allowed)
			(footprints allowed)
		)
		(placement
			(enabled no)
			(sheetname "")
		)
		(fill
			(thermal_gap 0.5)
			(thermal_bridge_width 0.5)
			(island_removal_mode 0)
		)
		(polygon
			(pts
				(xy 31.0388 -134.6454) (xy 31.0388 -132.7658) (xy 32.9184 -132.7658) (xy 32.9184 -134.6454)
			)
		)
	)
	(zone
		(layer "F.Cu")
		(hatch none 0.5)
		(connect_pads
			(clearance 0)
		)
		(min_thickness 0.25)
		(keepout
			(tracks allowed)
			(vias allowed)
			(pads allowed)
			(copperpour allowed)
			(footprints not_allowed)
		)
		(placement
			(enabled no)
			(sheetname "")
		)
		(fill
			(thermal_gap 0.5)
			(thermal_bridge_width 0.5)
			(island_removal_mode 0)
		)
		(polygon
			(pts
				(xy 177.299874 -96.799908) (xy 177.299874 -110.000034) (xy 191.799972 -110.000034) (xy 191.799972 -161.800032)
				(xy 180.64988 -161.800032) (xy 180.64988 -151.800052) (xy 166.099998 -151.800052) (xy 166.099998 -161.800032)
				(xy 149.100032 -161.800032) (xy 149.100032 -151.800052) (xy 134.549896 -151.800052) (xy 134.549896 -161.800032)
				(xy 117.54993 -161.800032) (xy 117.54993 -151.800052) (xy 103.000048 -151.800052) (xy 103.000048 -161.800032)
				(xy 86.000082 -161.800032) (xy 86.000082 -151.800052) (xy 71.449946 -151.800052) (xy 71.449946 -161.800032)
				(xy 54.44998 -161.800032) (xy 54.44998 -151.800052) (xy 39.900098 -151.800052) (xy 39.900098 -161.800032)
				(xy 22.899878 -161.800032) (xy 22.899878 -151.800052) (xy 8.349996 -151.800052) (xy 8.349996 -161.800032)
				(xy 0 -161.800032) (xy 0 -96.799908)
			)
		)
	)
	(zone
		(layer "F.Cu")
		(hatch none 0.5)
		(connect_pads
			(clearance 0)
		)
		(min_thickness 0.25)
		(keepout
			(tracks not_allowed)
			(vias allowed)
			(pads allowed)
			(copperpour not_allowed)
			(footprints allowed)
		)
		(placement
			(enabled no)
			(sheetname "")
		)
		(fill
			(thermal_gap 0.5)
			(thermal_bridge_width 0.5)
			(island_removal_mode 0)
		)
		(polygon
			(pts
				(arc
					(start 66.32067 -14.41958)
					(mid 65.835657 -13.934186)
					(end 65.35039 -14.419326)
				)
				(xy 65.35039 -14.768576)
				(arc
					(start 65.676526 -14.768576)
					(mid 65.735077 -14.744323)
					(end 65.75933 -14.685772)
				)
				(arc
					(start 65.75933 -14.67485)
					(mid 65.83553 -14.152682)
					(end 65.91173 -14.67485)
				)
				(xy 65.91173 -14.717268)
				(arc
					(start 65.90919 -14.719808)
					(mid 65.842795 -14.852041)
					(end 65.710562 -14.918436)
				)
				(xy 65.708022 -14.920976) (xy 65.35039 -14.920976) (xy 65.35039 -15.060676) (xy 65.708022 -15.060676)
				(arc
					(start 65.710562 -15.063216)
					(mid 65.842795 -15.129611)
					(end 65.90919 -15.261844)
				)
				(xy 65.91173 -15.264384)
				(arc
					(start 65.91173 -15.306802)
					(mid 65.83553 -15.82897)
					(end 65.75933 -15.306802)
				)
				(arc
					(start 65.75933 -15.29588)
					(mid 65.735077 -15.237329)
					(end 65.676526 -15.213076)
				)
				(xy 65.35039 -15.213076)
				(arc
					(start 65.35039 -15.562326)
					(mid 65.83553 -16.047466)
					(end 66.32067 -15.562326)
				)
			)
		)
	)
	(zone
		(net "P5V_HDD26")
		(layer "F.Cu")
		(hatch none 0.5)
		(connect_pads
			(clearance 0.5)
		)
		(min_thickness 0.25)
		(fill yes
			(thermal_gap 0.5)
			(thermal_bridge_width 0.5)
			(island_removal_mode 0)
		)
		(polygon
			(pts
				(xy 82.804 -27.686) (xy 82.55 -27.94) (xy 82.55 -30.226) (xy 82.804 -30.48) (xy 82.804 -32.512)
				(xy 83.566 -33.274) (xy 83.566 -34.194242) (xy 83.839558 -34.4678) (xy 84.3788 -34.4678) (xy 87.503 -37.592)
				(xy 94.361 -37.592) (xy 94.488 -37.465) (xy 94.488 -35.687) (xy 94.361 -35.56) (xy 89.281 -35.56)
				(xy 87.376 -33.655) (xy 86.487 -33.655) (xy 85.598 -32.766) (xy 85.598 -30.226) (xy 86.233 -29.591)
				(xy 86.233 -27.94) (xy 85.979 -27.686)
			)
		)
		(polygon
			(pts
				(xy 84.582 -34.1122) (xy 84.3788 -34.1122) (xy 84.3788 -34.3154) (xy 84.582 -34.3154)
			)
		)
		(polygon
			(pts
				(xy 84.582 -33.2486) (xy 84.3788 -33.2486) (xy 84.3788 -33.4518) (xy 84.582 -33.4518)
			)
		)
	)
	(zone
		(net "5V_PRE_21")
		(layer "F.Cu")
		(hatch none 0.5)
		(connect_pads
			(clearance 0.5)
		)
		(min_thickness 0.25)
		(fill yes
			(thermal_gap 0.5)
			(thermal_bridge_width 0.5)
			(island_removal_mode 0)
		)
		(polygon
			(pts
				(xy 424.053 -146.05) (xy 423.799 -146.304) (xy 423.799 -148.844) (xy 423.418 -149.225) (xy 420.878 -149.225)
				(xy 420.624 -149.479) (xy 420.624 -149.86) (xy 420.878 -150.114) (xy 424.18 -150.114) (xy 425.45 -148.844)
				(xy 425.45 -146.304) (xy 425.196 -146.05)
			)
		)
	)
	(zone
		(layer "F.Cu")
		(hatch none 0.5)
		(connect_pads
			(clearance 0)
		)
		(min_thickness 0.25)
		(keepout
			(tracks allowed)
			(vias allowed)
			(pads allowed)
			(copperpour allowed)
			(footprints allowed)
		)
		(placement
			(enabled no)
			(sheetname "")
		)
		(fill
			(thermal_gap 0.5)
			(thermal_bridge_width 0.5)
			(island_removal_mode 0)
		)
		(polygon
			(pts
				(xy 188.420248 -371.020848) (xy 188.420248 -370.030248) (xy 188.420248 -369.115848) (xy 189.639448 -369.115848)
				(xy 189.639448 -371.020848) (xy 189.207648 -371.020848)
			)
		)
	)
	(zone
		(layer "F.Cu")
		(hatch none 0.5)
		(connect_pads
			(clearance 0)
		)
		(min_thickness 0.25)
		(keepout
			(tracks allowed)
			(vias allowed)
			(pads allowed)
			(copperpour allowed)
			(footprints allowed)
		)
		(placement
			(enabled no)
			(sheetname "")
		)
		(fill
			(thermal_gap 0.5)
			(thermal_bridge_width 0.5)
			(island_removal_mode 0)
		)
		(polygon
			(pts
				(xy 55.980584 -364.746794) (xy 55.980584 -362.595922) (xy 58.40222 -362.595922) (xy 58.40222 -364.746794)
			)
		)
	)
	(zone
		(net "P12V_B")
		(layer "F.Cu")
		(hatch none 0.5)
		(connect_pads
			(clearance 0.5)
		)
		(min_thickness 0.25)
		(fill yes
			(thermal_gap 0.5)
			(thermal_bridge_width 0.5)
			(island_removal_mode 0)
		)
		(polygon
			(pts
				(xy 467.0806 -19.304) (xy 466.852 -19.5326) (xy 466.852 -22.479) (xy 467.106 -22.733) (xy 470.408 -22.733)
				(xy 470.662 -22.479) (xy 470.662 -19.4056) (xy 470.5604 -19.304)
			)
		)
	)
	(zone
		(layer "F.Cu")
		(hatch none 0.5)
		(connect_pads
			(clearance 0)
		)
		(min_thickness 0.25)
		(keepout
			(tracks allowed)
			(vias allowed)
			(pads allowed)
			(copperpour allowed)
			(footprints allowed)
		)
		(placement
			(enabled no)
			(sheetname "")
		)
		(fill
			(thermal_gap 0.5)
			(thermal_bridge_width 0.5)
			(island_removal_mode 0)
		)
		(polygon
			(pts
				(xy 265.85418 -365.872776) (xy 265.85418 -367.345976) (xy 263.432544 -367.345976) (xy 263.432544 -365.872776)
			)
		)
	)
	(zone
		(net "5V_PRE_35")
		(layer "F.Cu")
		(hatch none 0.5)
		(connect_pads
			(clearance 0.5)
		)
		(min_thickness 0.25)
		(fill yes
			(thermal_gap 0.5)
			(thermal_bridge_width 0.5)
			(island_removal_mode 0)
		)
		(polygon
			(pts
				(xy 478.05848 -30.9626) (xy 477.90608 -31.115) (xy 477.90608 -32.512) (xy 478.49028 -33.0962) (xy 479.76028 -33.0962)
				(xy 481.84308 -35.179) (xy 486.28808 -35.179) (xy 486.41508 -35.052) (xy 486.41508 -34.29) (xy 486.28808 -34.163)
				(xy 483.26548 -34.163) (xy 480.06508 -30.9626)
			)
		)
	)
	(zone
		(layer "F.Cu")
		(hatch none 0.5)
		(connect_pads
			(clearance 0)
		)
		(min_thickness 0.25)
		(keepout
			(tracks allowed)
			(vias allowed)
			(pads allowed)
			(copperpour allowed)
			(footprints allowed)
		)
		(placement
			(enabled no)
			(sheetname "")
		)
		(fill
			(thermal_gap 0.5)
			(thermal_bridge_width 0.5)
			(island_removal_mode 0)
		)
		(polygon
			(pts
				(xy 258.191 -216.2556) (xy 258.191 -217.805) (xy 254.762 -217.805) (xy 254.762 -216.2556)
			)
		)
	)
	(zone
		(layer "F.Cu")
		(hatch none 0.5)
		(connect_pads
			(clearance 0)
		)
		(min_thickness 0.25)
		(keepout
			(tracks not_allowed)
			(vias allowed)
			(pads allowed)
			(copperpour not_allowed)
			(footprints allowed)
		)
		(placement
			(enabled no)
			(sheetname "")
		)
		(fill
			(thermal_gap 0.5)
			(thermal_bridge_width 0.5)
			(island_removal_mode 0)
		)
		(polygon
			(pts
				(arc
					(start 448.8815 -131.951984)
					(mid 448.39636 -132.437124)
					(end 448.8815 -132.922264)
				)
				(xy 449.29425 -132.922264)
				(arc
					(start 449.29425 -132.60705)
					(mid 449.266798 -132.540776)
					(end 449.200524 -132.513324)
				)
				(arc
					(start 449.137024 -132.513324)
					(mid 448.614856 -132.437124)
					(end 449.137024 -132.360924)
				)
				(xy 449.23202 -132.360924)
				(arc
					(start 449.23456 -132.36321)
					(mid 449.374616 -132.432958)
					(end 449.444364 -132.573014)
				)
				(xy 449.44665 -132.575554) (xy 449.44665 -132.922264) (xy 449.58635 -132.922264) (xy 449.58635 -132.575554)
				(arc
					(start 449.588636 -132.573014)
					(mid 449.658384 -132.432958)
					(end 449.79844 -132.36321)
				)
				(xy 449.80098 -132.360924)
				(arc
					(start 449.895976 -132.360924)
					(mid 450.418144 -132.437124)
					(end 449.895976 -132.513324)
				)
				(arc
					(start 449.832476 -132.513324)
					(mid 449.766202 -132.540776)
					(end 449.73875 -132.60705)
				)
				(xy 449.73875 -132.922264)
				(arc
					(start 450.151246 -132.922264)
					(mid 450.63664 -132.437251)
					(end 450.1515 -131.951984)
				)
			)
		)
	)
	(zone
		(net "P12V_B")
		(layer "F.Cu")
		(hatch none 0.5)
		(connect_pads
			(clearance 0.5)
		)
		(min_thickness 0.25)
		(fill yes
			(thermal_gap 0.5)
			(thermal_bridge_width 0.5)
			(island_removal_mode 0)
		)
		(polygon
			(pts
				(xy 139.151614 -140.081) (xy 138.516868 -140.715746) (xy 138.516868 -145.433796) (xy 138.802872 -145.7198)
				(xy 141.9352 -145.7198) (xy 142.24 -145.415) (xy 142.24 -141.732) (xy 141.605 -141.097) (xy 141.224 -141.097)
				(xy 140.97 -140.843) (xy 140.97 -140.208) (xy 140.843 -140.081)
			)
		)
		(polygon
			(pts
				(xy 140.4366 -140.6652) (xy 140.2334 -140.6652) (xy 140.2334 -140.8684) (xy 140.4366 -140.8684)
			)
		)
	)
	(zone
		(net "GND")
		(layer "F.Cu")
		(hatch none 0.5)
		(connect_pads
			(clearance 0.5)
		)
		(min_thickness 0.25)
		(fill yes
			(thermal_gap 0.5)
			(thermal_bridge_width 0.5)
			(island_removal_mode 0)
		)
		(polygon
			(pts
				(xy 200.2282 -303.2506) (xy 199.9742 -303.5046) (xy 199.9742 -306.77739) (xy 200.362312 -307.165502)
				(xy 206.650844 -307.165502) (xy 207.0862 -306.730146) (xy 207.0862 -303.5046) (xy 206.8322 -303.2506)
			)
		)
	)
	(zone
		(layer "F.Cu")
		(hatch none 0.5)
		(connect_pads
			(clearance 0)
		)
		(min_thickness 0.25)
		(keepout
			(tracks not_allowed)
			(vias allowed)
			(pads allowed)
			(copperpour not_allowed)
			(footprints allowed)
		)
		(placement
			(enabled no)
			(sheetname "")
		)
		(fill
			(thermal_gap 0.5)
			(thermal_bridge_width 0.5)
			(island_removal_mode 0)
		)
		(polygon
			(pts
				(arc
					(start 39.250112 -13.999972)
					(mid 44.000166 -9.249918)
					(end 48.749966 -13.999972)
				)
				(arc
					(start 48.749966 -13.999972)
					(mid 44.000166 -18.749772)
					(end 39.250112 -13.999972)
				)
			)
		)
	)
	(zone
		(net "12V_PRE_4")
		(layer "F.Cu")
		(hatch none 0.5)
		(connect_pads
			(clearance 0.5)
		)
		(min_thickness 0.25)
		(fill yes
			(thermal_gap 0.5)
			(thermal_bridge_width 0.5)
			(island_removal_mode 0)
		)
		(polygon
			(pts
				(xy 145.923 -264.795) (xy 145.796 -264.922) (xy 145.796 -266.446) (xy 147.193 -267.843) (xy 148.59 -267.843)
				(xy 153.543 -272.796) (xy 157.48 -272.796) (xy 157.607 -272.669) (xy 157.607 -271.907) (xy 157.48 -271.78)
				(xy 154.178 -271.78) (xy 147.193 -264.795)
			)
		)
	)
	(zone
		(net "P12V_B")
		(layer "F.Cu")
		(hatch none 0.5)
		(connect_pads
			(clearance 0.5)
		)
		(min_thickness 0.25)
		(fill yes
			(thermal_gap 0.5)
			(thermal_bridge_width 0.5)
			(island_removal_mode 0)
		)
		(polygon
			(pts
				(xy 170.226482 -255.143) (xy 169.926 -255.443482) (xy 169.926 -259.08) (xy 170.18 -259.334) (xy 173.482 -259.334)
				(xy 173.736 -259.08) (xy 173.736 -256.794) (xy 173.101 -256.159) (xy 172.72 -256.159) (xy 172.466 -255.905)
				(xy 172.466 -255.27) (xy 172.339 -255.143)
			)
		)
		(polygon
			(pts
				(xy 171.9326 -255.7272) (xy 171.7294 -255.7272) (xy 171.7294 -255.9304) (xy 171.9326 -255.9304)
			)
		)
	)
	(zone
		(net "GND")
		(layer "F.Cu")
		(hatch none 0.5)
		(connect_pads
			(clearance 0.5)
		)
		(min_thickness 0.25)
		(fill yes
			(thermal_gap 0.5)
			(thermal_bridge_width 0.5)
			(island_removal_mode 0)
		)
		(polygon
			(pts
				(xy 349.682562 -358.816402) (xy 349.319596 -359.179368) (xy 349.319596 -362.331) (xy 348.709996 -362.9406)
				(xy 348.709996 -364.4646) (xy 348.862396 -364.617) (xy 352.215196 -364.617) (xy 352.596196 -364.236)
				(xy 352.596196 -359.500932) (xy 351.911666 -358.816402)
			)
		)
		(polygon
			(pts
				(xy 349.409766 -363.84103) (xy 349.206566 -363.84103) (xy 349.206566 -364.04423) (xy 349.409766 -364.04423)
			)
		)
		(polygon
			(pts
				(xy 349.827596 -363.5502) (xy 349.624396 -363.5502) (xy 349.624396 -363.7534) (xy 349.827596 -363.7534)
			)
		)
		(polygon
			(pts
				(xy 349.827596 -362.6866) (xy 349.624396 -362.6866) (xy 349.624396 -362.8898) (xy 349.827596 -362.8898)
			)
		)
	)
	(zone
		(net "P12V_IN")
		(layer "F.Cu")
		(hatch none 0.5)
		(connect_pads
			(clearance 0.5)
		)
		(min_thickness 0.25)
		(fill yes
			(thermal_gap 0.5)
			(thermal_bridge_width 0.5)
			(island_removal_mode 0)
		)
		(polygon
			(pts
				(xy 270.146272 -93.742764) (xy 269.812516 -94.07652) (xy 269.812516 -98.03638) (xy 270.499078 -98.722942)
				(xy 273.7612 -98.722942) (xy 274.1168 -98.367342) (xy 274.1168 -94.225364) (xy 273.6342 -93.742764)
			)
		)
	)
	(zone
		(net "GND")
		(layer "F.Cu")
		(hatch none 0.5)
		(connect_pads
			(clearance 0.5)
		)
		(min_thickness 0.25)
		(fill yes
			(thermal_gap 0.5)
			(thermal_bridge_width 0.5)
			(island_removal_mode 0)
		)
		(polygon
			(pts
				(xy 136.680702 -40.2082) (xy 135.334502 -41.5544) (xy 135.334502 -56.750966) (xy 135.47852 -56.894984)
				(xy 135.800592 -56.894984) (xy 142.062454 -50.633122) (xy 145.493486 -50.633122) (xy 146.2278 -49.898808)
				(xy 146.2278 -47.85741) (xy 146.136614 -47.766224) (xy 145.603976 -47.766224) (xy 145.603976 -47.233586)
				(xy 138.57859 -40.2082)
			)
		)
	)
	(zone
		(net "12V_PRE_21")
		(layer "F.Cu")
		(hatch none 0.5)
		(connect_pads
			(clearance 0.5)
		)
		(min_thickness 0.25)
		(fill yes
			(thermal_gap 0.5)
			(thermal_bridge_width 0.5)
			(island_removal_mode 0)
		)
		(polygon
			(pts
				(xy 425.6786 -154.686) (xy 423.7482 -156.6164) (xy 420.751 -156.6164) (xy 420.497 -156.8704) (xy 420.497 -157.5816)
				(xy 420.6367 -157.7213) (xy 422.9227 -157.7213) (xy 422.9354 -157.734) (xy 426.6184 -157.734) (xy 427.6344 -156.718)
				(xy 427.6344 -154.813) (xy 427.5074 -154.686)
			)
		)
	)
	(zone
		(layer "F.Cu")
		(hatch none 0.5)
		(connect_pads
			(clearance 0)
		)
		(min_thickness 0.25)
		(keepout
			(tracks allowed)
			(vias allowed)
			(pads allowed)
			(copperpour allowed)
			(footprints not_allowed)
		)
		(placement
			(enabled no)
			(sheetname "")
		)
		(fill
			(thermal_gap 0.5)
			(thermal_bridge_width 0.5)
			(island_removal_mode 0)
		)
		(polygon
			(pts
				(xy 177.299874 -220.000068) (xy 202.300078 -220.000068) (xy 202.300078 -194.00012) (xy 177.299874 -194.00012)
			)
		)
	)
	(zone
		(net "P5V_HDD4")
		(layer "F.Cu")
		(hatch none 0.5)
		(connect_pads
			(clearance 0.5)
		)
		(min_thickness 0.25)
		(fill yes
			(thermal_gap 0.5)
			(thermal_bridge_width 0.5)
			(island_removal_mode 0)
		)
		(polygon
			(pts
				(xy 145.923 -257.683) (xy 145.669 -257.937) (xy 145.669 -260.223) (xy 145.923 -260.477) (xy 145.923 -262.509)
				(xy 146.685 -263.271) (xy 146.685 -264.16) (xy 146.9898 -264.4648) (xy 147.4978 -264.4648) (xy 150.622 -267.589)
				(xy 157.48 -267.589) (xy 157.607 -267.462) (xy 157.607 -265.684) (xy 157.48 -265.557) (xy 152.4 -265.557)
				(xy 150.495 -263.652) (xy 149.606 -263.652) (xy 148.717 -262.763) (xy 148.717 -260.223) (xy 149.352 -259.588)
				(xy 149.352 -257.937) (xy 149.098 -257.683)
			)
		)
		(polygon
			(pts
				(xy 147.6756 -264.1092) (xy 147.4724 -264.1092) (xy 147.4724 -264.3124) (xy 147.6756 -264.3124)
			)
		)
		(polygon
			(pts
				(xy 147.6756 -263.2456) (xy 147.4724 -263.2456) (xy 147.4724 -263.4488) (xy 147.6756 -263.4488)
			)
		)
	)
	(zone
		(net "P5V_B_1")
		(layer "F.Cu")
		(hatch none 0.5)
		(connect_pads
			(clearance 0.5)
		)
		(min_thickness 0.25)
		(fill yes
			(thermal_gap 0.5)
			(thermal_bridge_width 0.5)
			(island_removal_mode 0)
		)
		(polygon
			(pts
				(xy 49.911 -136.779) (xy 49.657 -137.033) (xy 49.657 -139.319) (xy 49.911 -139.573) (xy 54.61 -139.573)
				(xy 54.864 -139.319) (xy 54.864 -137.033) (xy 54.61 -136.779)
			)
		)
	)
	(zone
		(net "P5V_B_3")
		(layer "F.Cu")
		(hatch none 0.5)
		(connect_pads
			(clearance 0.5)
		)
		(min_thickness 0.25)
		(fill yes
			(thermal_gap 0.5)
			(thermal_bridge_width 0.5)
			(island_removal_mode 0)
		)
		(polygon
			(pts
				(xy 336.804 -136.398) (xy 336.55 -136.652) (xy 336.55 -141.351) (xy 336.804 -141.605) (xy 339.09 -141.605)
				(xy 339.344 -141.351) (xy 339.344 -136.652) (xy 339.09 -136.398)
			)
		)
	)
	(zone
		(layer "F.Cu")
		(hatch none 0.5)
		(connect_pads
			(clearance 0)
		)
		(min_thickness 0.25)
		(keepout
			(tracks allowed)
			(vias allowed)
			(pads allowed)
			(copperpour allowed)
			(footprints not_allowed)
		)
		(placement
			(enabled no)
			(sheetname "")
		)
		(fill
			(thermal_gap 0.5)
			(thermal_bridge_width 0.5)
			(island_removal_mode 0)
		)
		(polygon
			(pts
				(xy 191.799972 -220.000068) (xy 198.399908 -220.000068) (xy 198.399908 -370.000022) (xy 198.000112 -370.000022)
				(xy 198.000112 -380.000002)
				(arc
					(start 199.00011 -380.000002)
					(mid 198.293005 -380.292895)
					(end 198.000112 -381)
				)
				(arc
					(start 198.000112 -384.999992)
					(mid 197.707219 -385.707097)
					(end 197.000114 -385.99999)
				)
				(xy 191.799972 -385.99999)
			)
		)
	)
	(zone
		(net "P5V_B_1")
		(layer "F.Cu")
		(hatch none 0.5)
		(connect_pads
			(clearance 0.5)
		)
		(min_thickness 0.25)
		(fill yes
			(thermal_gap 0.5)
			(thermal_bridge_width 0.5)
			(island_removal_mode 0)
		)
		(polygon
			(pts
				(xy 50.038 -251.841) (xy 49.784 -252.095) (xy 49.784 -254.381) (xy 50.038 -254.635) (xy 54.737 -254.635)
				(xy 54.991 -254.381) (xy 54.991 -252.095) (xy 54.737 -251.841)
			)
		)
	)
	(zone
		(layer "F.Cu")
		(hatch none 0.5)
		(connect_pads
			(clearance 0)
		)
		(min_thickness 0.25)
		(keepout
			(tracks allowed)
			(vias allowed)
			(pads allowed)
			(copperpour allowed)
			(footprints allowed)
		)
		(placement
			(enabled no)
			(sheetname "")
		)
		(fill
			(thermal_gap 0.5)
			(thermal_bridge_width 0.5)
			(island_removal_mode 0)
		)
		(polygon
			(pts
				(xy 246.850154 -363.662976) (xy 246.850154 -365.136176) (xy 244.428518 -365.136176) (xy 244.428518 -363.662976)
			)
		)
	)
	(zone
		(net "GND")
		(layer "F.Cu")
		(hatch none 0.5)
		(connect_pads
			(clearance 0.5)
		)
		(min_thickness 0.25)
		(fill yes
			(thermal_gap 0.5)
			(thermal_bridge_width 0.5)
			(island_removal_mode 0)
		)
		(polygon
			(pts
				(arc
					(start 454.67778 -90.984324)
					(mid 455.440274 -89.934274)
					(end 456.490324 -89.17178)
				)
				(xy 465.378292 -80.284066) (xy 465.378292 -78.556104) (xy 464.744816 -77.922628)
				(arc
					(start 463.818224 -77.922628)
					(mid 456.781959 -80.614799)
					(end 449.693792 -78.062328)
				)
				(xy 448.743832 -78.062328) (xy 447.991992 -78.814168) (xy 447.991992 -89.64295)
				(arc
					(start 449.88099 -91.531694)
					(mid 450.831448 -92.197874)
					(end 451.559676 -93.101668)
				)
				(xy 451.860666 -93.402658) (xy 452.678546 -93.402658)
				(arc
					(start 452.966582 -93.114622)
					(mid 453.329516 -92.438386)
					(end 453.81672 -91.845384)
				)
			)
		)
	)
	(zone
		(layer "F.Cu")
		(hatch none 0.5)
		(connect_pads
			(clearance 0)
		)
		(min_thickness 0.25)
		(keepout
			(tracks allowed)
			(vias allowed)
			(pads allowed)
			(copperpour allowed)
			(footprints not_allowed)
		)
		(placement
			(enabled no)
			(sheetname "")
		)
		(fill
			(thermal_gap 0.5)
			(thermal_bridge_width 0.5)
			(island_removal_mode 0)
		)
		(polygon
			(pts
				(xy 287.699958 -84.000086) (xy 287.699958 -110.000034) (xy 312.699908 -110.000034) (xy 312.699908 -84.000086)
			)
		)
	)
	(zone
		(net "P5V_B_3")
		(layer "F.Cu")
		(hatch none 0.5)
		(connect_pads
			(clearance 0.5)
		)
		(min_thickness 0.25)
		(fill yes
			(thermal_gap 0.5)
			(thermal_bridge_width 0.5)
			(island_removal_mode 0)
		)
		(polygon
			(pts
				(xy 368.3 -136.398) (xy 368.046 -136.652) (xy 368.046 -141.351) (xy 368.3 -141.605) (xy 370.586 -141.605)
				(xy 370.84 -141.351) (xy 370.84 -136.652) (xy 370.586 -136.398)
			)
		)
	)
	(zone
		(layer "F.Cu")
		(hatch none 0.5)
		(connect_pads
			(clearance 0)
		)
		(min_thickness 0.25)
		(keepout
			(tracks allowed)
			(vias allowed)
			(pads allowed)
			(copperpour allowed)
			(footprints allowed)
		)
		(placement
			(enabled no)
			(sheetname "")
		)
		(fill
			(thermal_gap 0.5)
			(thermal_bridge_width 0.5)
			(island_removal_mode 0)
		)
		(polygon
			(pts
				(xy 347.372432 -364.7186) (xy 347.372432 -362.567728) (xy 349.794068 -362.567728) (xy 349.794068 -364.7186)
			)
		)
	)
	(zone
		(net "12V_PRE_0")
		(layer "F.Cu")
		(hatch none 0.5)
		(connect_pads
			(clearance 0.5)
		)
		(min_thickness 0.25)
		(fill yes
			(thermal_gap 0.5)
			(thermal_bridge_width 0.5)
			(island_removal_mode 0)
		)
		(polygon
			(pts
				(xy 19.685 -264.795) (xy 19.558 -264.922) (xy 19.558 -268.0462) (xy 21.1709 -269.6591) (xy 24.1681 -269.6591)
				(xy 27.305 -272.796) (xy 31.242 -272.796) (xy 31.369 -272.669) (xy 31.369 -271.907) (xy 31.242 -271.78)
				(xy 27.94 -271.78) (xy 20.955 -264.795)
			)
		)
	)
	(zone
		(layer "F.Cu")
		(hatch none 0.5)
		(connect_pads
			(clearance 0)
		)
		(min_thickness 0.25)
		(keepout
			(tracks not_allowed)
			(vias allowed)
			(pads allowed)
			(copperpour not_allowed)
			(footprints allowed)
		)
		(placement
			(enabled no)
			(sheetname "")
		)
		(fill
			(thermal_gap 0.5)
			(thermal_bridge_width 0.5)
			(island_removal_mode 0)
		)
		(polygon
			(pts
				(arc
					(start 354.231956 -131.951984)
					(mid 353.746562 -132.436997)
					(end 354.231702 -132.922264)
				)
				(xy 354.644452 -132.922264)
				(arc
					(start 354.644452 -132.623052)
					(mid 354.612313 -132.545463)
					(end 354.534724 -132.513324)
				)
				(arc
					(start 354.487226 -132.513324)
					(mid 353.965058 -132.437124)
					(end 354.487226 -132.360924)
				)
				(xy 354.56622 -132.360924)
				(arc
					(start 354.568506 -132.36321)
					(mid 354.720006 -132.43777)
					(end 354.794566 -132.58927)
				)
				(xy 354.796852 -132.591556) (xy 354.796852 -132.922264) (xy 354.936552 -132.922264) (xy 354.936552 -132.584952)
				(arc
					(start 354.939854 -132.58165)
					(mid 355.016074 -132.435009)
					(end 355.164898 -132.36321)
				)
				(xy 355.167184 -132.360924)
				(arc
					(start 355.246178 -132.360924)
					(mid 355.768346 -132.437124)
					(end 355.246178 -132.513324)
				)
				(arc
					(start 355.19868 -132.513324)
					(mid 355.121091 -132.545463)
					(end 355.088952 -132.623052)
				)
				(xy 355.088952 -132.922264)
				(arc
					(start 355.501702 -132.922264)
					(mid 355.986842 -132.437124)
					(end 355.501702 -131.951984)
				)
			)
		)
	)
	(zone
		(net "GND")
		(layer "F.Cu")
		(hatch none 0.5)
		(connect_pads
			(clearance 0.5)
		)
		(min_thickness 0.25)
		(fill yes
			(thermal_gap 0.5)
			(thermal_bridge_width 0.5)
			(island_removal_mode 0)
		)
		(polygon
			(pts
				(xy 166.995348 -270.3322) (xy 166.58336 -270.744188) (xy 166.58336 -280.199084) (xy 166.840916 -280.45664)
				(xy 177.267362 -280.45664) (xy 177.7238 -280.000202) (xy 177.7238 -277.85441) (xy 177.632614 -277.763224)
				(xy 177.176176 -277.763224) (xy 177.176176 -277.306786) (xy 170.20159 -270.3322)
			)
		)
	)
	(zone
		(layer "F.Cu")
		(hatch none 0.5)
		(connect_pads
			(clearance 0)
		)
		(min_thickness 0.25)
		(keepout
			(tracks allowed)
			(vias allowed)
			(pads allowed)
			(copperpour allowed)
			(footprints allowed)
		)
		(placement
			(enabled no)
			(sheetname "")
		)
		(fill
			(thermal_gap 0.5)
			(thermal_bridge_width 0.5)
			(island_removal_mode 0)
		)
		(polygon
			(pts
				(xy 249.7074 -138.6586) (xy 249.7074 -139.7254) (xy 248.0564 -139.7254) (xy 248.0564 -138.6586)
			)
		)
	)
	(zone
		(net "5V_PRE_32")
		(layer "F.Cu")
		(hatch none 0.5)
		(connect_pads
			(clearance 0.5)
		)
		(min_thickness 0.25)
		(fill yes
			(thermal_gap 0.5)
			(thermal_bridge_width 0.5)
			(island_removal_mode 0)
		)
		(polygon
			(pts
				(xy 392.557 -30.988) (xy 392.303 -31.242) (xy 392.303 -33.782) (xy 391.922 -34.163) (xy 389.382 -34.163)
				(xy 389.128 -34.417) (xy 389.128 -34.798) (xy 389.382 -35.052) (xy 392.684 -35.052) (xy 393.954 -33.782)
				(xy 393.954 -31.242) (xy 393.7 -30.988)
			)
		)
	)
	(zone
		(layer "F.Cu")
		(hatch none 0.5)
		(connect_pads
			(clearance 0)
		)
		(min_thickness 0.25)
		(keepout
			(tracks allowed)
			(vias allowed)
			(pads allowed)
			(copperpour allowed)
			(footprints not_allowed)
		)
		(placement
			(enabled no)
			(sheetname "")
		)
		(fill
			(thermal_gap 0.5)
			(thermal_bridge_width 0.5)
			(island_removal_mode 0)
		)
		(polygon
			(pts
				(arc
					(start 439.17489 -66.799968)
					(mid 425.174918 -80.79994)
					(end 411.174946 -66.799968)
				)
				(arc
					(start 411.174946 -66.799968)
					(mid 425.174918 -52.799996)
					(end 439.17489 -66.799968)
				)
			)
		)
	)
	(zone
		(net "12V_PRE_12")
		(layer "F.Cu")
		(hatch none 0.5)
		(connect_pads
			(clearance 0.5)
		)
		(min_thickness 0.25)
		(fill yes
			(thermal_gap 0.5)
			(thermal_bridge_width 0.5)
			(island_removal_mode 0)
		)
		(polygon
			(pts
				(xy 19.685 -149.733) (xy 19.558 -149.86) (xy 19.558 -151.384) (xy 20.955 -152.781) (xy 22.352 -152.781)
				(xy 27.305 -157.734) (xy 31.242 -157.734) (xy 31.369 -157.607) (xy 31.369 -156.845) (xy 31.242 -156.718)
				(xy 27.94 -156.718) (xy 20.955 -149.733)
			)
		)
	)
	(zone
		(net "5V_PRE_13")
		(layer "F.Cu")
		(hatch none 0.5)
		(connect_pads
			(clearance 0.5)
		)
		(min_thickness 0.25)
		(fill yes
			(thermal_gap 0.5)
			(thermal_bridge_width 0.5)
			(island_removal_mode 0)
		)
		(polygon
			(pts
				(xy 54.5084 -145.962624) (xy 54.356 -146.115024) (xy 54.356 -147.512024) (xy 54.9402 -148.096224)
				(xy 56.2102 -148.096224) (xy 58.293 -150.179024) (xy 62.738 -150.179024) (xy 62.865 -150.052024)
				(xy 62.865 -149.290024) (xy 62.738 -149.163024) (xy 59.7154 -149.163024) (xy 56.515 -145.962624)
			)
		)
	)
	(zone
		(net "P12V_B")
		(layer "F.Cu")
		(hatch none 0.5)
		(connect_pads
			(clearance 0.5)
		)
		(min_thickness 0.25)
		(fill yes
			(thermal_gap 0.5)
			(thermal_bridge_width 0.5)
			(island_removal_mode 0)
		)
		(polygon
			(pts
				(xy 469.265 -255.143) (xy 468.249 -256.159) (xy 467.614 -256.159) (xy 467.233 -256.54) (xy 467.233 -259.08)
				(xy 467.487 -259.334) (xy 470.789 -259.334) (xy 471.043 -259.08) (xy 471.043 -256.794) (xy 470.408 -256.159)
				(xy 470.00668 -256.159) (xy 469.748108 -255.900428) (xy 469.748108 -255.245108) (xy 469.646 -255.143)
			)
		)
		(polygon
			(pts
				(xy 469.2396 -255.7272) (xy 469.0364 -255.7272) (xy 469.0364 -255.9304) (xy 469.2396 -255.9304)
			)
		)
	)
	(zone
		(net "GND")
		(layer "F.Cu")
		(hatch none 0.5)
		(connect_pads
			(clearance 0.5)
		)
		(min_thickness 0.25)
		(fill yes
			(thermal_gap 0.5)
			(thermal_bridge_width 0.5)
			(island_removal_mode 0)
		)
		(polygon
			(pts
				(xy 90.538554 -79.795116) (xy 90.07856 -80.25511) (xy 90.07856 -101.621082) (xy 85.375496 -106.324146)
				(xy 82.634074 -106.324146) (xy 82.634074 -106.51871) (xy 72.423274 -106.51871)
				(arc
					(start 71.657464 -107.28452)
					(mid 71.485242 -107.733698)
					(end 71.261478 -108.15955)
				)
				(arc
					(start 71.261478 -108.789216)
					(mid 71.392959 -108.962435)
					(end 71.515224 -109.142276)
				)
				(arc
					(start 75.2602 -109.142276)
					(mid 76.683492 -109.392892)
					(end 77.935582 -110.114588)
				)
				(xy 109.346238 -110.114588) (xy 109.859064 -109.601762) (xy 109.859064 -108.63961)
				(arc
					(start 108.774484 -107.55503)
					(mid 107.997056 -107.0781)
					(end 107.34294 -106.44251)
				)
				(xy 105.211626 -106.44251)
				(arc
					(start 105.211626 -105.59796)
					(mid 104.729181 -105.411492)
					(end 104.274112 -105.165652)
				)
				(xy 102.053644 -105.165652)
				(arc
					(start 102.053644 -103.390954)
					(mid 100.657665 -101.931088)
					(end 100.149406 -99.976178)
				)
				(arc
					(start 100.149406 -99.620578)
					(mid 100.262203 -98.675951)
					(end 100.59416 -97.784412)
				)
				(arc
					(start 100.59416 -94.731078)
					(mid 100.893851 -93.224342)
					(end 101.74732 -91.946984)
				)
				(arc
					(start 102.60838 -91.085924)
					(mid 103.323696 -90.083824)
					(end 104.302052 -89.336372)
				)
				(xy 104.302052 -82.948272) (xy 101.595174 -80.241394)
				(arc
					(start 99.146106 -80.241394)
					(mid 95.631939 -80.593403)
					(end 92.191586 -79.795116)
				)
			)
		)
	)
	(zone
		(net "5V_PRE_20")
		(layer "F.Cu")
		(hatch none 0.5)
		(connect_pads
			(clearance 0.5)
		)
		(min_thickness 0.25)
		(fill yes
			(thermal_gap 0.5)
			(thermal_bridge_width 0.5)
			(island_removal_mode 0)
		)
		(polygon
			(pts
				(xy 392.557 -146.05) (xy 392.303 -146.304) (xy 392.303 -148.844) (xy 391.922 -149.225) (xy 389.382 -149.225)
				(xy 389.128 -149.479) (xy 389.128 -149.86) (xy 389.382 -150.114) (xy 392.684 -150.114) (xy 393.954 -148.844)
				(xy 393.954 -146.304) (xy 393.7 -146.05)
			)
		)
	)
	(zone
		(layer "F.Cu")
		(hatch none 0.5)
		(connect_pads
			(clearance 0)
		)
		(min_thickness 0.25)
		(keepout
			(tracks not_allowed)
			(vias allowed)
			(pads allowed)
			(copperpour not_allowed)
			(footprints allowed)
		)
		(placement
			(enabled no)
			(sheetname "")
		)
		(fill
			(thermal_gap 0.5)
			(thermal_bridge_width 0.5)
			(island_removal_mode 0)
		)
		(polygon
			(pts
				(arc
					(start 97.870772 -14.41958)
					(mid 97.385759 -13.934186)
					(end 96.900492 -14.419326)
				)
				(xy 96.900492 -14.768576)
				(arc
					(start 97.226628 -14.768576)
					(mid 97.285179 -14.744323)
					(end 97.309432 -14.685772)
				)
				(arc
					(start 97.309432 -14.67485)
					(mid 97.385632 -14.152682)
					(end 97.461832 -14.67485)
				)
				(xy 97.461832 -14.717268)
				(arc
					(start 97.459292 -14.719808)
					(mid 97.392897 -14.852041)
					(end 97.260664 -14.918436)
				)
				(xy 97.258124 -14.920976) (xy 96.900492 -14.920976) (xy 96.900492 -15.060676) (xy 97.258124 -15.060676)
				(arc
					(start 97.260664 -15.063216)
					(mid 97.392897 -15.129611)
					(end 97.459292 -15.261844)
				)
				(xy 97.461832 -15.264384)
				(arc
					(start 97.461832 -15.306802)
					(mid 97.385632 -15.82897)
					(end 97.309432 -15.306802)
				)
				(arc
					(start 97.309432 -15.29588)
					(mid 97.285179 -15.237329)
					(end 97.226628 -15.213076)
				)
				(xy 96.900492 -15.213076)
				(arc
					(start 96.900492 -15.562326)
					(mid 97.385632 -16.047466)
					(end 97.870772 -15.562326)
				)
			)
		)
	)
	(zone
		(layer "F.Cu")
		(hatch none 0.5)
		(connect_pads
			(clearance 0)
		)
		(min_thickness 0.25)
		(keepout
			(tracks allowed)
			(vias allowed)
			(pads allowed)
			(copperpour allowed)
			(footprints not_allowed)
		)
		(placement
			(enabled no)
			(sheetname "")
		)
		(fill
			(thermal_gap 0.5)
			(thermal_bridge_width 0.5)
			(island_removal_mode 0)
		)
		(polygon
			(pts
				(arc
					(start 152.32507 -178.799998)
					(mid 159.325056 -171.800012)
					(end 166.325042 -178.799998)
				)
				(arc
					(start 166.325042 -184.799986)
					(mid 159.325056 -191.799972)
					(end 152.32507 -184.799986)
				)
			)
		)
	)
	(zone
		(net "12V_PRE_8")
		(layer "F.Cu")
		(hatch none 0.5)
		(connect_pads
			(clearance 0.5)
		)
		(min_thickness 0.25)
		(fill yes
			(thermal_gap 0.5)
			(thermal_bridge_width 0.5)
			(island_removal_mode 0)
		)
		(polygon
			(pts
				(xy 394.128498 -269.686024) (xy 392.198098 -271.616424) (xy 389.200898 -271.616424) (xy 388.946898 -271.870424)
				(xy 388.946898 -272.581624) (xy 389.086598 -272.721324) (xy 391.372598 -272.721324) (xy 391.385298 -272.734024)
				(xy 395.068298 -272.734024) (xy 396.084298 -271.718024) (xy 396.084298 -269.813024) (xy 395.957298 -269.686024)
			)
		)
	)
	(zone
		(net "GND")
		(layer "F.Cu")
		(hatch none 0.5)
		(connect_pads
			(clearance 0.5)
		)
		(min_thickness 0.25)
		(fill yes
			(thermal_gap 0.5)
			(thermal_bridge_width 0.5)
			(island_removal_mode 0)
		)
		(polygon
			(pts
				(xy 428.63516 -172.75556) (xy 428.63516 -206.512922) (xy 429.288956 -207.166718) (xy 430.499012 -207.166718)
				(xy 433.861464 -203.804266)
				(arc
					(start 433.861464 -198.792084)
					(mid 433.658129 -197.5104)
					(end 433.861464 -196.228716)
				)
				(arc
					(start 433.861464 -178.963574)
					(mid 434.161223 -177.456672)
					(end 435.014878 -176.179226)
				)
				(arc
					(start 435.899052 -175.295052)
					(mid 437.176419 -174.441606)
					(end 438.683146 -174.141892)
				)
				(arc
					(start 441.38088 -174.141892)
					(mid 442.079816 -174.204422)
					(end 442.756544 -174.39005)
				)
				(arc
					(start 446.793112 -174.39005)
					(mid 447.054032 -173.846679)
					(end 447.3448 -173.318678)
				)
				(xy 447.3448 -173.077124) (xy 447.023236 -172.75556)
			)
		)
	)
	(zone
		(layer "F.Cu")
		(hatch none 0.5)
		(connect_pads
			(clearance 0)
		)
		(min_thickness 0.25)
		(keepout
			(tracks allowed)
			(vias allowed)
			(pads allowed)
			(copperpour allowed)
			(footprints allowed)
		)
		(placement
			(enabled no)
			(sheetname "")
		)
		(fill
			(thermal_gap 0.5)
			(thermal_bridge_width 0.5)
			(island_removal_mode 0)
		)
		(polygon
			(pts
				(xy 37.639498 -364.915196) (xy 37.639498 -363.947456) (xy 40.061134 -363.947456) (xy 40.061134 -364.915196)
			)
		)
	)
	(zone
		(layer "F.Cu")
		(hatch none 0.5)
		(connect_pads
			(clearance 0)
		)
		(min_thickness 0.25)
		(keepout
			(tracks not_allowed)
			(vias allowed)
			(pads allowed)
			(copperpour not_allowed)
			(footprints allowed)
		)
		(placement
			(enabled no)
			(sheetname "")
		)
		(fill
			(thermal_gap 0.5)
			(thermal_bridge_width 0.5)
			(island_removal_mode 0)
		)
		(polygon
			(pts
				(arc
					(start 387.17474 -248.115328)
					(mid 386.689727 -247.629934)
					(end 386.20446 -248.115074)
				)
				(arc
					(start 386.20446 -249.385074)
					(mid 386.6896 -249.870214)
					(end 387.17474 -249.385074)
				)
				(xy 387.17474 -248.972324)
				(arc
					(start 386.8166 -248.972324)
					(mid 386.780679 -248.987203)
					(end 386.7658 -249.023124)
				)
				(arc
					(start 386.7658 -249.12955)
					(mid 386.6896 -249.651718)
					(end 386.6134 -249.12955)
				)
				(xy 386.6134 -248.991628)
				(arc
					(start 386.616448 -248.98858)
					(mid 386.672979 -248.879503)
					(end 386.782056 -248.822972)
				)
				(xy 386.785104 -248.819924) (xy 387.17474 -248.819924) (xy 387.17474 -248.680224) (xy 386.785104 -248.680224)
				(arc
					(start 386.782056 -248.677176)
					(mid 386.672979 -248.620645)
					(end 386.616448 -248.511568)
				)
				(xy 386.6134 -248.50852)
				(arc
					(start 386.6134 -248.370598)
					(mid 386.6896 -247.84843)
					(end 386.7658 -248.370598)
				)
				(arc
					(start 386.7658 -248.477024)
					(mid 386.780679 -248.512945)
					(end 386.8166 -248.527824)
				)
				(xy 387.17474 -248.527824)
			)
		)
	)
	(zone
		(net "GND")
		(layer "F.Cu")
		(hatch none 0.5)
		(connect_pads
			(clearance 0.5)
		)
		(min_thickness 0.25)
		(fill yes
			(thermal_gap 0.5)
			(thermal_bridge_width 0.5)
			(island_removal_mode 0)
		)
		(polygon
			(pts
				(xy 43.950128 -59.353196) (xy 43.543474 -59.75985)
				(arc
					(start 43.543474 -60.239656)
					(mid 43.62745 -60.490508)
					(end 43.705272 -60.743338)
				)
				(xy 44.276772 -60.743338) (xy 44.593764 -60.426346)
				(arc
					(start 44.707556 -60.426346)
					(mid 45.817931 -59.850183)
					(end 47.052992 -59.651392)
				)
				(arc
					(start 49.492408 -59.651392)
					(mid 50.727468 -59.850188)
					(end 51.837844 -60.426346)
				)
				(xy 54.093618 -60.426346) (xy 54.093618 -70.373494) (xy 53.788056 -70.373494) (xy 53.788056 -84.03336)
				(xy 54.036722 -84.282026) (xy 54.461918 -84.282026) (xy 54.70144 -84.042504) (xy 54.70144 -59.353196)
			)
		)
	)
	(zone
		(layer "F.Cu")
		(hatch none 0.5)
		(connect_pads
			(clearance 0)
		)
		(min_thickness 0.25)
		(keepout
			(tracks not_allowed)
			(vias allowed)
			(pads allowed)
			(copperpour not_allowed)
			(footprints allowed)
		)
		(placement
			(enabled no)
			(sheetname "")
		)
		(fill
			(thermal_gap 0.5)
			(thermal_bridge_width 0.5)
			(island_removal_mode 0)
		)
		(polygon
			(pts
				(arc
					(start 336.55 -13.999972)
					(mid 341.300054 -9.249918)
					(end 346.050108 -13.999972)
				)
				(arc
					(start 346.050108 -13.999972)
					(mid 341.300054 -18.750026)
					(end 336.55 -13.999972)
				)
			)
		)
	)
	(zone
		(net "GND")
		(layer "F.Cu")
		(hatch none 0.5)
		(connect_pads
			(clearance 0.5)
		)
		(min_thickness 0.25)
		(fill yes
			(thermal_gap 0.5)
			(thermal_bridge_width 0.5)
			(island_removal_mode 0)
		)
		(polygon
			(pts
				(xy 285.387542 -378.091192) (xy 285.235142 -378.243592) (xy 285.235142 -380.377192) (xy 285.387542 -380.529592)
				(xy 287.444942 -380.529592) (xy 287.648142 -380.326392) (xy 287.648142 -378.345192) (xy 287.394142 -378.091192)
			)
		)
	)
	(zone
		(net "P12V_B_2_VIN_U32")
		(layer "F.Cu")
		(hatch none 0.5)
		(connect_pads
			(clearance 0.5)
		)
		(min_thickness 0.25)
		(fill yes
			(thermal_gap 0.5)
			(thermal_bridge_width 0.5)
			(island_removal_mode 0)
		)
		(polygon
			(pts
				(xy 41.927018 -110.061248) (xy 40.871394 -111.116872) (xy 40.871394 -113.437162) (xy 41.072562 -113.63833)
				(xy 43.7515 -113.63833) (xy 43.860466 -113.529364) (xy 43.860466 -110.165388) (xy 43.756326 -110.061248)
			)
		)
	)
	(zone
		(net "MB3_CM_GATE_R")
		(layer "F.Cu")
		(hatch none 0.5)
		(connect_pads
			(clearance 0.5)
		)
		(min_thickness 0.25)
		(fill yes
			(thermal_gap 0.5)
			(thermal_bridge_width 0.5)
			(island_removal_mode 0)
		)
		(polygon
			(pts
				(xy 266.069826 -336.517996) (xy 265.948414 -336.639408) (xy 265.948414 -338.10448) (xy 266.039854 -338.19592)
				(xy 268.042644 -338.19592) (xy 268.203172 -338.035392) (xy 268.203172 -336.59445) (xy 268.126718 -336.517996)
			)
		)
	)
	(zone
		(layer "F.Cu")
		(hatch none 0.5)
		(connect_pads
			(clearance 0)
		)
		(min_thickness 0.25)
		(keepout
			(tracks not_allowed)
			(vias allowed)
			(pads allowed)
			(copperpour not_allowed)
			(footprints allowed)
		)
		(placement
			(enabled no)
			(sheetname "")
		)
		(fill
			(thermal_gap 0.5)
			(thermal_bridge_width 0.5)
			(island_removal_mode 0)
		)
		(polygon
			(pts
				(arc
					(start 97.870772 -244.419374)
					(mid 97.385632 -243.934234)
					(end 96.900492 -244.419374)
				)
				(xy 96.900492 -244.768624)
				(arc
					(start 97.226628 -244.768624)
					(mid 97.285179 -244.744371)
					(end 97.309432 -244.68582)
				)
				(arc
					(start 97.309432 -244.674898)
					(mid 97.385632 -244.15273)
					(end 97.461832 -244.674898)
				)
				(xy 97.461832 -244.717316)
				(arc
					(start 97.459292 -244.719856)
					(mid 97.392897 -244.852089)
					(end 97.260664 -244.918484)
				)
				(xy 97.258124 -244.921024) (xy 96.900492 -244.921024) (xy 96.900492 -245.060724) (xy 97.258124 -245.060724)
				(arc
					(start 97.260664 -245.063264)
					(mid 97.392897 -245.129659)
					(end 97.459292 -245.261892)
				)
				(xy 97.461832 -245.264432)
				(arc
					(start 97.461832 -245.30685)
					(mid 97.385632 -245.829018)
					(end 97.309432 -245.30685)
				)
				(arc
					(start 97.309432 -245.295928)
					(mid 97.285179 -245.237377)
					(end 97.226628 -245.213124)
				)
				(xy 96.900492 -245.213124)
				(arc
					(start 96.900492 -245.56212)
					(mid 97.385505 -246.047514)
					(end 97.870772 -245.562374)
				)
			)
		)
	)
	(zone
		(layer "F.Cu")
		(hatch none 0.5)
		(connect_pads
			(clearance 0)
		)
		(min_thickness 0.25)
		(keepout
			(tracks allowed)
			(vias allowed)
			(pads allowed)
			(copperpour allowed)
			(footprints allowed)
		)
		(placement
			(enabled no)
			(sheetname "")
		)
		(fill
			(thermal_gap 0.5)
			(thermal_bridge_width 0.5)
			(island_removal_mode 0)
		)
		(polygon
			(pts
				(xy 344.297 -98.298) (xy 343.2302 -98.298) (xy 343.2302 -96.9518) (xy 344.297 -96.9518)
			)
		)
	)
	(zone
		(net "P12V_B")
		(layer "F.Cu")
		(hatch none 0.5)
		(connect_pads
			(clearance 0.5)
		)
		(min_thickness 0.25)
		(fill yes
			(thermal_gap 0.5)
			(thermal_bridge_width 0.5)
			(island_removal_mode 0)
		)
		(polygon
			(pts
				(xy 334.645 -257.429) (xy 334.137 -257.937) (xy 334.137 -261.366) (xy 334.391 -261.62) (xy 337.693 -261.62)
				(xy 337.947 -261.366) (xy 337.947 -259.334) (xy 338.074 -259.207) (xy 338.455 -259.207) (xy 338.553552 -259.108448)
				(xy 338.553552 -257.527552) (xy 338.455 -257.429)
			)
		)
		(polygon
			(pts
				(xy 338.0486 -258.4196) (xy 337.8454 -258.4196) (xy 337.8454 -258.6228) (xy 338.0486 -258.6228)
			)
		)
		(polygon
			(pts
				(xy 338.0994 -257.9878) (xy 337.8962 -257.9878) (xy 337.8962 -258.191) (xy 338.0994 -258.191)
			)
		)
	)
	(zone
		(net "12V_PRE_31")
		(layer "F.Cu")
		(hatch none 0.5)
		(connect_pads
			(clearance 0.5)
		)
		(min_thickness 0.25)
		(fill yes
			(thermal_gap 0.5)
			(thermal_bridge_width 0.5)
			(island_removal_mode 0)
		)
		(polygon
			(pts
				(xy 362.143802 -39.685976) (xy 360.111802 -41.717976) (xy 357.546402 -41.717976) (xy 357.292402 -41.971976)
				(xy 357.292402 -42.505376) (xy 357.521002 -42.733976) (xy 363.515402 -42.733976) (xy 364.531402 -41.717976)
				(xy 364.531402 -39.812976) (xy 364.404402 -39.685976)
			)
		)
	)
	(zone
		(net "P3V3_IN")
		(layer "F.Cu")
		(hatch none 0.5)
		(connect_pads
			(clearance 0.5)
		)
		(min_thickness 0.25)
		(fill yes
			(thermal_gap 0.5)
			(thermal_bridge_width 0.5)
			(island_removal_mode 0)
		)
		(polygon
			(pts
				(xy 277.885906 -375.601992) (xy 277.669498 -375.8184) (xy 277.669498 -377.668536) (xy 277.812754 -377.811792)
				(xy 284.366208 -377.811792) (xy 284.584648 -377.593352) (xy 284.584648 -375.793) (xy 284.39364 -375.601992)
			)
		)
	)
	(zone
		(layer "F.Cu")
		(hatch none 0.5)
		(connect_pads
			(clearance 0)
		)
		(min_thickness 0.25)
		(keepout
			(tracks not_allowed)
			(vias allowed)
			(pads allowed)
			(copperpour not_allowed)
			(footprints allowed)
		)
		(placement
			(enabled no)
			(sheetname "")
		)
		(fill
			(thermal_gap 0.5)
			(thermal_bridge_width 0.5)
			(island_removal_mode 0)
		)
		(polygon
			(pts
				(arc
					(start 417.331906 -16.95196)
					(mid 416.846512 -17.436973)
					(end 417.331652 -17.92224)
				)
				(xy 417.744402 -17.92224)
				(arc
					(start 417.744402 -17.599152)
					(mid 417.719257 -17.538445)
					(end 417.65855 -17.5133)
				)
				(arc
					(start 417.587176 -17.5133)
					(mid 417.065008 -17.4371)
					(end 417.587176 -17.3609)
				)
				(xy 417.690046 -17.3609)
				(arc
					(start 417.692586 -17.36344)
					(mid 417.826952 -17.43075)
					(end 417.894262 -17.565116)
				)
				(xy 417.896802 -17.567656) (xy 417.896802 -17.92224) (xy 418.036502 -17.92224) (xy 418.036502 -17.567656)
				(arc
					(start 418.039042 -17.565116)
					(mid 418.106352 -17.43075)
					(end 418.240718 -17.36344)
				)
				(xy 418.243258 -17.3609)
				(arc
					(start 418.346128 -17.3609)
					(mid 418.868296 -17.4371)
					(end 418.346128 -17.5133)
				)
				(arc
					(start 418.274754 -17.5133)
					(mid 418.214047 -17.538445)
					(end 418.188902 -17.599152)
				)
				(xy 418.188902 -17.92224)
				(arc
					(start 418.601652 -17.92224)
					(mid 419.086792 -17.4371)
					(end 418.601652 -16.95196)
				)
			)
		)
	)
	(zone
		(layer "F.Cu")
		(hatch none 0.5)
		(connect_pads
			(clearance 0)
		)
		(min_thickness 0.25)
		(keepout
			(tracks allowed)
			(vias allowed)
			(pads allowed)
			(copperpour allowed)
			(footprints allowed)
		)
		(placement
			(enabled no)
			(sheetname "")
		)
		(fill
			(thermal_gap 0.5)
			(thermal_bridge_width 0.5)
			(island_removal_mode 0)
		)
		(polygon
			(pts
				(xy 181.5338 -374.3452) (xy 182.8038 -374.3452) (xy 182.9816 -374.1674) (xy 182.9816 -373.6848)
				(xy 182.7276 -373.4308) (xy 181.4322 -373.4308) (xy 181.4068 -373.4562) (xy 181.4068 -374.2182)
			)
		)
	)
	(zone
		(layer "F.Cu")
		(hatch none 0.5)
		(connect_pads
			(clearance 0)
		)
		(min_thickness 0.25)
		(keepout
			(tracks allowed)
			(vias allowed)
			(pads allowed)
			(copperpour allowed)
			(footprints allowed)
		)
		(placement
			(enabled no)
			(sheetname "")
		)
		(fill
			(thermal_gap 0.5)
			(thermal_bridge_width 0.5)
			(island_removal_mode 0)
		)
		(polygon
			(pts
				(xy 241.935 -309.7276) (xy 241.935 -308.102) (xy 244.4496 -308.102) (xy 244.4496 -309.7276)
			)
		)
	)
	(zone
		(net "MB3_CM_GATE")
		(layer "F.Cu")
		(hatch none 0.5)
		(connect_pads
			(clearance 0.5)
		)
		(min_thickness 0.25)
		(fill yes
			(thermal_gap 0.5)
			(thermal_bridge_width 0.5)
			(island_removal_mode 0)
		)
		(polygon
			(pts
				(xy 261.877302 -354.552758) (xy 261.678674 -354.751386) (xy 261.678674 -355.979222) (xy 261.919974 -356.220522)
				(xy 265.128248 -356.220522) (xy 265.418824 -355.929946) (xy 265.418824 -354.82276) (xy 265.148822 -354.552758)
			)
		)
	)
	(zone
		(layer "F.Cu")
		(hatch none 0.5)
		(connect_pads
			(clearance 0)
		)
		(min_thickness 0.25)
		(keepout
			(tracks allowed)
			(vias allowed)
			(pads allowed)
			(copperpour allowed)
			(footprints allowed)
		)
		(placement
			(enabled no)
			(sheetname "")
		)
		(fill
			(thermal_gap 0.5)
			(thermal_bridge_width 0.5)
			(island_removal_mode 0)
		)
		(polygon
			(pts
				(xy 219.6338 -222.6818) (xy 219.6338 -223.7486) (xy 217.9828 -223.7486) (xy 217.9828 -222.6818)
			)
		)
	)
	(zone
		(layer "F.Cu")
		(hatch none 0.5)
		(connect_pads
			(clearance 0)
		)
		(min_thickness 0.25)
		(keepout
			(tracks allowed)
			(vias allowed)
			(pads allowed)
			(copperpour allowed)
			(footprints allowed)
		)
		(placement
			(enabled no)
			(sheetname "")
		)
		(fill
			(thermal_gap 0.5)
			(thermal_bridge_width 0.5)
			(island_removal_mode 0)
		)
		(polygon
			(pts
				(xy 318.712596 -380.1999) (xy 318.712596 -379.2093) (xy 318.712596 -378.2949) (xy 319.931796 -378.2949)
				(xy 319.931796 -380.1999) (xy 319.499996 -380.1999)
			)
		)
	)
	(zone
		(net "GND")
		(layer "F.Cu")
		(hatch none 0.5)
		(connect_pads
			(clearance 0.5)
		)
		(min_thickness 0.25)
		(fill yes
			(thermal_gap 0.5)
			(thermal_bridge_width 0.5)
			(island_removal_mode 0)
		)
		(polygon
			(pts
				(xy 133.710934 -363.570266) (xy 133.671818 -363.609382) (xy 132.792978 -363.609382) (xy 132.78358 -363.61878)
				(xy 132.73278 -363.669326) (xy 132.73278 -365.66983) (xy 133.340602 -366.277652) (xy 137.658348 -366.277652)
				(xy 138.482578 -365.453422) (xy 138.482578 -364.151418) (xy 137.901426 -363.570266)
			)
		)
		(polygon
			(pts
				(xy 134.730236 -364.446566) (xy 134.527036 -364.446566) (xy 134.527036 -364.649766) (xy 134.730236 -364.649766)
			)
		)
		(polygon
			(pts
				(xy 133.866636 -364.446566) (xy 133.663436 -364.446566) (xy 133.663436 -364.649766) (xy 133.866636 -364.649766)
			)
		)
		(polygon
			(pts
				(xy 133.555994 -364.117636) (xy 133.352794 -364.117636) (xy 133.352794 -364.320836) (xy 133.555994 -364.320836)
			)
		)
	)
	(zone
		(layer "F.Cu")
		(hatch none 0.5)
		(connect_pads
			(clearance 0)
		)
		(min_thickness 0.25)
		(keepout
			(tracks not_allowed)
			(vias allowed)
			(pads allowed)
			(copperpour not_allowed)
			(footprints allowed)
		)
		(placement
			(enabled no)
			(sheetname "")
		)
		(fill
			(thermal_gap 0.5)
			(thermal_bridge_width 0.5)
			(island_removal_mode 0)
		)
		(polygon
			(pts
				(arc
					(start 192.520824 -244.419374)
					(mid 192.035684 -243.934234)
					(end 191.550544 -244.419374)
				)
				(xy 191.550544 -244.768624)
				(arc
					(start 191.87668 -244.768624)
					(mid 191.935231 -244.744371)
					(end 191.959484 -244.68582)
				)
				(arc
					(start 191.959484 -244.674898)
					(mid 192.035684 -244.15273)
					(end 192.111884 -244.674898)
				)
				(xy 192.111884 -244.717316)
				(arc
					(start 192.109344 -244.719856)
					(mid 192.042949 -244.852089)
					(end 191.910716 -244.918484)
				)
				(xy 191.908176 -244.921024) (xy 191.550544 -244.921024) (xy 191.550544 -245.060724) (xy 191.908176 -245.060724)
				(arc
					(start 191.910716 -245.063264)
					(mid 192.042949 -245.129659)
					(end 192.109344 -245.261892)
				)
				(xy 192.111884 -245.264432)
				(arc
					(start 192.111884 -245.30685)
					(mid 192.035684 -245.829018)
					(end 191.959484 -245.30685)
				)
				(arc
					(start 191.959484 -245.295928)
					(mid 191.935231 -245.237377)
					(end 191.87668 -245.213124)
				)
				(xy 191.550544 -245.213124)
				(arc
					(start 191.550544 -245.56212)
					(mid 192.035557 -246.047514)
					(end 192.520824 -245.562374)
				)
			)
		)
	)
	(zone
		(net "P3V3_STBY_B")
		(layer "F.Cu")
		(hatch none 0.5)
		(connect_pads
			(clearance 0.5)
		)
		(min_thickness 0.25)
		(fill yes
			(thermal_gap 0.5)
			(thermal_bridge_width 0.5)
			(island_removal_mode 0)
		)
		(polygon
			(pts
				(xy 252.479048 -131.147058) (xy 252.454918 -131.171188) (xy 252.454918 -134.731506) (xy 252.562868 -134.839456)
				(xy 253.919736 -134.839456) (xy 254.021844 -134.737348) (xy 254.021844 -134.38632) (xy 253.36754 -133.732016)
				(xy 253.36754 -131.4831) (xy 253.031498 -131.147058)
			)
		)
		(polygon
			(pts
				(xy 253.152402 -133.897878) (xy 252.949202 -133.897878) (xy 252.949202 -134.101078) (xy 253.152402 -134.101078)
			)
		)
		(polygon
			(pts
				(xy 253.152402 -133.339078) (xy 252.949202 -133.339078) (xy 252.949202 -133.542278) (xy 253.152402 -133.542278)
			)
		)
		(polygon
			(pts
				(xy 253.146052 -131.606798) (xy 252.942852 -131.606798) (xy 252.942852 -131.809998) (xy 253.146052 -131.809998)
			)
		)
	)
	(zone
		(net "12V_PRE_7")
		(layer "F.Cu")
		(hatch none 0.5)
		(connect_pads
			(clearance 0.5)
		)
		(min_thickness 0.25)
		(fill yes
			(thermal_gap 0.5)
			(thermal_bridge_width 0.5)
			(island_removal_mode 0)
		)
		(polygon
			(pts
				(xy 362.57865 -269.686024) (xy 360.64825 -271.616424) (xy 357.65105 -271.616424) (xy 357.39705 -271.870424)
				(xy 357.39705 -272.581624) (xy 357.53675 -272.721324) (xy 359.82275 -272.721324) (xy 359.83545 -272.734024)
				(xy 363.51845 -272.734024) (xy 364.53445 -271.718024) (xy 364.53445 -269.813024) (xy 364.40745 -269.686024)
			)
		)
	)
	(zone
		(net "P5V_B_4")
		(layer "F.Cu")
		(hatch none 0.5)
		(connect_pads
			(clearance 0.5)
		)
		(min_thickness 0.25)
		(fill yes
			(thermal_gap 0.5)
			(thermal_bridge_width 0.5)
			(island_removal_mode 0)
		)
		(polygon
			(pts
				(xy 462.915 -136.398) (xy 462.661 -136.652) (xy 462.661 -141.351) (xy 462.915 -141.605) (xy 465.201 -141.605)
				(xy 465.455 -141.351) (xy 465.455 -136.652) (xy 465.201 -136.398)
			)
		)
	)
	(zone
		(layer "F.Cu")
		(hatch none 0.5)
		(connect_pads
			(clearance 0)
		)
		(min_thickness 0.25)
		(keepout
			(tracks not_allowed)
			(vias allowed)
			(pads allowed)
			(copperpour not_allowed)
			(footprints allowed)
		)
		(placement
			(enabled no)
			(sheetname "")
		)
		(fill
			(thermal_gap 0.5)
			(thermal_bridge_width 0.5)
			(island_removal_mode 0)
		)
		(polygon
			(pts
				(arc
					(start 160.970722 -129.419604)
					(mid 160.485709 -128.93421)
					(end 160.000442 -129.41935)
				)
				(xy 160.000442 -129.7686)
				(arc
					(start 160.326578 -129.7686)
					(mid 160.385129 -129.744347)
					(end 160.409382 -129.685796)
				)
				(arc
					(start 160.409382 -129.674874)
					(mid 160.485582 -129.152706)
					(end 160.561782 -129.674874)
				)
				(xy 160.561782 -129.717292)
				(arc
					(start 160.559242 -129.719832)
					(mid 160.492847 -129.852065)
					(end 160.360614 -129.91846)
				)
				(xy 160.358074 -129.921) (xy 160.000442 -129.921) (xy 160.000442 -130.0607) (xy 160.358074 -130.0607)
				(arc
					(start 160.360614 -130.06324)
					(mid 160.492847 -130.129635)
					(end 160.559242 -130.261868)
				)
				(xy 160.561782 -130.264408)
				(arc
					(start 160.561782 -130.306826)
					(mid 160.485582 -130.828994)
					(end 160.409382 -130.306826)
				)
				(arc
					(start 160.409382 -130.295904)
					(mid 160.385129 -130.237353)
					(end 160.326578 -130.2131)
				)
				(xy 160.000442 -130.2131)
				(arc
					(start 160.000442 -130.56235)
					(mid 160.485582 -131.04749)
					(end 160.970722 -130.56235)
				)
			)
		)
	)
	(zone
		(net "GND")
		(layer "F.Cu")
		(hatch none 0.5)
		(connect_pads
			(clearance 0.5)
		)
		(min_thickness 0.25)
		(fill yes
			(thermal_gap 0.5)
			(thermal_bridge_width 0.5)
			(island_removal_mode 0)
		)
		(polygon
			(pts
				(xy 279.317958 -100.322888) (xy 278.892 -100.748846) (xy 278.892 -103.96093) (xy 279.444958 -104.513888)
				(xy 285.921958 -104.513888) (xy 286.175958 -104.259888) (xy 286.175958 -100.576888) (xy 285.921958 -100.322888)
			)
		)
	)
	(zone
		(net "12V_PRE_16")
		(layer "F.Cu")
		(hatch none 0.5)
		(connect_pads
			(clearance 0.5)
		)
		(min_thickness 0.25)
		(fill yes
			(thermal_gap 0.5)
			(thermal_bridge_width 0.5)
			(island_removal_mode 0)
		)
		(polygon
			(pts
				(xy 145.923 -149.733) (xy 145.796 -149.86) (xy 145.796 -151.384) (xy 147.193 -152.781) (xy 148.59 -152.781)
				(xy 153.543 -157.734) (xy 157.48 -157.734) (xy 157.607 -157.607) (xy 157.607 -156.845) (xy 157.48 -156.718)
				(xy 154.178 -156.718) (xy 147.193 -149.733)
			)
		)
	)
	(zone
		(net "P5V_HDD22")
		(layer "F.Cu")
		(hatch none 0.5)
		(connect_pads
			(clearance 0.5)
		)
		(min_thickness 0.25)
		(fill yes
			(thermal_gap 0.5)
			(thermal_bridge_width 0.5)
			(island_removal_mode 0)
		)
		(polygon
			(pts
				(xy 457.708 -137.795) (xy 457.454 -138.049) (xy 457.454 -148.844) (xy 455.803 -150.495) (xy 452.374 -150.495)
				(xy 452.12 -150.749) (xy 452.12 -152.4) (xy 452.374 -152.654) (xy 456.946 -152.654) (xy 457.581 -152.019)
				(xy 459.359 -152.019) (xy 459.867 -151.511) (xy 459.867 -138.049) (xy 459.613 -137.795)
			)
		)
		(polygon
			(pts
				(xy 456.4634 -151.6634) (xy 456.2602 -151.6634) (xy 456.2602 -151.8666) (xy 456.4634 -151.8666)
			)
		)
		(polygon
			(pts
				(xy 455.5998 -151.6634) (xy 455.3966 -151.6634) (xy 455.3966 -151.8666) (xy 455.5998 -151.8666)
			)
		)
	)
	(zone
		(net "GND")
		(layer "F.Cu")
		(hatch none 0.5)
		(connect_pads
			(clearance 0.5)
		)
		(min_thickness 0.25)
		(fill yes
			(thermal_gap 0.5)
			(thermal_bridge_width 0.5)
			(island_removal_mode 0)
		)
		(polygon
			(pts
				(xy 73.279 -331.47) (xy 72.771 -331.978) (xy 72.771 -346.456) (xy 73.279 -346.964) (xy 101.219 -346.964)
				(xy 101.981 -346.202) (xy 101.981 -332.486) (xy 100.965 -331.47)
			)
		)
	)
	(zone
		(net "5V_PRE_17")
		(layer "F.Cu")
		(hatch none 0.5)
		(connect_pads
			(clearance 0.5)
		)
		(min_thickness 0.25)
		(fill yes
			(thermal_gap 0.5)
			(thermal_bridge_width 0.5)
			(island_removal_mode 0)
		)
		(polygon
			(pts
				(xy 180.708554 -145.962624) (xy 180.556154 -146.115024) (xy 180.556154 -147.512024) (xy 181.140354 -148.096224)
				(xy 182.410354 -148.096224) (xy 184.493154 -150.179024) (xy 188.938154 -150.179024) (xy 189.065154 -150.052024)
				(xy 189.065154 -149.290024) (xy 188.938154 -149.163024) (xy 185.915554 -149.163024) (xy 182.715154 -145.962624)
			)
		)
	)
	(zone
		(layer "F.Cu")
		(hatch none 0.5)
		(connect_pads
			(clearance 0)
		)
		(min_thickness 0.25)
		(keepout
			(tracks allowed)
			(vias allowed)
			(pads allowed)
			(copperpour allowed)
			(footprints allowed)
		)
		(placement
			(enabled no)
			(sheetname "")
		)
		(fill
			(thermal_gap 0.5)
			(thermal_bridge_width 0.5)
			(island_removal_mode 0)
		)
		(polygon
			(pts
				(xy 51.985418 -8.30834) (xy 51.985418 -9.89965) (xy 50.07737 -9.89965) (xy 50.07737 -8.30834)
			)
		)
	)
	(zone
		(net "12V_PRE_2")
		(layer "F.Cu")
		(hatch none 0.5)
		(connect_pads
			(clearance 0.5)
		)
		(min_thickness 0.25)
		(fill yes
			(thermal_gap 0.5)
			(thermal_bridge_width 0.5)
			(island_removal_mode 0)
		)
		(polygon
			(pts
				(xy 82.804 -264.795) (xy 82.677 -264.922) (xy 82.677 -266.446) (xy 84.074 -267.843) (xy 85.471 -267.843)
				(xy 90.424 -272.796) (xy 94.361 -272.796) (xy 94.488 -272.669) (xy 94.488 -271.907) (xy 94.361 -271.78)
				(xy 91.059 -271.78) (xy 84.074 -264.795)
			)
		)
	)
	(zone
		(net "MB0_CM_GATE_C")
		(layer "F.Cu")
		(hatch none 0.5)
		(connect_pads
			(clearance 0.5)
		)
		(min_thickness 0.25)
		(fill yes
			(thermal_gap 0.5)
			(thermal_bridge_width 0.5)
			(island_removal_mode 0)
		)
		(polygon
			(pts
				(xy 214.642446 -352.983292) (xy 214.515446 -353.110292) (xy 214.515446 -354.473256) (xy 214.64524 -354.60305)
				(xy 217.921332 -354.60305) (xy 218.127072 -354.39731) (xy 218.127072 -353.149408) (xy 217.960956 -352.983292)
			)
		)
		(polygon
			(pts
				(xy 217.362532 -354.124768) (xy 217.159332 -354.124768) (xy 217.159332 -354.327968) (xy 217.362532 -354.327968)
			)
		)
		(polygon
			(pts
				(xy 217.362532 -353.261168) (xy 217.159332 -353.261168) (xy 217.159332 -353.464368) (xy 217.362532 -353.464368)
			)
		)
	)
	(zone
		(net "GND")
		(layer "F.Cu")
		(hatch none 0.5)
		(connect_pads
			(clearance 0.5)
		)
		(min_thickness 0.25)
		(fill yes
			(thermal_gap 0.5)
			(thermal_bridge_width 0.5)
			(island_removal_mode 0)
		)
		(polygon
			(pts
				(xy 298.465494 -271.357852)
				(arc
					(start 297.558968 -272.264378)
					(mid 296.882611 -275.254662)
					(end 294.318182 -276.93493)
				)
				(arc
					(start 294.318182 -276.93493)
					(mid 293.823077 -277.031356)
					(end 293.319708 -277.063708)
				)
				(xy 267.845286 -277.063708) (xy 266.140946 -278.768048)
				(arc
					(start 266.140946 -281.802332)
					(mid 266.237354 -283.733062)
					(end 265.43635 -285.492444)
				)
				(arc
					(start 265.43635 -285.492444)
					(mid 265.384594 -285.851551)
					(end 265.301222 -286.20466)
				)
				(arc
					(start 265.301222 -286.20466)
					(mid 265.754881 -288.143024)
					(end 265.239754 -290.065968)
				)
				(xy 265.239754 -292.915594) (xy 266.28217 -293.95801)
				(arc
					(start 275.13026 -293.95801)
					(mid 275.491712 -292.897444)
					(end 276.058376 -291.930836)
				)
				(arc
					(start 276.058376 -290.111942)
					(mid 275.360068 -288.152229)
					(end 275.635466 -286.090106)
				)
				(arc
					(start 275.635466 -286.090106)
					(mid 276.10838 -281.993443)
					(end 279.756108 -280.069798)
				)
				(arc
					(start 281.458162 -280.069798)
					(mid 282.200614 -280.132596)
					(end 282.921964 -280.319226)
				)
				(arc
					(start 282.921964 -280.319226)
					(mid 283.643317 -280.132617)
					(end 284.385766 -280.069798)
				)
				(arc
					(start 286.08782 -280.069798)
					(mid 289.735556 -281.993438)
					(end 290.208462 -286.090106)
				)
				(arc
					(start 290.208462 -286.090106)
					(mid 289.764214 -290.144363)
					(end 286.190182 -292.109144)
				)
				(xy 285.74238 -292.556946)
				(arc
					(start 285.74238 -293.215314)
					(mid 285.951057 -293.878497)
					(end 286.075374 -294.56253)
				)
				(xy 286.746442 -295.233598) (xy 295.726104 -295.233598) (xy 298.182538 -297.690032) (xy 298.182538 -303.705006)
				(xy 295.562782 -306.324762) (xy 293.275766 -306.324762) (xy 292.252654 -307.347874) (xy 292.252654 -308.655974)
				(xy 293.603426 -310.006746) (xy 315.607446 -310.006746) (xy 319.853818 -305.760374)
				(arc
					(start 319.853818 -293.799768)
					(mid 320.394568 -290.4218)
					(end 321.96278 -287.381442)
				)
				(xy 321.961256 -287.379918) (xy 321.961256 -286.282892) (xy 321.569588 -285.891224) (xy 320.44386 -285.891224)
				(xy 320.44386 -275.6789) (xy 321.1957 -275.6789) (xy 321.649852 -275.224748) (xy 321.649852 -274.454112)
				(xy 320.93281 -273.73707)
				(arc
					(start 320.451988 -273.73707)
					(mid 317.553124 -273.580556)
					(end 315.442346 -271.587468)
				)
				(xy 315.21273 -271.357852)
				(arc
					(start 312.205116 -271.357852)
					(mid 310.803036 -271.60244)
					(end 309.400956 -271.357852)
				)
			)
		)
	)
	(zone
		(layer "F.Cu")
		(hatch none 0.5)
		(connect_pads
			(clearance 0)
		)
		(min_thickness 0.25)
		(keepout
			(tracks allowed)
			(vias allowed)
			(pads allowed)
			(copperpour allowed)
			(footprints allowed)
		)
		(placement
			(enabled no)
			(sheetname "")
		)
		(fill
			(thermal_gap 0.5)
			(thermal_bridge_width 0.5)
			(island_removal_mode 0)
		)
		(polygon
			(pts
				(xy 458.089 -11.1506) (xy 457.0222 -11.1506) (xy 457.0222 -9.4996) (xy 458.089 -9.4996)
			)
		)
	)
	(zone
		(layer "F.Cu")
		(hatch none 0.5)
		(connect_pads
			(clearance 0)
		)
		(min_thickness 0.25)
		(keepout
			(tracks allowed)
			(vias allowed)
			(pads allowed)
			(copperpour allowed)
			(footprints allowed)
		)
		(placement
			(enabled no)
			(sheetname "")
		)
		(fill
			(thermal_gap 0.5)
			(thermal_bridge_width 0.5)
			(island_removal_mode 0)
		)
		(polygon
			(pts
				(xy 233.06151 -309.822342) (xy 233.06151 -308.80177) (xy 235.57611 -308.80177) (xy 235.57611 -309.822342)
			)
		)
	)
	(zone
		(net "P12V_B")
		(layer "F.Cu")
		(hatch none 0.5)
		(connect_pads
			(clearance 0.5)
		)
		(min_thickness 0.25)
		(fill yes
			(thermal_gap 0.5)
			(thermal_bridge_width 0.5)
			(island_removal_mode 0)
		)
		(polygon
			(pts
				(xy 45.740828 -18.860262) (xy 44.880022 -19.721068) (xy 44.26331 -19.721068) (xy 43.307 -20.677378)
				(xy 43.307 -22.606) (xy 43.561 -22.86) (xy 46.863 -22.86) (xy 47.117 -22.606) (xy 47.117 -19.124422)
				(xy 46.85284 -18.860262)
			)
		)
	)
	(zone
		(net "P12V_HDD16")
		(layer "F.Cu")
		(hatch none 0.5)
		(connect_pads
			(clearance 0.5)
		)
		(min_thickness 0.25)
		(fill yes
			(thermal_gap 0.5)
			(thermal_bridge_width 0.5)
			(island_removal_mode 0)
		)
		(polygon
			(pts
				(xy 138.557 -147.193) (xy 138.303 -147.447) (xy 138.303 -149.098) (xy 138.557 -149.352) (xy 140.716 -149.352)
				(xy 141.224 -149.86) (xy 141.224 -152.4) (xy 148.971 -160.147) (xy 157.48 -160.147) (xy 157.607 -160.02)
				(xy 157.607 -158.242) (xy 157.48 -158.115) (xy 151.511 -158.115) (xy 150.876 -157.48) (xy 149.225 -157.48)
				(xy 144.907 -153.162) (xy 144.907 -149.606) (xy 143.764 -148.463) (xy 143.764 -147.447) (xy 143.51 -147.193)
			)
		)
		(polygon
			(pts
				(xy 151.0284 -159.1564) (xy 150.8252 -159.1564) (xy 150.8252 -159.3596) (xy 151.0284 -159.3596)
			)
		)
		(polygon
			(pts
				(xy 150.1648 -159.1564) (xy 149.9616 -159.1564) (xy 149.9616 -159.3596) (xy 150.1648 -159.3596)
			)
		)
	)
	(zone
		(net "12V_PRE_30")
		(layer "F.Cu")
		(hatch none 0.5)
		(connect_pads
			(clearance 0.5)
		)
		(min_thickness 0.25)
		(fill yes
			(thermal_gap 0.5)
			(thermal_bridge_width 0.5)
			(island_removal_mode 0)
		)
		(polygon
			(pts
				(xy 330.5937 -39.685976) (xy 328.5617 -41.717976) (xy 325.9963 -41.717976) (xy 325.7423 -41.971976)
				(xy 325.7423 -42.505376) (xy 325.9709 -42.733976) (xy 331.9653 -42.733976) (xy 332.9813 -41.717976)
				(xy 332.9813 -39.812976) (xy 332.8543 -39.685976)
			)
		)
	)
	(zone
		(net "P12V_HDD15")
		(layer "F.Cu")
		(hatch none 0.5)
		(connect_pads
			(clearance 0.5)
		)
		(min_thickness 0.25)
		(fill yes
			(thermal_gap 0.5)
			(thermal_bridge_width 0.5)
			(island_removal_mode 0)
		)
		(polygon
			(pts
				(xy 106.934 -147.193) (xy 106.68 -147.447) (xy 106.68 -149.098) (xy 106.934 -149.352) (xy 109.093 -149.352)
				(xy 109.601 -149.86) (xy 109.601 -152.4) (xy 117.348 -160.147) (xy 125.857 -160.147) (xy 125.984 -160.02)
				(xy 125.984 -158.242) (xy 125.857 -158.115) (xy 119.888 -158.115) (xy 119.253 -157.48) (xy 117.602 -157.48)
				(xy 113.284 -153.162) (xy 113.284 -149.606) (xy 112.141 -148.463) (xy 112.141 -147.447) (xy 111.887 -147.193)
			)
		)
		(polygon
			(pts
				(xy 119.4054 -159.1564) (xy 119.2022 -159.1564) (xy 119.2022 -159.3596) (xy 119.4054 -159.3596)
			)
		)
		(polygon
			(pts
				(xy 118.5418 -159.1564) (xy 118.3386 -159.1564) (xy 118.3386 -159.3596) (xy 118.5418 -159.3596)
			)
		)
	)
	(zone
		(layer "F.Cu")
		(hatch none 0.5)
		(connect_pads
			(clearance 0)
		)
		(min_thickness 0.25)
		(keepout
			(tracks allowed)
			(vias allowed)
			(pads allowed)
			(copperpour allowed)
			(footprints allowed)
		)
		(placement
			(enabled no)
			(sheetname "")
		)
		(fill
			(thermal_gap 0.5)
			(thermal_bridge_width 0.5)
			(island_removal_mode 0)
		)
		(polygon
			(pts
				(xy 27.552396 -379.095) (xy 27.552396 -378.1044) (xy 27.552396 -377.19) (xy 28.771596 -377.19) (xy 28.771596 -379.095)
				(xy 28.339796 -379.095)
			)
		)
	)
	(zone
		(net "P12V_B")
		(layer "F.Cu")
		(hatch none 0.5)
		(connect_pads
			(clearance 0.5)
		)
		(min_thickness 0.25)
		(fill yes
			(thermal_gap 0.5)
			(thermal_bridge_width 0.5)
			(island_removal_mode 0)
		)
		(polygon
			(pts
				(xy 44.0182 -140.081) (xy 43.688 -140.4112) (xy 43.688 -144.018) (xy 43.942 -144.272) (xy 47.244 -144.272)
				(xy 47.498 -144.018) (xy 47.498 -141.732) (xy 46.863 -141.097) (xy 46.482 -141.097) (xy 46.228 -140.843)
				(xy 46.228 -140.208) (xy 46.101 -140.081)
			)
		)
		(polygon
			(pts
				(xy 45.6946 -140.6652) (xy 45.4914 -140.6652) (xy 45.4914 -140.8684) (xy 45.6946 -140.8684)
			)
		)
	)
	(zone
		(net "P12V_B")
		(layer "F.Cu")
		(hatch none 0.5)
		(connect_pads
			(clearance 0.5)
		)
		(min_thickness 0.25)
		(fill yes
			(thermal_gap 0.5)
			(thermal_bridge_width 0.5)
			(island_removal_mode 0)
		)
		(polygon
			(pts
				(xy 108.839 -140.081) (xy 107.823 -141.097) (xy 107.188 -141.097) (xy 106.807 -141.478) (xy 106.807 -144.018)
				(xy 107.061 -144.272) (xy 110.363 -144.272) (xy 110.617 -144.018) (xy 110.617 -141.732) (xy 109.982 -141.097)
				(xy 109.601 -141.097) (xy 109.347 -140.843) (xy 109.347 -140.208) (xy 109.22 -140.081)
			)
		)
		(polygon
			(pts
				(xy 108.8136 -140.6652) (xy 108.6104 -140.6652) (xy 108.6104 -140.8684) (xy 108.8136 -140.8684)
			)
		)
	)
	(zone
		(net "P12V_HDD27")
		(layer "F.Cu")
		(hatch none 0.5)
		(connect_pads
			(clearance 0.5)
		)
		(min_thickness 0.25)
		(fill yes
			(thermal_gap 0.5)
			(thermal_bridge_width 0.5)
			(island_removal_mode 0)
		)
		(polygon
			(pts
				(xy 107.6452 -15.9766) (xy 107.315 -16.3068) (xy 107.315 -18.796) (xy 107.569 -19.05) (xy 112.268 -19.05)
				(xy 112.522 -18.796) (xy 112.522 -16.2052) (xy 112.2934 -15.9766)
			)
		)
	)
	(zone
		(net "P12V_HDD13")
		(layer "F.Cu")
		(hatch none 0.5)
		(connect_pads
			(clearance 0.5)
		)
		(min_thickness 0.25)
		(fill yes
			(thermal_gap 0.5)
			(thermal_bridge_width 0.5)
			(island_removal_mode 0)
		)
		(polygon
			(pts
				(xy 43.815 -147.193) (xy 43.561 -147.447) (xy 43.561 -149.098) (xy 43.815 -149.352) (xy 45.974 -149.352)
				(xy 46.482 -149.86) (xy 46.482 -152.4) (xy 54.229 -160.147) (xy 62.738 -160.147) (xy 62.865 -160.02)
				(xy 62.865 -158.242) (xy 62.738 -158.115) (xy 56.769 -158.115) (xy 56.134 -157.48) (xy 54.483 -157.48)
				(xy 50.165 -153.162) (xy 50.165 -149.606) (xy 49.022 -148.463) (xy 49.022 -147.447) (xy 48.768 -147.193)
			)
		)
		(polygon
			(pts
				(xy 56.2864 -159.1564) (xy 56.0832 -159.1564) (xy 56.0832 -159.3596) (xy 56.2864 -159.3596)
			)
		)
		(polygon
			(pts
				(xy 55.4228 -159.1564) (xy 55.2196 -159.1564) (xy 55.2196 -159.3596) (xy 55.4228 -159.3596)
			)
		)
	)
	(zone
		(net "12V_PRE_5")
		(layer "F.Cu")
		(hatch none 0.5)
		(connect_pads
			(clearance 0.5)
		)
		(min_thickness 0.25)
		(fill yes
			(thermal_gap 0.5)
			(thermal_bridge_width 0.5)
			(island_removal_mode 0)
		)
		(polygon
			(pts
				(xy 177.419 -264.795) (xy 177.292 -264.922) (xy 177.292 -266.446) (xy 178.689 -267.843) (xy 180.086 -267.843)
				(xy 185.039 -272.796) (xy 188.976 -272.796) (xy 189.103 -272.669) (xy 189.103 -271.907) (xy 188.976 -271.78)
				(xy 185.674 -271.78) (xy 178.689 -264.795)
			)
		)
	)
	(zone
		(layer "F.Cu")
		(hatch none 0.5)
		(connect_pads
			(clearance 0)
		)
		(min_thickness 0.25)
		(keepout
			(tracks allowed)
			(vias allowed)
			(pads allowed)
			(copperpour allowed)
			(footprints not_allowed)
		)
		(placement
			(enabled no)
			(sheetname "")
		)
		(fill
			(thermal_gap 0.5)
			(thermal_bridge_width 0.5)
			(island_removal_mode 0)
		)
		(polygon
			(pts
				(arc
					(start 346.050108 -13.999972)
					(mid 341.300054 -18.750026)
					(end 336.55 -13.999972)
				)
				(arc
					(start 336.55 -13.999972)
					(mid 341.300054 -9.249918)
					(end 346.050108 -13.999972)
				)
			)
		)
	)
	(zone
		(net "5V_PRE_34")
		(layer "F.Cu")
		(hatch none 0.5)
		(connect_pads
			(clearance 0.5)
		)
		(min_thickness 0.25)
		(fill yes
			(thermal_gap 0.5)
			(thermal_bridge_width 0.5)
			(island_removal_mode 0)
		)
		(polygon
			(pts
				(xy 455.549 -30.988) (xy 455.295 -31.242) (xy 455.295 -33.782) (xy 454.914 -34.163) (xy 452.374 -34.163)
				(xy 452.12 -34.417) (xy 452.12 -34.798) (xy 452.374 -35.052) (xy 455.676 -35.052) (xy 456.946 -33.782)
				(xy 456.946 -31.242) (xy 456.692 -30.988)
			)
		)
	)
	(zone
		(net "P5V_B_1")
		(layer "F.Cu")
		(hatch none 0.5)
		(connect_pads
			(clearance 0.5)
		)
		(min_thickness 0.25)
		(fill yes
			(thermal_gap 0.5)
			(thermal_bridge_width 0.5)
			(island_removal_mode 0)
		)
		(polygon
			(pts
				(xy 176.149 -251.841) (xy 175.895 -252.095) (xy 175.895 -254.381) (xy 176.149 -254.635) (xy 180.848 -254.635)
				(xy 181.102 -254.381) (xy 181.102 -252.095) (xy 180.848 -251.841)
			)
		)
	)
	(zone
		(layer "F.Cu")
		(hatch none 0.5)
		(connect_pads
			(clearance 0)
		)
		(min_thickness 0.25)
		(keepout
			(tracks allowed)
			(vias allowed)
			(pads allowed)
			(copperpour allowed)
			(footprints not_allowed)
		)
		(placement
			(enabled no)
			(sheetname "")
		)
		(fill
			(thermal_gap 0.5)
			(thermal_bridge_width 0.5)
			(island_removal_mode 0)
		)
		(polygon
			(pts
				(arc
					(start 399.64995 -23.999952)
					(mid 404.400004 -19.249898)
					(end 409.150058 -23.999952)
				)
				(arc
					(start 409.150058 -23.999952)
					(mid 404.400004 -28.750006)
					(end 399.64995 -23.999952)
				)
			)
		)
	)
	(zone
		(net "GND")
		(layer "F.Cu")
		(hatch none 0.5)
		(connect_pads
			(clearance 0.5)
		)
		(min_thickness 0.25)
		(fill yes
			(thermal_gap 0.5)
			(thermal_bridge_width 0.5)
			(island_removal_mode 0)
		)
		(polygon
			(pts
				(xy 281.2796 -340.5632) (xy 281.2796 -342.4174) (xy 281.1526 -342.5444) (xy 280.7462 -342.5444)
				(xy 280.2382 -343.0524) (xy 280.2382 -344.3478) (xy 280.3652 -344.4748) (xy 282.1686 -344.4748)
				(xy 282.2702 -344.3732) (xy 282.2702 -342.773) (xy 281.8638 -342.3666) (xy 281.8638 -340.614) (xy 281.813 -340.5632)
			)
		)
		(polygon
			(pts
				(xy 281.4066 -343.3826) (xy 281.2034 -343.3826) (xy 281.2034 -343.5858) (xy 281.4066 -343.5858)
			)
		)
	)
	(zone
		(layer "F.Cu")
		(hatch none 0.5)
		(connect_pads
			(clearance 0)
		)
		(min_thickness 0.25)
		(keepout
			(tracks allowed)
			(vias allowed)
			(pads allowed)
			(copperpour allowed)
			(footprints not_allowed)
		)
		(placement
			(enabled no)
			(sheetname "")
		)
		(fill
			(thermal_gap 0.5)
			(thermal_bridge_width 0.5)
			(island_removal_mode 0)
		)
		(polygon
			(pts
				(arc
					(start 45.39996 -30.999938)
					(mid 44.000166 -32.399732)
					(end 42.600118 -30.999938)
				)
				(arc
					(start 42.600118 -30.999938)
					(mid 44.000166 -29.59989)
					(end 45.39996 -30.999938)
				)
			)
		)
	)
	(zone
		(layer "F.Cu")
		(hatch none 0.5)
		(connect_pads
			(clearance 0)
		)
		(min_thickness 0.25)
		(keepout
			(tracks allowed)
			(vias allowed)
			(pads allowed)
			(copperpour allowed)
			(footprints not_allowed)
		)
		(placement
			(enabled no)
			(sheetname "")
		)
		(fill
			(thermal_gap 0.5)
			(thermal_bridge_width 0.5)
			(island_removal_mode 0)
		)
		(polygon
			(pts
				(xy 209.609944 -140.599922) (xy 201.989944 -140.599922) (xy 201.989944 -149.969982) (xy 209.609944 -149.969982)
			)
		)
	)
	(zone
		(net "P5V_B_1")
		(layer "F.Cu")
		(hatch none 0.5)
		(connect_pads
			(clearance 0.5)
		)
		(min_thickness 0.25)
		(fill yes
			(thermal_gap 0.5)
			(thermal_bridge_width 0.5)
			(island_removal_mode 0)
		)
		(polygon
			(pts
				(xy 18.415 -136.779) (xy 18.161 -137.033) (xy 18.161 -139.319) (xy 18.415 -139.573) (xy 23.114 -139.573)
				(xy 23.368 -139.319) (xy 23.368 -137.033) (xy 23.114 -136.779)
			)
		)
	)
	(zone
		(net "5V_PRE_10")
		(layer "F.Cu")
		(hatch none 0.5)
		(connect_pads
			(clearance 0.5)
		)
		(min_thickness 0.25)
		(fill yes
			(thermal_gap 0.5)
			(thermal_bridge_width 0.5)
			(island_removal_mode 0)
		)
		(polygon
			(pts
				(xy 455.549 -260.985) (xy 455.295 -261.239) (xy 455.295 -263.779) (xy 454.914 -264.16) (xy 452.374 -264.16)
				(xy 452.12 -264.414) (xy 452.12 -264.795) (xy 452.374 -265.049) (xy 455.676 -265.049) (xy 456.946 -263.779)
				(xy 456.946 -261.239) (xy 456.692 -260.985)
			)
		)
	)
	(zone
		(layer "F.Cu")
		(hatch none 0.5)
		(connect_pads
			(clearance 0)
		)
		(min_thickness 0.25)
		(keepout
			(tracks allowed)
			(vias allowed)
			(pads allowed)
			(copperpour allowed)
			(footprints allowed)
		)
		(placement
			(enabled no)
			(sheetname "")
		)
		(fill
			(thermal_gap 0.5)
			(thermal_bridge_width 0.5)
			(island_removal_mode 0)
		)
		(polygon
			(pts
				(xy 192.863978 -373.093742) (xy 191.873378 -373.093742) (xy 190.958978 -373.093742) (xy 190.958978 -371.874542)
				(xy 192.863978 -371.874542) (xy 192.863978 -372.306342)
			)
		)
	)
	(zone
		(net "P5V_HDD11")
		(layer "F.Cu")
		(hatch none 0.5)
		(connect_pads
			(clearance 0.5)
		)
		(min_thickness 0.25)
		(fill yes
			(thermal_gap 0.5)
			(thermal_bridge_width 0.5)
			(island_removal_mode 0)
		)
		(polygon
			(pts
				(xy 474.726 -257.683) (xy 474.472 -257.937) (xy 474.472 -260.223) (xy 474.726 -260.477) (xy 474.726 -262.509)
				(xy 475.488 -263.271) (xy 475.488 -264.235946) (xy 475.666054 -264.414) (xy 476.25 -264.414) (xy 479.425 -267.589)
				(xy 486.283 -267.589) (xy 486.41 -267.462) (xy 486.41 -265.684) (xy 486.283 -265.557) (xy 481.203 -265.557)
				(xy 479.298 -263.652) (xy 478.409 -263.652) (xy 477.52 -262.763) (xy 477.52 -260.223) (xy 478.155 -259.588)
				(xy 478.155 -257.937) (xy 477.901 -257.683)
			)
		)
		(polygon
			(pts
				(xy 476.5294 -264.1092) (xy 476.3262 -264.1092) (xy 476.3262 -264.3124) (xy 476.5294 -264.3124)
			)
		)
		(polygon
			(pts
				(xy 476.5294 -263.2456) (xy 476.3262 -263.2456) (xy 476.3262 -263.4488) (xy 476.5294 -263.4488)
			)
		)
	)
	(zone
		(net "12V_PRE_20")
		(layer "F.Cu")
		(hatch none 0.5)
		(connect_pads
			(clearance 0.5)
		)
		(min_thickness 0.25)
		(fill yes
			(thermal_gap 0.5)
			(thermal_bridge_width 0.5)
			(island_removal_mode 0)
		)
		(polygon
			(pts
				(xy 394.128498 -154.686) (xy 392.198098 -156.6164) (xy 389.200898 -156.6164) (xy 388.946898 -156.8704)
				(xy 388.946898 -157.5816) (xy 389.086598 -157.7213) (xy 391.372598 -157.7213) (xy 391.385298 -157.734)
				(xy 395.068298 -157.734) (xy 396.084298 -156.718) (xy 396.084298 -154.813) (xy 395.957298 -154.686)
			)
		)
	)
	(zone
		(net "5V_PRE_3")
		(layer "F.Cu")
		(hatch none 0.5)
		(connect_pads
			(clearance 0.5)
		)
		(min_thickness 0.25)
		(fill yes
			(thermal_gap 0.5)
			(thermal_bridge_width 0.5)
			(island_removal_mode 0)
		)
		(polygon
			(pts
				(xy 117.60835 -260.962648) (xy 117.45595 -261.115048) (xy 117.45595 -262.512048) (xy 118.04015 -263.096248)
				(xy 119.31015 -263.096248) (xy 121.39295 -265.179048) (xy 125.83795 -265.179048) (xy 125.96495 -265.052048)
				(xy 125.96495 -264.290048) (xy 125.83795 -264.163048) (xy 122.81535 -264.163048) (xy 119.61495 -260.962648)
			)
		)
	)
	(zone
		(net "5V_PRE_24")
		(layer "F.Cu")
		(hatch none 0.5)
		(connect_pads
			(clearance 0.5)
		)
		(min_thickness 0.25)
		(fill yes
			(thermal_gap 0.5)
			(thermal_bridge_width 0.5)
			(island_removal_mode 0)
		)
		(polygon
			(pts
				(xy 23.0124 -30.9372) (xy 22.86 -31.0896) (xy 22.86 -32.512) (xy 23.3934 -33.0454) (xy 24.6634 -33.0454)
				(xy 26.797 -35.179) (xy 31.242 -35.179) (xy 31.369 -35.052) (xy 31.369 -34.29) (xy 31.242 -34.163)
				(xy 28.1178 -34.163) (xy 24.892 -30.9372)
			)
		)
	)
	(zone
		(net "P12V_B")
		(layer "F.Cu")
		(hatch none 0.5)
		(connect_pads
			(clearance 0.5)
		)
		(min_thickness 0.25)
		(fill yes
			(thermal_gap 0.5)
			(thermal_bridge_width 0.5)
			(island_removal_mode 0)
		)
		(polygon
			(pts
				(xy 260.866128 -332.47965) (xy 260.329172 -333.016606) (xy 260.329172 -336.217006) (xy 260.405372 -336.293206)
				(xy 262.990076 -336.293206) (xy 263.13384 -336.149442) (xy 268.237208 -336.149442) (xy 268.54531 -336.457544)
				(xy 268.54531 -338.23529) (xy 268.156182 -338.624418) (xy 260.543548 -338.624418) (xy 260.329172 -338.838794)
				(xy 260.329172 -343.337134) (xy 260.425184 -343.433146) (xy 263.116568 -343.433146) (xy 263.34339 -343.206324)
				(xy 268.245082 -343.206324) (xy 268.54531 -343.506552) (xy 268.54531 -345.156282) (xy 268.019276 -345.682316)
				(xy 260.483096 -345.682316) (xy 260.329172 -345.83624) (xy 260.329172 -350.47682) (xy 260.413246 -350.560894)
				(xy 262.882888 -350.560894) (xy 263.184894 -350.258888) (xy 267.711428 -350.258888) (xy 267.71219 -350.25965)
				(xy 268.121384 -350.25965) (xy 269.013178 -351.151444) (xy 269.963646 -351.151444) (xy 272.185638 -348.929452)
				(xy 272.185638 -334.281272) (xy 270.384016 -332.47965)
			)
		)
		(polygon
			(pts
				(xy 269.650972 -350.491806) (xy 269.447772 -350.491806) (xy 269.447772 -350.695006) (xy 269.650972 -350.695006)
			)
		)
		(polygon
			(pts
				(xy 269.092172 -350.491806) (xy 268.888972 -350.491806) (xy 268.888972 -350.695006) (xy 269.092172 -350.695006)
			)
		)
	)
	(zone
		(layer "F.Cu")
		(hatch none 0.5)
		(connect_pads
			(clearance 0)
		)
		(min_thickness 0.25)
		(keepout
			(tracks not_allowed)
			(vias allowed)
			(pads allowed)
			(copperpour not_allowed)
			(footprints allowed)
		)
		(placement
			(enabled no)
			(sheetname "")
		)
		(fill
			(thermal_gap 0.5)
			(thermal_bridge_width 0.5)
			(island_removal_mode 0)
		)
		(polygon
			(pts
				(arc
					(start 141.824964 -181.799992)
					(mid 127.824992 -195.799964)
					(end 113.82502 -181.799992)
				)
				(arc
					(start 113.82502 -181.799992)
					(mid 127.824992 -167.80002)
					(end 141.824964 -181.799992)
				)
			)
		)
	)
	(zone
		(layer "F.Cu")
		(hatch none 0.5)
		(connect_pads
			(clearance 0)
		)
		(min_thickness 0.25)
		(keepout
			(tracks allowed)
			(vias allowed)
			(pads allowed)
			(copperpour allowed)
			(footprints not_allowed)
		)
		(placement
			(enabled no)
			(sheetname "")
		)
		(fill
			(thermal_gap 0.5)
			(thermal_bridge_width 0.5)
			(island_removal_mode 0)
		)
		(polygon
			(pts
				(arc
					(start 165.450012 -13.999972)
					(mid 170.200066 -9.249918)
					(end 174.95012 -13.999972)
				)
				(arc
					(start 174.95012 -13.999972)
					(mid 170.200066 -18.750026)
					(end 165.450012 -13.999972)
				)
			)
		)
	)
	(zone
		(net "5V_PRE_5")
		(layer "F.Cu")
		(hatch none 0.5)
		(connect_pads
			(clearance 0.5)
		)
		(min_thickness 0.25)
		(fill yes
			(thermal_gap 0.5)
			(thermal_bridge_width 0.5)
			(island_removal_mode 0)
		)
		(polygon
			(pts
				(xy 180.708554 -260.962648) (xy 180.556154 -261.115048) (xy 180.556154 -262.512048) (xy 181.140354 -263.096248)
				(xy 182.410354 -263.096248) (xy 184.493154 -265.179048) (xy 188.938154 -265.179048) (xy 189.065154 -265.052048)
				(xy 189.065154 -264.290048) (xy 188.938154 -264.163048) (xy 185.915554 -264.163048) (xy 182.715154 -260.962648)
			)
		)
	)
	(zone
		(net "P5V_B_1")
		(layer "F.Cu")
		(hatch none 0.5)
		(connect_pads
			(clearance 0.5)
		)
		(min_thickness 0.25)
		(fill yes
			(thermal_gap 0.5)
			(thermal_bridge_width 0.5)
			(island_removal_mode 0)
		)
		(polygon
			(pts
				(xy 144.653 -251.841) (xy 144.399 -252.095) (xy 144.399 -254.381) (xy 144.653 -254.635) (xy 149.352 -254.635)
				(xy 149.606 -254.381) (xy 149.606 -252.095) (xy 149.352 -251.841)
			)
		)
	)
	(zone
		(layer "F.Cu")
		(hatch none 0.5)
		(connect_pads
			(clearance 0)
		)
		(min_thickness 0.25)
		(keepout
			(tracks allowed)
			(vias allowed)
			(pads allowed)
			(copperpour allowed)
			(footprints not_allowed)
		)
		(placement
			(enabled no)
			(sheetname "")
		)
		(fill
			(thermal_gap 0.5)
			(thermal_bridge_width 0.5)
			(island_removal_mode 0)
		)
		(polygon
			(pts
				(xy 298.200064 -276.800056) (xy 298.200064 -326.799956) (xy 491.450122 -326.799956) (xy 491.450122 -276.800056)
				(xy 478.00006 -276.800056) (xy 478.00006 -266.800076) (xy 463.449924 -266.800076) (xy 463.449924 -276.800056)
				(xy 446.449958 -276.800056) (xy 446.449958 -266.800076) (xy 431.900076 -266.800076) (xy 431.900076 -276.800056)
				(xy 414.90011 -276.800056) (xy 414.90011 -266.800076) (xy 400.349974 -266.800076) (xy 400.349974 -276.800056)
				(xy 383.350008 -276.800056) (xy 383.350008 -266.800076) (xy 368.800126 -266.800076) (xy 368.800126 -276.800056)
				(xy 351.799906 -276.800056) (xy 351.799906 -266.800076) (xy 337.250024 -266.800076) (xy 337.250024 -276.800056)
				(xy 320.250058 -276.800056) (xy 320.250058 -266.800076) (xy 305.699922 -266.800076) (xy 305.699922 -276.800056)
			)
		)
	)
	(zone
		(net "GPIO_VCC_U8")
		(layer "F.Cu")
		(hatch none 0.5)
		(connect_pads
			(clearance 0.5)
		)
		(min_thickness 0.25)
		(fill yes
			(thermal_gap 0.5)
			(thermal_bridge_width 0.5)
			(island_removal_mode 0)
		)
		(polygon
			(pts
				(xy 235.413804 -220.345) (xy 233.0196 -222.739204)
				(arc
					(start 233.0196 -223.612456)
					(mid 232.980135 -223.82517)
					(end 232.8672 -224.009712)
				)
				(xy 232.8672 -224.3328) (xy 232.9434 -224.409) (xy 236.307376 -224.409) (xy 236.671612 -224.044764)
				(xy 236.671612 -220.445584) (xy 236.571028 -220.345)
			)
		)
		(polygon
			(pts
				(xy 236.4232 -223.8502) (xy 236.22 -223.8502) (xy 236.22 -224.0534) (xy 236.4232 -224.0534)
			)
		)
		(polygon
			(pts
				(xy 235.5596 -223.8502) (xy 235.3564 -223.8502) (xy 235.3564 -224.0534) (xy 235.5596 -224.0534)
			)
		)
		(polygon
			(pts
				(xy 235.1024 -223.5454) (xy 234.8992 -223.5454) (xy 234.8992 -223.7486) (xy 235.1024 -223.7486)
			)
		)
		(polygon
			(pts
				(xy 234.4928 -223.5454) (xy 234.2896 -223.5454) (xy 234.2896 -223.7486) (xy 234.4928 -223.7486)
			)
		)
		(polygon
			(pts
				(xy 236.4232 -222.9866) (xy 236.22 -222.9866) (xy 236.22 -223.1898) (xy 236.4232 -223.1898)
			)
		)
		(polygon
			(pts
				(xy 235.5596 -222.9866) (xy 235.3564 -222.9866) (xy 235.3564 -223.1898) (xy 235.5596 -223.1898)
			)
		)
		(polygon
			(pts
				(xy 236.1184 -222.5548) (xy 235.9152 -222.5548) (xy 235.9152 -222.758) (xy 236.1184 -222.758)
			)
		)
		(polygon
			(pts
				(xy 236.1184 -221.996) (xy 235.9152 -221.996) (xy 235.9152 -222.1992) (xy 236.1184 -222.1992)
			)
		)
	)
	(zone
		(layer "F.Cu")
		(hatch none 0.5)
		(connect_pads
			(clearance 0)
		)
		(min_thickness 0.25)
		(keepout
			(tracks allowed)
			(vias allowed)
			(pads allowed)
			(copperpour allowed)
			(footprints allowed)
		)
		(placement
			(enabled no)
			(sheetname "")
		)
		(fill
			(thermal_gap 0.5)
			(thermal_bridge_width 0.5)
			(island_removal_mode 0)
		)
		(polygon
			(pts
				(xy 28.492196 -369.1255) (xy 28.492196 -368.1349) (xy 28.492196 -367.2205) (xy 29.711396 -367.2205)
				(xy 29.711396 -369.1255) (xy 29.279596 -369.1255)
			)
		)
	)
	(zone
		(net "12V_PRE_29")
		(layer "F.Cu")
		(hatch none 0.5)
		(connect_pads
			(clearance 0.5)
		)
		(min_thickness 0.25)
		(fill yes
			(thermal_gap 0.5)
			(thermal_bridge_width 0.5)
			(island_removal_mode 0)
		)
		(polygon
			(pts
				(xy 177.419 -34.798) (xy 177.292 -34.925) (xy 177.292 -38.2524) (xy 179.3494 -40.3098) (xy 182.5498 -40.3098)
				(xy 185.039 -42.799) (xy 188.976 -42.799) (xy 189.103 -42.672) (xy 189.103 -41.91) (xy 188.976 -41.783)
				(xy 185.674 -41.783) (xy 183.1467 -39.2557) (xy 180.0479 -39.2557) (xy 179.1716 -38.3794) (xy 179.1716 -35.2806)
				(xy 178.689 -34.798)
			)
		)
	)
	(zone
		(layer "F.Cu")
		(hatch none 0.5)
		(connect_pads
			(clearance 0)
		)
		(min_thickness 0.25)
		(keepout
			(tracks allowed)
			(vias allowed)
			(pads allowed)
			(copperpour allowed)
			(footprints not_allowed)
		)
		(placement
			(enabled no)
			(sheetname "")
		)
		(fill
			(thermal_gap 0.5)
			(thermal_bridge_width 0.5)
			(island_removal_mode 0)
		)
		(polygon
			(pts
				(xy 291.599874 -48.200056) (xy 298.200064 -48.200056) (xy 298.200064 -84.000086) (xy 291.599874 -84.000086)
			)
		)
	)
	(zone
		(net "12V_PRE_10")
		(layer "F.Cu")
		(hatch none 0.5)
		(connect_pads
			(clearance 0.5)
		)
		(min_thickness 0.25)
		(fill yes
			(thermal_gap 0.5)
			(thermal_bridge_width 0.5)
			(island_removal_mode 0)
		)
		(polygon
			(pts
				(xy 457.228448 -269.686024) (xy 455.298048 -271.616424) (xy 452.300848 -271.616424) (xy 452.046848 -271.870424)
				(xy 452.046848 -272.581624) (xy 452.186548 -272.721324) (xy 454.472548 -272.721324) (xy 454.485248 -272.734024)
				(xy 458.168248 -272.734024) (xy 459.184248 -271.718024) (xy 459.184248 -269.813024) (xy 459.057248 -269.686024)
			)
		)
	)
	(zone
		(layer "F.Cu")
		(hatch none 0.5)
		(connect_pads
			(clearance 0)
		)
		(min_thickness 0.25)
		(keepout
			(tracks allowed)
			(vias allowed)
			(pads allowed)
			(copperpour allowed)
			(footprints not_allowed)
		)
		(placement
			(enabled no)
			(sheetname "")
		)
		(fill
			(thermal_gap 0.5)
			(thermal_bridge_width 0.5)
			(island_removal_mode 0)
		)
		(polygon
			(pts
				(arc
					(start 449.674996 -293.800022)
					(mid 456.674982 -286.800036)
					(end 463.674968 -293.800022)
				)
				(arc
					(start 463.674968 -299.80001)
					(mid 456.674982 -306.799996)
					(end 449.674996 -299.80001)
				)
			)
		)
	)
	(zone
		(net "GND")
		(layer "F.Cu")
		(hatch none 0.5)
		(connect_pads
			(clearance 0.5)
		)
		(min_thickness 0.25)
		(fill yes
			(thermal_gap 0.5)
			(thermal_bridge_width 0.5)
			(island_removal_mode 0)
		)
		(polygon
			(pts
				(xy 36.914074 -20.81657)
				(arc
					(start 36.48583 -21.244814)
					(mid 35.959015 -22.551669)
					(end 35.01771 -23.600156)
				)
				(arc
					(start 35.01771 -26.482548)
					(mid 35.496889 -26.723003)
					(end 35.940492 -27.024076)
				)
				(xy 36.526724 -27.024076)
				(arc
					(start 36.526724 -27.582368)
					(mid 36.630349 -27.70761)
					(end 36.728908 -27.836876)
				)
				(xy 38.857174 -27.836876) (xy 39.431976 -27.262074) (xy 39.431976 -22.95271) (xy 37.295836 -20.81657)
			)
		)
	)
	(zone
		(layer "F.Cu")
		(hatch none 0.5)
		(connect_pads
			(clearance 0)
		)
		(min_thickness 0.25)
		(keepout
			(tracks allowed)
			(vias allowed)
			(pads allowed)
			(copperpour allowed)
			(footprints allowed)
		)
		(placement
			(enabled no)
			(sheetname "")
		)
		(fill
			(thermal_gap 0.5)
			(thermal_bridge_width 0.5)
			(island_removal_mode 0)
		)
		(polygon
			(pts
				(xy 282.659582 -329.278234) (xy 282.659582 -327.652634) (xy 285.174182 -327.652634) (xy 285.174182 -329.278234)
			)
		)
	)
	(zone
		(net "GND")
		(layer "F.Cu")
		(hatch none 0.5)
		(connect_pads
			(clearance 0.5)
		)
		(min_thickness 0.25)
		(fill yes
			(thermal_gap 0.5)
			(thermal_bridge_width 0.5)
			(island_removal_mode 0)
		)
		(polygon
			(pts
				(xy 175.111918 -125.689614) (xy 172.658786 -123.236228) (xy 161.642552 -123.236228) (xy 161.21761 -123.66117)
				(arc
					(start 161.21761 -124.404374)
					(mid 163.608375 -125.800307)
					(end 164.551106 -128.40335)
				)
				(arc
					(start 164.551106 -131.57835)
					(mid 164.079583 -133.478845)
					(end 162.774376 -134.938516)
				)
				(arc
					(start 162.774376 -135.40105)
					(mid 162.36453 -137.179956)
					(end 161.21761 -138.60018)
				)
				(xy 161.21761 -141.20876)
				(arc
					(start 162.097212 -142.088362)
					(mid 163.368216 -142.32657)
					(end 164.501322 -142.949676)
				)
				(xy 165.645084 -142.949676) (xy 166.050976 -142.543784) (xy 166.050976 -138.618976) (xy 166.115746 -138.618976)
				(xy 166.115746 -138.193272) (xy 168.070276 -136.238742) (xy 168.070276 -134.663688)
				(arc
					(start 167.617394 -134.210806)
					(mid 165.212865 -128.37662)
					(end 171.39793 -127.125476)
				)
				(xy 172.058076 -127.125476) (xy 172.058076 -127.049276)
				(arc
					(start 174.435008 -127.049276)
					(mid 174.757235 -126.735758)
					(end 175.111918 -126.459488)
				)
			)
		)
	)
	(zone
		(layer "F.Cu")
		(hatch none 0.5)
		(connect_pads
			(clearance 0)
		)
		(min_thickness 0.25)
		(keepout
			(tracks not_allowed)
			(vias allowed)
			(pads allowed)
			(copperpour not_allowed)
			(footprints allowed)
		)
		(placement
			(enabled no)
			(sheetname "")
		)
		(fill
			(thermal_gap 0.5)
			(thermal_bridge_width 0.5)
			(island_removal_mode 0)
		)
		(polygon
			(pts
				(arc
					(start 134.999984 -331.399896)
					(mid 138.999976 -335.399888)
					(end 134.999984 -339.39988)
				)
				(arc
					(start 129.919984 -339.39988)
					(mid 125.919992 -335.399888)
					(end 129.919984 -331.399896)
				)
			)
		)
	)
	(zone
		(layer "F.Cu")
		(hatch none 0.5)
		(connect_pads
			(clearance 0)
		)
		(min_thickness 0.25)
		(keepout
			(tracks not_allowed)
			(vias allowed)
			(pads allowed)
			(copperpour not_allowed)
			(footprints allowed)
		)
		(placement
			(enabled no)
			(sheetname "")
		)
		(fill
			(thermal_gap 0.5)
			(thermal_bridge_width 0.5)
			(island_removal_mode 0)
		)
		(polygon
			(pts
				(arc
					(start 354.231956 -16.95196)
					(mid 353.746562 -17.436973)
					(end 354.231702 -17.92224)
				)
				(xy 354.644452 -17.92224)
				(arc
					(start 354.644452 -17.611852)
					(mid 354.615587 -17.542165)
					(end 354.5459 -17.5133)
				)
				(arc
					(start 354.487226 -17.5133)
					(mid 353.965058 -17.4371)
					(end 354.487226 -17.3609)
				)
				(xy 354.577396 -17.3609)
				(arc
					(start 354.579682 -17.363186)
					(mid 354.723349 -17.434403)
					(end 354.794566 -17.57807)
				)
				(xy 354.796852 -17.580356) (xy 354.796852 -17.92224) (xy 354.936552 -17.92224) (xy 354.936552 -17.580356)
				(arc
					(start 354.938838 -17.57807)
					(mid 355.010055 -17.434403)
					(end 355.153722 -17.363186)
				)
				(xy 355.156008 -17.3609)
				(arc
					(start 355.246178 -17.3609)
					(mid 355.768346 -17.4371)
					(end 355.246178 -17.5133)
				)
				(arc
					(start 355.187504 -17.5133)
					(mid 355.117817 -17.542165)
					(end 355.088952 -17.611852)
				)
				(xy 355.088952 -17.92224)
				(arc
					(start 355.501702 -17.92224)
					(mid 355.986842 -17.4371)
					(end 355.501702 -16.95196)
				)
			)
		)
	)
	(zone
		(net "EMITTER_K")
		(layer "F.Cu")
		(hatch none 0.5)
		(connect_pads
			(clearance 0.5)
		)
		(min_thickness 0.25)
		(fill yes
			(thermal_gap 0.5)
			(thermal_bridge_width 0.5)
			(island_removal_mode 0)
		)
		(polygon
			(pts
				(xy 277.813516 -378.243592) (xy 277.612094 -378.445014) (xy 277.612094 -381.205232) (xy 277.901654 -381.494792)
				(xy 284.346142 -381.494792) (xy 284.600142 -381.240792) (xy 284.600142 -378.421392) (xy 284.422342 -378.243592)
			)
		)
	)
	(zone
		(net "GND")
		(layer "F.Cu")
		(hatch none 0.5)
		(connect_pads
			(clearance 0.5)
		)
		(min_thickness 0.25)
		(fill yes
			(thermal_gap 0.5)
			(thermal_bridge_width 0.5)
			(island_removal_mode 0)
		)
		(polygon
			(pts
				(xy 224.028508 -364.268512) (xy 210.329272 -377.968002)
				(arc
					(start 199.00011 -377.968002)
					(mid 196.856164 -378.856054)
					(end 195.968112 -381)
				)
				(xy 195.968112 -383.96799) (xy 184.381902 -383.96799)
				(arc
					(start 184.381902 -383.299716)
					(mid 183.748489 -381.4453)
					(end 182.113174 -380.365508)
				)
				(arc
					(start 182.113174 -380.365508)
					(mid 181.735023 -380.292488)
					(end 181.350666 -380.267972)
				)
				(arc
					(start 174.849282 -380.267972)
					(mid 174.464922 -380.292465)
					(end 174.086774 -380.365508)
				)
				(arc
					(start 174.086774 -380.365508)
					(mid 172.451376 -381.445235)
					(end 171.818046 -383.299716)
				)
				(xy 171.818046 -383.96799) (xy 128.331976 -383.96799)
				(arc
					(start 128.331976 -381)
					(mid 127.443924 -378.856054)
					(end 125.299978 -377.968002)
				)
				(arc
					(start 73.300082 -377.968002)
					(mid 71.156136 -378.856054)
					(end 70.268084 -381)
				)
				(xy 70.268084 -383.96799) (xy 26.782014 -383.96799)
				(arc
					(start 26.782014 -383.299716)
					(mid 26.148601 -381.4453)
					(end 24.513286 -380.365508)
				)
				(arc
					(start 24.513286 -380.365508)
					(mid 24.135135 -380.292488)
					(end 23.750778 -380.267972)
				)
				(arc
					(start 17.249648 -380.267972)
					(mid 16.86516 -380.292449)
					(end 16.486886 -380.365508)
				)
				(arc
					(start 16.486886 -380.365508)
					(mid 14.851282 -381.445278)
					(end 14.217904 -383.29997)
				)
				(xy 14.217904 -383.96799) (xy 5.031994 -383.96799) (xy 5.031994 -372.285006)
				(arc
					(start 6.048756 -371.268244)
					(mid 6.726554 -369.550018)
					(end 8.060182 -368.27206)
				)
				(arc
					(start 8.060436 -368.272314)
					(mid 9.499171 -367.715981)
					(end 11.041634 -367.700814)
				)
				(arc
					(start 12.013946 -366.728502)
					(mid 16.415591 -364.550322)
					(end 20.497546 -367.280952)
				)
				(xy 20.509484 -367.29289) (xy 22.02688 -367.29289) (xy 23.275036 -366.044734) (xy 23.275036 -365.151416)
				(arc
					(start 29.144468 -359.281984)
					(mid 29.208232 -357.564823)
					(end 29.971746 -356.02545)
				)
				(xy 29.971746 -311.3532)
				(arc
					(start 27.587956 -308.96941)
					(mid 23.85972 -305.039043)
					(end 22.503638 -299.794168)
				)
				(arc
					(start 22.503638 -293.799768)
					(mid 22.652232 -292.012595)
					(end 23.093934 -290.274502)
				)
				(xy 23.093934 -282.362402) (xy 21.149056 -280.417524) (xy 20.013676 -280.417524) (xy 20.013676 -277.878286)
				(xy 19.898614 -277.763224) (xy 19.365976 -277.763224) (xy 19.365976 -277.230586) (xy 12.329414 -270.194024)
				(xy 9.256776 -270.194024) (xy 8.316976 -269.254224) (xy 8.316976 -265.800586) (xy 8.254746 -265.738356)
				(xy 8.254746 -260.930644) (xy 8.316976 -260.868414) (xy 8.316976 -253.680976) (xy 9.662414 -253.680976)
				(xy 10.285476 -253.057914)
				(arc
					(start 10.285476 -249.131582)
					(mid 9.639527 -245.355373)
					(end 12.40155 -242.700556)
				)
				(arc
					(start 12.40155 -242.700556)
					(mid 12.473893 -242.621953)
					(end 12.548362 -242.545362)
				)
				(xy 12.571476 -242.522248) (xy 12.571476 -242.187476)
				(arc
					(start 12.906756 -242.187476)
					(mid 13.065291 -242.041892)
					(end 13.231622 -241.905282)
				)
				(arc
					(start 13.231622 -241.905282)
					(mid 15.453706 -240.878525)
					(end 17.867376 -241.28603)
				)
				(arc
					(start 17.867376 -241.28603)
					(mid 18.379953 -241.498244)
					(end 18.857214 -241.781076)
				)
				(xy 22.319996 -241.781076) (xy 23.093934 -241.007138) (xy 23.093934 -239.277652) (xy 21.99259 -238.176308)
				(xy 2.032 -238.176308) (xy 2.032 -121.402348) (xy 5.842254 -121.402348) (xy 14.443964 -112.800892)
				(xy 25.981406 -112.800892) (xy 27.024076 -111.758222)
				(arc
					(start 27.024076 -108.6866)
					(mid 28.244598 -105.739998)
					(end 31.1912 -104.519476)
				)
				(arc
					(start 32.4104 -104.519476)
					(mid 34.068351 -104.863496)
					(end 35.452558 -105.838752)
				)
				(xy 43.547792 -105.838752) (xy 43.547792 -105.802938) (xy 44.577 -104.77373)
				(arc
					(start 44.577 -103.377238)
					(mid 43.196609 -101.919792)
					(end 42.694606 -99.976178)
				)
				(arc
					(start 42.694606 -99.620578)
					(mid 42.807403 -98.675951)
					(end 43.13936 -97.784412)
				)
				(xy 43.13936 -90.160602)
				(arc
					(start 43.011852 -90.033348)
					(mid 42.158406 -88.755981)
					(end 41.858692 -87.249254)
				)
				(arc
					(start 41.858692 -85.177884)
					(mid 41.655345 -83.8962)
					(end 41.858692 -82.614516)
				)
				(xy 41.858692 -78.815692) (xy 41.319704 -78.276704)
				(arc
					(start 40.044116 -78.276704)
					(mid 34.736591 -80.522994)
					(end 29.028644 -79.726028)
				)
				(xy 28.321508 -79.726028) (xy 27.59456 -80.452976) (xy 27.59456 -101.816916) (xy 25.723342 -103.688134)
				(xy 25.723342 -104.356408) (xy 25.055068 -104.356408)
				(arc
					(start 24.216868 -105.194608)
					(mid 23.527491 -105.743135)
					(end 22.732492 -106.122724)
				)
				(xy 22.732492 -106.530394)
				(arc
					(start 20.228306 -106.530394)
					(mid 17.765268 -107.355147)
					(end 15.30223 -106.530394)
				)
				(xy 13.687044 -106.530394) (xy 13.687044 -105.253536) (xy 10.529062 -105.253536)
				(arc
					(start 10.529062 -103.478838)
					(mid 9.133083 -102.018972)
					(end 8.624824 -100.064062)
				)
				(arc
					(start 8.624824 -99.708208)
					(mid 8.737524 -98.763726)
					(end 9.069324 -97.872296)
				)
				(arc
					(start 9.069324 -94.01429)
					(mid 9.286585 -92.724432)
					(end 9.914382 -91.576906)
				)
				(arc
					(start 9.914382 -91.576906)
					(mid 10.226882 -91.037972)
					(end 10.616692 -90.552016)
				)
				(arc
					(start 10.616692 -64.845946)
					(mid 10.916383 -63.33921)
					(end 11.769852 -62.061852)
				)
				(xy 12.989052 -60.842652) (xy 13.056362 -60.776866) (xy 13.056362 -60.426346)
				(arc
					(start 13.47978 -60.426346)
					(mid 14.568734 -59.878253)
					(end 15.773146 -59.689492)
				)
				(xy 19.180048 -59.689492) (xy 19.80184 -59.0677) (xy 19.80184 -58.355484) (xy 23.093934 -55.06339)
				(arc
					(start 23.093934 -51.165252)
					(mid 22.350466 -50.862572)
					(end 21.680424 -50.420524)
				)
				(xy 20.013676 -50.420524) (xy 20.013676 -47.881286) (xy 19.898614 -47.766224) (xy 19.365976 -47.766224)
				(xy 19.365976 -47.233586) (xy 12.329414 -40.197024) (xy 9.256776 -40.197024) (xy 9.256776 -38.081204)
				(xy 9.226042 -38.038024) (xy 8.316976 -38.038024) (xy 8.316976 -35.803586) (xy 8.254746 -35.741356)
				(xy 8.254746 -30.933644) (xy 8.316976 -30.871414) (xy 8.316976 -23.683976) (xy 9.662414 -23.683976)
				(xy 10.285476 -23.060914) (xy 10.285476 -21.7297) (xy 9.663938 -21.108162)
				(arc
					(start 7.743952 -21.108162)
					(mid 6.764516 -20.988348)
					(end 5.842254 -20.6375)
				)
				(arc
					(start 5.842254 -20.6375)
					(mid 4.854711 -19.910035)
					(end 4.127246 -18.922492)
				)
				(xy 2.032 -16.827246) (xy 2.032 -2.032) (xy 14.899386 -2.032)
				(arc
					(start 16.433038 -3.565652)
					(mid 18.460837 -4.722265)
					(end 19.723862 -6.685534)
				)
				(arc
					(start 19.723862 -6.685534)
					(mid 19.957764 -8.846107)
					(end 19.234912 -10.895584)
				)
				(xy 19.234912 -11.337036)
				(arc
					(start 19.710146 -11.81227)
					(mid 19.968452 -11.828224)
					(end 20.225258 -11.860276)
				)
				(xy 22.202648 -11.860276) (xy 23.093934 -10.96899) (xy 23.093934 -2.032) (xy 65.545208 -2.032)
				(arc
					(start 65.545208 -5.842254)
					(mid 65.689352 -6.511194)
					(end 65.71996 -7.194804)
				)
				(xy 66.567558 -8.042402) (xy 66.567558 -9.015476)
				(arc
					(start 67.087496 -9.535414)
					(mid 69.123235 -11.01185)
					(end 69.901054 -13.403326)
				)
				(arc
					(start 69.901054 -16.578326)
					(mid 69.429531 -18.478821)
					(end 68.124324 -19.938492)
				)
				(arc
					(start 68.124324 -20.401026)
					(mid 67.714478 -22.179932)
					(end 66.567558 -23.600156)
				)
				(arc
					(start 66.567558 -26.715974)
					(mid 66.870163 -26.882956)
					(end 67.1576 -27.074876)
				)
				(xy 69.463412 -27.074876) (xy 70.4469 -26.091388) (xy 70.4469 -24.839422) (xy 71.435976 -23.850346)
				(xy 71.435976 -23.683976) (xy 71.602346 -23.683976) (xy 73.404476 -21.881846)
				(arc
					(start 73.404476 -19.134582)
					(mid 72.786883 -15.275215)
					(end 75.690476 -12.658852)
				)
				(xy 75.690476 -12.190476) (xy 75.792076 -12.088876)
				(arc
					(start 81.352644 -12.088876)
					(mid 82.7786 -11.835616)
					(end 84.204556 -12.088876)
				)
				(xy 85.602572 -12.088876) (xy 86.193884 -11.497564) (xy 86.193884 -2.032) (xy 97.09531 -2.032)
				(arc
					(start 97.09531 -5.842254)
					(mid 97.259129 -6.696669)
					(end 97.238566 -7.566406)
				)
				(xy 97.714562 -8.042402) (xy 98.11766 -8.042402) (xy 98.11766 -9.10209)
				(arc
					(start 98.512884 -9.497314)
					(mid 100.634631 -10.959414)
					(end 101.451156 -13.403326)
				)
				(xy 101.451156 -16.482822) (xy 101.771196 -16.802862)
				(arc
					(start 102.440994 -16.802862)
					(mid 102.931215 -16.508324)
					(end 103.439976 -16.24711)
				)
				(xy 103.439976 -7.199376) (xy 105.014014 -7.199376) (xy 107.745276 -4.468114) (xy 107.745276 -2.032)
				(xy 128.645158 -2.032)
				(arc
					(start 128.645158 -5.842254)
					(mid 128.789302 -6.511194)
					(end 128.81991 -7.194804)
				)
				(xy 129.667508 -8.042402) (xy 129.667508 -8.930132)
				(arc
					(start 130.31724 -9.579864)
					(mid 132.263065 -11.067667)
					(end 133.001004 -13.403326)
				)
				(arc
					(start 133.001004 -16.578326)
					(mid 132.529481 -18.478821)
					(end 131.224274 -19.938492)
				)
				(arc
					(start 131.224274 -20.401026)
					(mid 130.814428 -22.179932)
					(end 129.667508 -23.600156)
				)
				(arc
					(start 129.667508 -26.621486)
					(mid 130.046719 -26.816278)
					(end 130.4036 -27.049476)
				)
				(xy 132.674106 -27.049476) (xy 134.554976 -25.168606) (xy 134.554976 -23.683976) (xy 135.224266 -23.683976)
				(xy 136.523476 -22.384766)
				(arc
					(start 136.523476 -19.134582)
					(mid 135.905883 -15.275215)
					(end 138.809476 -12.658852)
				)
				(xy 138.809476 -12.190476) (xy 140.562076 -12.190476) (xy 140.562076 -12.114276)
				(arc
					(start 144.376648 -12.114276)
					(mid 145.8722 -11.834834)
					(end 147.367752 -12.114276)
				)
				(xy 148.540724 -12.114276) (xy 149.293834 -11.361166) (xy 149.293834 -2.032) (xy 196.96811 -2.032)
				(xy 196.96811 -35.675824)
				(arc
					(start 195.442586 -35.675824)
					(mid 194.969189 -37.137746)
					(end 193.98996 -38.321996)
				)
				(xy 193.98996 -56.452516) (xy 190.158116 -60.28436) (xy 181.092348 -60.28436) (xy 180.3146 -61.062108)
				(xy 180.3146 -70.3834) (xy 179.987956 -70.3834)
				(arc
					(start 179.987956 -85.698838)
					(mid 180.191333 -87.000977)
					(end 179.975256 -88.301068)
				)
				(arc
					(start 179.975256 -88.301068)
					(mid 179.624442 -89.63547)
					(end 178.834796 -90.7669)
				)
				(xy 178.360324 -91.241118) (xy 178.360324 -103.96855) (xy 178.659028 -104.267254) (xy 179.237386 -104.267254)
				(xy 179.598066 -103.906574)
				(arc
					(start 179.598066 -103.602536)
					(mid 179.134765 -101.824877)
					(end 178.978814 -99.994466)
				)
				(arc
					(start 178.978814 -93.999812)
					(mid 189.799976 -83.17865)
					(end 200.621138 -93.999812)
				)
				(xy 200.621138 -95.304102) (xy 202.089766 -96.77273) (xy 205.970378 -96.77273) (xy 206.793084 -95.950024)
				(arc
					(start 206.793084 -82.800444)
					(mid 206.061645 -81.537283)
					(end 205.807564 -80.099916)
				)
				(arc
					(start 205.807564 -66.799968)
					(mid 205.821886 -66.453982)
					(end 205.864714 -66.110358)
				)
				(arc
					(start 205.864714 -66.110358)
					(mid 205.850487 -65.948523)
					(end 205.842616 -65.786254)
				)
				(xy 205.842362 -65.786254) (xy 205.842362 -61.976) (xy 206.237078 -61.976) (xy 206.237078 -50.419)
				(xy 206.23784 -50.419)
				(arc
					(start 206.23784 -49.200054)
					(mid 206.168206 -49.031944)
					(end 206.000096 -48.96231)
				)
				(xy 204.78369 -48.96231) (xy 204.782928 -48.963072)
				(arc
					(start 200.000108 -48.963072)
					(mid 198.753469 -48.446697)
					(end 198.237094 -47.200058)
				)
				(arc
					(start 198.237094 -0.999998)
					(mid 198.167684 -0.832426)
					(end 198.000112 -0.763016)
				)
				(arc
					(start 0.999998 -0.763016)
					(mid 0.832426 -0.832426)
					(end 0.763016 -0.999998)
				)
				(arc
					(start 0.763016 -370.000022)
					(mid 0.832426 -370.167594)
					(end 0.999998 -370.237004)
				)
				(arc
					(start 1.999996 -370.237004)
					(mid 3.246635 -370.753379)
					(end 3.76301 -372.000018)
				)
				(arc
					(start 3.76301 -384.999992)
					(mid 3.83242 -385.167564)
					(end 3.999992 -385.236974)
				)
				(arc
					(start 15.249906 -385.236974)
					(mid 15.417478 -385.167564)
					(end 15.486888 -384.999992)
				)
				(arc
					(start 15.486888 -383.29997)
					(mid 15.757676 -382.361098)
					(end 16.486886 -381.710692)
				)
				(arc
					(start 16.486886 -381.710692)
					(mid 16.85863 -381.580932)
					(end 17.249902 -381.536956)
				)
				(arc
					(start 23.750016 -381.536956)
					(mid 24.996655 -382.053331)
					(end 25.51303 -383.29997)
				)
				(arc
					(start 25.51303 -384.999992)
					(mid 25.58244 -385.167564)
					(end 25.750012 -385.236974)
				)
				(arc
					(start 71.300086 -385.236974)
					(mid 71.467658 -385.167564)
					(end 71.537068 -384.999992)
				)
				(arc
					(start 71.537068 -381)
					(mid 72.053443 -379.753361)
					(end 73.300082 -379.236986)
				)
				(arc
					(start 125.299978 -379.236986)
					(mid 126.546617 -379.753361)
					(end 127.062992 -381)
				)
				(arc
					(start 127.062992 -384.999992)
					(mid 127.132402 -385.167564)
					(end 127.299974 -385.236974)
				)
				(arc
					(start 172.850048 -385.236974)
					(mid 173.01762 -385.167564)
					(end 173.08703 -384.999992)
				)
				(arc
					(start 173.08703 -383.29997)
					(mid 173.603405 -382.053331)
					(end 174.850044 -381.536956)
				)
				(arc
					(start 181.349904 -381.536956)
					(mid 182.596543 -382.053331)
					(end 183.112918 -383.29997)
				)
				(arc
					(start 183.112918 -384.999992)
					(mid 183.182328 -385.167564)
					(end 183.3499 -385.236974)
				)
				(arc
					(start 197.000114 -385.236974)
					(mid 197.167686 -385.167564)
					(end 197.237096 -384.999992)
				)
				(arc
					(start 197.237096 -381)
					(mid 197.753471 -379.753361)
					(end 199.00011 -379.236986)
				)
				(arc
					(start 251.000006 -379.236986)
					(mid 252.246645 -379.753361)
					(end 252.76302 -381)
				)
				(arc
					(start 252.76302 -384.999992)
					(mid 252.83243 -385.167564)
					(end 253.000002 -385.236974)
				)
				(arc
					(start 269.036292 -385.236974)
					(mid 269.126761 -385.218921)
					(end 269.203424 -385.167632)
				)
				(arc
					(start 271.617694 -382.753362)
					(mid 271.668989 -382.676683)
					(end 271.687036 -382.58623)
				)
				(xy 271.687036 -380.746) (xy 270.418052 -380.746) (xy 270.418052 -382.158494) (xy 268.608556 -383.96799)
				(xy 254.032004 -383.96799)
				(arc
					(start 254.032004 -381)
					(mid 253.143952 -378.856054)
					(end 251.000006 -377.968002)
				)
				(xy 248.365518 -377.968002) (xy 248.365518 -375.00052)
				(arc
					(start 246.76481 -373.399812)
					(mid 245.63154 -373.600941)
					(end 244.486684 -373.482362)
				)
				(xy 236.85754 -373.482362) (xy 235.68914 -372.313962) (xy 235.68914 -360.505502) (xy 235.040932 -359.857294)
				(arc
					(start 233.883962 -359.857294)
					(mid 232.225447 -360.247059)
					(end 230.55199 -359.927398)
				)
				(arc
					(start 230.55199 -359.927398)
					(mid 228.958687 -360.24803)
					(end 227.366322 -359.922826)
				)
				(arc
					(start 227.366322 -359.922826)
					(mid 226.82829 -360.111147)
					(end 226.269296 -360.2228)
				)
				(arc
					(start 226.269296 -360.2228)
					(mid 225.545564 -361.223699)
					(end 224.556066 -361.962954)
				)
				(xy 224.028508 -362.490512)
			)
		)
	)
	(zone
		(net "GND")
		(layer "F.Cu")
		(hatch none 0.5)
		(connect_pads
			(clearance 0.5)
		)
		(min_thickness 0.25)
		(fill yes
			(thermal_gap 0.5)
			(thermal_bridge_width 0.5)
			(island_removal_mode 0)
		)
		(polygon
			(pts
				(arc
					(start 302.95469 -182.12689)
					(mid 303.37237 -182.785683)
					(end 303.906174 -183.354472)
				)
				(xy 303.906174 -187.834778)
				(arc
					(start 303.80686 -187.934092)
					(mid 303.036874 -189.029389)
					(end 302.683164 -190.320676)
				)
				(arc
					(start 302.683164 -190.320676)
					(mid 302.421428 -191.715312)
					(end 302.645826 -193.116454)
				)
				(arc
					(start 302.645826 -193.116454)
					(mid 300.933939 -193.431286)
					(end 299.50791 -194.42938)
				)
				(arc
					(start 292.913054 -194.42938)
					(mid 292.794221 -194.055376)
					(end 292.640512 -193.694304)
				)
				(arc
					(start 292.640512 -193.694304)
					(mid 293.052127 -191.89446)
					(end 292.640512 -190.094616)
				)
				(arc
					(start 292.640512 -190.094616)
					(mid 293.052237 -188.294518)
					(end 292.640512 -186.49442)
				)
				(arc
					(start 292.640512 -186.49442)
					(mid 293.052127 -184.694576)
					(end 292.640512 -182.894732)
				)
				(arc
					(start 292.640512 -182.894732)
					(mid 293.052237 -181.094634)
					(end 292.640512 -179.294536)
				)
				(arc
					(start 292.640512 -179.294536)
					(mid 292.81468 -178.877087)
					(end 292.942264 -178.443128)
				)
				(xy 299.271182 -178.443128)
			)
		)
	)
	(zone
		(net "AGND_P5V_B_4")
		(layer "F.Cu")
		(hatch none 0.5)
		(connect_pads
			(clearance 0.5)
		)
		(min_thickness 0.25)
		(fill yes
			(thermal_gap 0.5)
			(thermal_bridge_width 0.5)
			(island_removal_mode 0)
		)
		(polygon
			(pts
				(xy 435.940708 -119.345456) (xy 435.421278 -119.864886) (xy 435.421278 -120.98147) (xy 435.624986 -121.185178)
				(xy 437.987186 -121.185178) (xy 438.418986 -120.753378) (xy 438.418986 -120.336818) (xy 438.883298 -119.872506)
				(xy 438.883298 -119.424958) (xy 438.803796 -119.345456)
			)
		)
		(polygon
			(pts
				(xy 436.082186 -120.829578) (xy 435.878986 -120.829578) (xy 435.878986 -121.032778) (xy 436.082186 -121.032778)
			)
		)
		(polygon
			(pts
				(xy 436.082186 -120.270778) (xy 435.878986 -120.270778) (xy 435.878986 -120.473978) (xy 436.082186 -120.473978)
			)
		)
		(polygon
			(pts
				(xy 438.427114 -119.824246) (xy 438.223914 -119.824246) (xy 438.223914 -120.027446) (xy 438.427114 -120.027446)
			)
		)
		(polygon
			(pts
				(xy 437.844184 -119.802148) (xy 437.640984 -119.802148) (xy 437.640984 -120.005348) (xy 437.844184 -120.005348)
			)
		)
		(polygon
			(pts
				(xy 437.285384 -119.802148) (xy 437.082184 -119.802148) (xy 437.082184 -120.005348) (xy 437.285384 -120.005348)
			)
		)
		(polygon
			(pts
				(xy 436.793386 -119.788178) (xy 436.590186 -119.788178) (xy 436.590186 -119.991378) (xy 436.793386 -119.991378)
			)
		)
		(polygon
			(pts
				(xy 436.234586 -119.788178) (xy 436.031386 -119.788178) (xy 436.031386 -119.991378) (xy 436.234586 -119.991378)
			)
		)
	)
	(zone
		(net "P5V_B_3")
		(layer "F.Cu")
		(hatch none 0.5)
		(connect_pads
			(clearance 0.5)
		)
		(min_thickness 0.25)
		(fill yes
			(thermal_gap 0.5)
			(thermal_bridge_width 0.5)
			(island_removal_mode 0)
		)
		(polygon
			(pts
				(xy 431.419 -251.333) (xy 431.165 -251.587) (xy 431.165 -256.286) (xy 431.419 -256.54) (xy 433.705 -256.54)
				(xy 433.959 -256.286) (xy 433.959 -251.587) (xy 433.705 -251.333)
			)
		)
	)
	(zone
		(layer "F.Cu")
		(hatch none 0.5)
		(connect_pads
			(clearance 0)
		)
		(min_thickness 0.25)
		(keepout
			(tracks not_allowed)
			(vias allowed)
			(pads allowed)
			(copperpour not_allowed)
			(footprints allowed)
		)
		(placement
			(enabled no)
			(sheetname "")
		)
		(fill
			(thermal_gap 0.5)
			(thermal_bridge_width 0.5)
			(island_removal_mode 0)
		)
		(polygon
			(pts
				(arc
					(start 165.450012 -13.999972)
					(mid 170.200066 -9.249918)
					(end 174.95012 -13.999972)
				)
				(arc
					(start 174.95012 -13.999972)
					(mid 170.200066 -18.750026)
					(end 165.450012 -13.999972)
				)
			)
		)
	)
	(zone
		(net "MB3_12V_CTRL_GATE2")
		(layer "F.Cu")
		(hatch none 0.5)
		(connect_pads
			(clearance 0.5)
		)
		(min_thickness 0.25)
		(fill yes
			(thermal_gap 0.5)
			(thermal_bridge_width 0.5)
			(island_removal_mode 0)
		)
		(polygon
			(pts
				(xy 263.4742 -343.5858) (xy 263.252458 -343.807542) (xy 260.425184 -343.807542) (xy 260.317996 -343.91473)
				(xy 260.317996 -345.114118) (xy 260.550152 -345.346274) (xy 265.211052 -345.346274) (xy 265.464036 -345.09329)
				(xy 265.464036 -343.727278) (xy 265.322558 -343.5858)
			)
		)
	)
	(zone
		(net "GND")
		(layer "F.Cu")
		(hatch none 0.5)
		(connect_pads
			(clearance 0.5)
		)
		(min_thickness 0.25)
		(fill yes
			(thermal_gap 0.5)
			(thermal_bridge_width 0.5)
			(island_removal_mode 0)
		)
		(polygon
			(pts
				(xy 83.226148 -117.990112) (xy 77.276452 -123.939808)
				(arc
					(start 71.639176 -123.939808)
					(mid 70.970061 -125.213987)
					(end 69.901054 -126.177548)
				)
				(arc
					(start 69.901054 -131.57835)
					(mid 69.429531 -133.478845)
					(end 68.124324 -134.938516)
				)
				(arc
					(start 68.124324 -135.40105)
					(mid 67.714478 -137.179956)
					(end 66.567558 -138.60018)
				)
				(xy 66.567558 -142.187422) (xy 67.329812 -142.949676) (xy 70.560184 -142.949676) (xy 71.435976 -142.073884)
				(xy 71.435976 -138.618976) (xy 72.781414 -138.618976) (xy 73.404476 -137.995914)
				(arc
					(start 73.404476 -134.069582)
					(mid 72.786883 -130.210215)
					(end 75.690476 -127.593852)
				)
				(xy 75.690476 -127.125476) (xy 77.443076 -127.125476) (xy 77.443076 -127.049276)
				(arc
					(start 80.861662 -127.049276)
					(mid 82.702962 -126.592297)
					(end 84.554822 -127.004318)
				)
				(arc
					(start 84.554822 -127.004318)
					(mid 84.624374 -127.026149)
					(end 84.693506 -127.049276)
				)
				(xy 85.803994 -127.049276) (xy 86.193884 -126.659386) (xy 86.193884 -118.561612) (xy 85.622384 -117.990112)
			)
		)
	)
	(zone
		(net "P12V_B_3_VIN_U33")
		(layer "F.Cu")
		(hatch none 0.5)
		(connect_pads
			(clearance 0.5)
		)
		(min_thickness 0.25)
		(fill yes
			(thermal_gap 0.5)
			(thermal_bridge_width 0.5)
			(island_removal_mode 0)
		)
		(polygon
			(pts
				(xy 452.68896 -221.246192) (xy 451.633336 -222.301816) (xy 451.633336 -224.622106) (xy 451.834504 -224.823274)
				(xy 454.513442 -224.823274) (xy 454.622408 -224.714308) (xy 454.622408 -221.350332) (xy 454.518268 -221.246192)
			)
		)
	)
	(zone
		(net "P12V_B")
		(layer "F.Cu")
		(hatch none 0.5)
		(connect_pads
			(clearance 0.5)
		)
		(min_thickness 0.25)
		(fill yes
			(thermal_gap 0.5)
			(thermal_bridge_width 0.5)
			(island_removal_mode 0)
		)
		(polygon
			(pts
				(xy 429.26 -257.429) (xy 428.752 -257.937) (xy 428.752 -261.366) (xy 429.006 -261.62) (xy 432.308 -261.62)
				(xy 432.562 -261.366) (xy 432.562 -259.334) (xy 432.689 -259.207) (xy 433.07 -259.207) (xy 433.171092 -259.105908)
				(xy 433.171092 -257.530092) (xy 433.07 -257.429)
			)
		)
		(polygon
			(pts
				(xy 432.6636 -258.4196) (xy 432.4604 -258.4196) (xy 432.4604 -258.6228) (xy 432.6636 -258.6228)
			)
		)
		(polygon
			(pts
				(xy 432.7144 -257.9878) (xy 432.5112 -257.9878) (xy 432.5112 -258.191) (xy 432.7144 -258.191)
			)
		)
	)
	(zone
		(layer "F.Cu")
		(hatch none 0.5)
		(connect_pads
			(clearance 0)
		)
		(min_thickness 0.25)
		(keepout
			(tracks not_allowed)
			(vias allowed)
			(pads allowed)
			(copperpour not_allowed)
			(footprints allowed)
		)
		(placement
			(enabled no)
			(sheetname "")
		)
		(fill
			(thermal_gap 0.5)
			(thermal_bridge_width 0.5)
			(island_removal_mode 0)
		)
		(polygon
			(pts
				(arc
					(start 67.69989 -331.399896)
					(mid 71.699882 -335.399888)
					(end 67.69989 -339.39988)
				)
				(arc
					(start 62.61989 -339.39988)
					(mid 58.619898 -335.399888)
					(end 62.61989 -331.399896)
				)
			)
		)
	)
	(zone
		(net "P5V_B_3")
		(layer "F.Cu")
		(hatch none 0.5)
		(connect_pads
			(clearance 0.5)
		)
		(min_thickness 0.25)
		(fill yes
			(thermal_gap 0.5)
			(thermal_bridge_width 0.5)
			(island_removal_mode 0)
		)
		(polygon
			(pts
				(xy 462.915 -251.333) (xy 462.661 -251.587) (xy 462.661 -256.286) (xy 462.915 -256.54) (xy 465.201 -256.54)
				(xy 465.455 -256.286) (xy 465.455 -251.587) (xy 465.201 -251.333)
			)
		)
	)
	(zone
		(layer "F.Cu")
		(hatch none 0.5)
		(connect_pads
			(clearance 0)
		)
		(min_thickness 0.25)
		(keepout
			(tracks allowed)
			(vias allowed)
			(pads allowed)
			(copperpour allowed)
			(footprints allowed)
		)
		(placement
			(enabled no)
			(sheetname "")
		)
		(fill
			(thermal_gap 0.5)
			(thermal_bridge_width 0.5)
			(island_removal_mode 0)
		)
		(polygon
			(pts
				(xy 31.4706 -249.6312) (xy 32.7406 -249.6312) (xy 32.893 -249.4788) (xy 32.893 -248.0564) (xy 32.766 -247.9294)
				(xy 31.5468 -247.9294) (xy 31.3436 -248.1326) (xy 31.3436 -249.5042)
			)
		)
	)
	(zone
		(net "GND")
		(layer "F.Cu")
		(hatch none 0.5)
		(connect_pads
			(clearance 0.5)
		)
		(min_thickness 0.25)
		(fill yes
			(thermal_gap 0.5)
			(thermal_bridge_width 0.5)
			(island_removal_mode 0)
		)
		(polygon
			(pts
				(xy 343.119202 -130.37439) (xy 342.909398 -130.584194) (xy 342.909398 -131.310634) (xy 343.26449 -131.665726)
				(arc
					(start 343.26449 -131.761992)
					(mid 345.765775 -135.264307)
					(end 343.74836 -139.066016)
				)
				(arc
					(start 343.74836 -142.1765)
					(mid 343.646445 -143.061861)
					(end 343.346024 -143.900906)
				)
				(xy 343.346024 -160.263586) (xy 340.033356 -163.576254) (xy 338.363052 -163.576254) (xy 338.012024 -163.927282)
				(xy 338.012024 -164.699188) (xy 338.275676 -164.96284) (xy 351.556574 -164.96284) (xy 351.993962 -164.525452)
				(xy 351.993962 -161.948368) (xy 345.540076 -155.494482) (xy 345.540076 -141.399768) (xy 345.88704 -141.052804)
				(xy 345.88704 -132.929884) (xy 343.331546 -130.37439)
			)
		)
	)
	(zone
		(net "P12V_HDD1")
		(layer "F.Cu")
		(hatch none 0.5)
		(connect_pads
			(clearance 0.5)
		)
		(min_thickness 0.25)
		(fill yes
			(thermal_gap 0.5)
			(thermal_bridge_width 0.5)
			(island_removal_mode 0)
		)
		(polygon
			(pts
				(xy 43.942 -262.255) (xy 43.688 -262.509) (xy 43.688 -264.16) (xy 43.942 -264.414) (xy 46.101 -264.414)
				(xy 46.609 -264.922) (xy 46.609 -267.462) (xy 54.356 -275.209) (xy 62.865 -275.209) (xy 62.992 -275.082)
				(xy 62.992 -273.304) (xy 62.865 -273.177) (xy 56.896 -273.177) (xy 56.261 -272.542) (xy 54.61 -272.542)
				(xy 50.292 -268.224) (xy 50.292 -264.668) (xy 49.149 -263.525) (xy 49.149 -262.509) (xy 48.895 -262.255)
			)
		)
		(polygon
			(pts
				(xy 56.4134 -274.2184) (xy 56.2102 -274.2184) (xy 56.2102 -274.4216) (xy 56.4134 -274.4216)
			)
		)
		(polygon
			(pts
				(xy 55.5498 -274.2184) (xy 55.3466 -274.2184) (xy 55.3466 -274.4216) (xy 55.5498 -274.4216)
			)
		)
	)
	(zone
		(layer "F.Cu")
		(hatch none 0.5)
		(connect_pads
			(clearance 0)
		)
		(min_thickness 0.25)
		(keepout
			(tracks not_allowed)
			(vias allowed)
			(pads allowed)
			(copperpour not_allowed)
			(footprints allowed)
		)
		(placement
			(enabled no)
			(sheetname "")
		)
		(fill
			(thermal_gap 0.5)
			(thermal_bridge_width 0.5)
			(island_removal_mode 0)
		)
		(polygon
			(pts
				(arc
					(start 127.64389 -133.11505)
					(mid 127.15875 -132.62991)
					(end 126.67361 -133.11505)
				)
				(xy 126.67361 -133.5278)
				(arc
					(start 127.03175 -133.5278)
					(mid 127.067671 -133.512921)
					(end 127.08255 -133.477)
				)
				(arc
					(start 127.08255 -133.370574)
					(mid 127.15875 -132.848406)
					(end 127.23495 -133.370574)
				)
				(xy 127.23495 -133.508496)
				(arc
					(start 127.231902 -133.511544)
					(mid 127.175371 -133.620621)
					(end 127.066294 -133.677152)
				)
				(xy 127.063246 -133.6802) (xy 126.67361 -133.6802) (xy 126.67361 -133.8199) (xy 127.063246 -133.8199)
				(arc
					(start 127.066294 -133.822948)
					(mid 127.175371 -133.879479)
					(end 127.231902 -133.988556)
				)
				(xy 127.23495 -133.991604)
				(arc
					(start 127.23495 -134.129526)
					(mid 127.15875 -134.651694)
					(end 127.08255 -134.129526)
				)
				(arc
					(start 127.08255 -134.0231)
					(mid 127.067671 -133.987179)
					(end 127.03175 -133.9723)
				)
				(xy 126.67361 -133.9723)
				(arc
					(start 126.67361 -134.384796)
					(mid 127.158623 -134.87019)
					(end 127.64389 -134.38505)
				)
			)
		)
	)
	(zone
		(layer "F.Cu")
		(hatch none 0.5)
		(connect_pads
			(clearance 0)
		)
		(min_thickness 0.25)
		(keepout
			(tracks allowed)
			(vias allowed)
			(pads allowed)
			(copperpour allowed)
			(footprints not_allowed)
		)
		(placement
			(enabled no)
			(sheetname "")
		)
		(fill
			(thermal_gap 0.5)
			(thermal_bridge_width 0.5)
			(island_removal_mode 0)
		)
		(polygon
			(pts
				(xy 291.599874 -259.999988) (xy 298.200064 -259.999988) (xy 298.200064 -385.99999) (xy 291.599874 -385.99999)
			)
		)
	)
	(zone
		(net "P5V_B_3")
		(layer "F.Cu")
		(hatch none 0.5)
		(connect_pads
			(clearance 0.5)
		)
		(min_thickness 0.25)
		(fill yes
			(thermal_gap 0.5)
			(thermal_bridge_width 0.5)
			(island_removal_mode 0)
		)
		(polygon
			(pts
				(xy 473.456 -251.841) (xy 473.202 -252.095) (xy 473.202 -254.381) (xy 473.456 -254.635) (xy 478.155 -254.635)
				(xy 478.409 -254.381) (xy 478.409 -252.095) (xy 478.155 -251.841)
			)
		)
	)
	(zone
		(net "P12V_HDD3")
		(layer "F.Cu")
		(hatch none 0.5)
		(connect_pads
			(clearance 0.5)
		)
		(min_thickness 0.25)
		(fill yes
			(thermal_gap 0.5)
			(thermal_bridge_width 0.5)
			(island_removal_mode 0)
		)
		(polygon
			(pts
				(xy 106.934 -262.255) (xy 106.68 -262.509) (xy 106.68 -264.16) (xy 106.934 -264.414) (xy 109.093 -264.414)
				(xy 109.601 -264.922) (xy 109.601 -267.462) (xy 117.348 -275.209) (xy 125.857 -275.209) (xy 125.984 -275.082)
				(xy 125.984 -273.304) (xy 125.857 -273.177) (xy 119.888 -273.177) (xy 119.253 -272.542) (xy 117.602 -272.542)
				(xy 113.284 -268.224) (xy 113.284 -264.8458) (xy 112.141 -263.7028) (xy 112.141 -262.509) (xy 111.887 -262.255)
			)
		)
		(polygon
			(pts
				(xy 119.4054 -274.2184) (xy 119.2022 -274.2184) (xy 119.2022 -274.4216) (xy 119.4054 -274.4216)
			)
		)
		(polygon
			(pts
				(xy 118.5418 -274.2184) (xy 118.3386 -274.2184) (xy 118.3386 -274.4216) (xy 118.5418 -274.4216)
			)
		)
	)
	(zone
		(net "GND")
		(layer "F.Cu")
		(hatch none 0.5)
		(connect_pads
			(clearance 0.5)
		)
		(min_thickness 0.25)
		(fill yes
			(thermal_gap 0.5)
			(thermal_bridge_width 0.5)
			(island_removal_mode 0)
		)
		(polygon
			(pts
				(xy 374.551956 -131.111752) (xy 374.270524 -131.393184)
				(arc
					(start 374.270524 -133.01218)
					(mid 374.693512 -133.703161)
					(end 374.97385 -134.463282)
				)
				(arc
					(start 374.97385 -134.463282)
					(mid 375.176108 -135.163678)
					(end 375.24436 -135.889492)
				)
				(arc
					(start 375.24436 -142.1765)
					(mid 375.142445 -143.061861)
					(end 374.842024 -143.900906)
				)
				(xy 374.842024 -160.263586) (xy 371.529356 -163.576254) (xy 369.890802 -163.576254) (xy 369.508024 -163.959032)
				(xy 369.508024 -164.720778) (xy 369.750086 -164.96284) (xy 382.266698 -164.96284) (xy 383.212594 -164.016944)
				(xy 383.212594 -160.250632)
				(arc
					(start 381.859536 -158.897574)
					(mid 378.433497 -156.352383)
					(end 378.983748 -152.120092)
				)
				(xy 378.983748 -151.707088) (xy 378.484384 -151.207724) (xy 376.959876 -151.207724) (xy 376.959876 -141.298676)
				(xy 376.96013 -141.298676) (xy 377.30684 -140.951966) (xy 377.30684 -133.115558) (xy 375.303034 -131.111752)
			)
		)
	)
	(zone
		(net "P12V_B")
		(layer "F.Cu")
		(hatch none 0.5)
		(connect_pads
			(clearance 0.5)
		)
		(min_thickness 0.25)
		(fill yes
			(thermal_gap 0.5)
			(thermal_bridge_width 0.5)
			(island_removal_mode 0)
		)
		(polygon
			(pts
				(xy 77.343 -255.143) (xy 76.327 -256.159) (xy 75.692 -256.159) (xy 75.311 -256.54) (xy 75.311 -259.08)
				(xy 75.565 -259.334) (xy 78.867 -259.334) (xy 79.121 -259.08) (xy 79.121 -256.794) (xy 78.486 -256.159)
				(xy 78.105 -256.159) (xy 77.851 -255.905) (xy 77.851 -255.27) (xy 77.724 -255.143)
			)
		)
		(polygon
			(pts
				(xy 77.3176 -255.7272) (xy 77.1144 -255.7272) (xy 77.1144 -255.9304) (xy 77.3176 -255.9304)
			)
		)
	)
	(zone
		(layer "F.Cu")
		(hatch none 0.5)
		(connect_pads
			(clearance 0)
		)
		(min_thickness 0.25)
		(keepout
			(tracks allowed)
			(vias allowed)
			(pads allowed)
			(copperpour allowed)
			(footprints allowed)
		)
		(placement
			(enabled no)
			(sheetname "")
		)
		(fill
			(thermal_gap 0.5)
			(thermal_bridge_width 0.5)
			(island_removal_mode 0)
		)
		(polygon
			(pts
				(xy 218.4908 -194.0306) (xy 218.4908 -196.5452) (xy 216.916 -196.5452) (xy 216.916 -194.0306)
			)
		)
	)
	(zone
		(layer "F.Cu")
		(hatch none 0.5)
		(connect_pads
			(clearance 0)
		)
		(min_thickness 0.25)
		(keepout
			(tracks not_allowed)
			(vias allowed)
			(pads allowed)
			(copperpour not_allowed)
			(footprints allowed)
		)
		(placement
			(enabled no)
			(sheetname "")
		)
		(fill
			(thermal_gap 0.5)
			(thermal_bridge_width 0.5)
			(island_removal_mode 0)
		)
		(polygon
			(pts
				(arc
					(start 160.970722 -244.419374)
					(mid 160.485582 -243.934234)
					(end 160.000442 -244.419374)
				)
				(xy 160.000442 -244.768624)
				(arc
					(start 160.326578 -244.768624)
					(mid 160.385129 -244.744371)
					(end 160.409382 -244.68582)
				)
				(arc
					(start 160.409382 -244.674898)
					(mid 160.485582 -244.15273)
					(end 160.561782 -244.674898)
				)
				(xy 160.561782 -244.717316)
				(arc
					(start 160.559242 -244.719856)
					(mid 160.492847 -244.852089)
					(end 160.360614 -244.918484)
				)
				(xy 160.358074 -244.921024) (xy 160.000442 -244.921024) (xy 160.000442 -245.060724) (xy 160.358074 -245.060724)
				(arc
					(start 160.360614 -245.063264)
					(mid 160.492847 -245.129659)
					(end 160.559242 -245.261892)
				)
				(xy 160.561782 -245.264432)
				(arc
					(start 160.561782 -245.30685)
					(mid 160.485582 -245.829018)
					(end 160.409382 -245.30685)
				)
				(arc
					(start 160.409382 -245.295928)
					(mid 160.385129 -245.237377)
					(end 160.326578 -245.213124)
				)
				(xy 160.000442 -245.213124)
				(arc
					(start 160.000442 -245.56212)
					(mid 160.485455 -246.047514)
					(end 160.970722 -245.562374)
				)
			)
		)
	)
	(zone
		(net "GND")
		(layer "F.Cu")
		(hatch none 0.5)
		(connect_pads
			(clearance 0.5)
		)
		(min_thickness 0.25)
		(fill yes
			(thermal_gap 0.5)
			(thermal_bridge_width 0.5)
			(island_removal_mode 0)
		)
		(polygon
			(pts
				(xy 258.1148 -193.167) (xy 257.656076 -193.625724) (xy 257.656076 -197.734682) (xy 258.037076 -198.115682)
				(xy 264.514076 -198.115682) (xy 264.768076 -197.861682) (xy 264.768076 -193.825876) (xy 264.1092 -193.167)
			)
		)
	)
	(zone
		(layer "F.Cu")
		(hatch none 0.5)
		(connect_pads
			(clearance 0)
		)
		(min_thickness 0.25)
		(keepout
			(tracks not_allowed)
			(vias allowed)
			(pads allowed)
			(copperpour not_allowed)
			(footprints allowed)
		)
		(placement
			(enabled no)
			(sheetname "")
		)
		(fill
			(thermal_gap 0.5)
			(thermal_bridge_width 0.5)
			(island_removal_mode 0)
		)
		(polygon
			(pts
				(arc
					(start 480.431856 -131.951984)
					(mid 479.946462 -132.436997)
					(end 480.431602 -132.922264)
				)
				(xy 480.844352 -132.922264)
				(arc
					(start 480.844352 -132.599176)
					(mid 480.819207 -132.538469)
					(end 480.7585 -132.513324)
				)
				(arc
					(start 480.687126 -132.513324)
					(mid 480.164958 -132.437124)
					(end 480.687126 -132.360924)
				)
				(xy 480.789996 -132.360924)
				(arc
					(start 480.792536 -132.363464)
					(mid 480.926902 -132.430774)
					(end 480.994212 -132.56514)
				)
				(xy 480.996752 -132.56768) (xy 480.996752 -132.922264) (xy 481.136452 -132.922264) (xy 481.136452 -132.56768)
				(arc
					(start 481.138992 -132.56514)
					(mid 481.206302 -132.430774)
					(end 481.340668 -132.363464)
				)
				(xy 481.343208 -132.360924)
				(arc
					(start 481.446078 -132.360924)
					(mid 481.968246 -132.437124)
					(end 481.446078 -132.513324)
				)
				(arc
					(start 481.374704 -132.513324)
					(mid 481.313997 -132.538469)
					(end 481.288852 -132.599176)
				)
				(xy 481.288852 -132.922264)
				(arc
					(start 481.701602 -132.922264)
					(mid 482.186742 -132.437124)
					(end 481.701602 -131.951984)
				)
			)
		)
	)
	(zone
		(net "P12V_HDD7")
		(layer "F.Cu")
		(hatch none 0.5)
		(connect_pads
			(clearance 0.5)
		)
		(min_thickness 0.25)
		(fill yes
			(thermal_gap 0.5)
			(thermal_bridge_width 0.5)
			(island_removal_mode 0)
		)
		(polygon
			(pts
				(xy 366.141 -264.541) (xy 365.887 -264.795) (xy 365.887 -268.859) (xy 365.4298 -269.3162) (xy 365.4298 -271.6276)
				(xy 364.0074 -273.05) (xy 357.759 -273.05) (xy 357.505 -273.304) (xy 357.505 -274.955) (xy 357.759 -275.209)
				(xy 361.696 -275.209) (xy 362.204 -274.701) (xy 369.951 -274.701) (xy 370.84 -273.812) (xy 370.84 -264.795)
				(xy 370.586 -264.541)
			)
		)
		(polygon
			(pts
				(xy 361.8484 -274.0914) (xy 361.6452 -274.0914) (xy 361.6452 -274.2946) (xy 361.8484 -274.2946)
			)
		)
		(polygon
			(pts
				(xy 360.9848 -274.0914) (xy 360.7816 -274.0914) (xy 360.7816 -274.2946) (xy 360.9848 -274.2946)
			)
		)
	)
	(zone
		(net "12V_PRE_14")
		(layer "F.Cu")
		(hatch none 0.5)
		(connect_pads
			(clearance 0.5)
		)
		(min_thickness 0.25)
		(fill yes
			(thermal_gap 0.5)
			(thermal_bridge_width 0.5)
			(island_removal_mode 0)
		)
		(polygon
			(pts
				(xy 82.804 -149.733) (xy 82.677 -149.86) (xy 82.677 -151.384) (xy 84.074 -152.781) (xy 85.471 -152.781)
				(xy 90.424 -157.734) (xy 94.361 -157.734) (xy 94.488 -157.607) (xy 94.488 -156.845) (xy 94.361 -156.718)
				(xy 91.059 -156.718) (xy 84.074 -149.733)
			)
		)
	)
	(zone
		(net "P12V_FAN0")
		(layer "F.Cu")
		(hatch none 0.5)
		(connect_pads
			(clearance 0.5)
		)
		(min_thickness 0.25)
		(fill yes
			(thermal_gap 0.5)
			(thermal_bridge_width 0.5)
			(island_removal_mode 0)
		)
		(polygon
			(pts
				(xy 54.102 -358.267) (xy 53.942996 -358.426004) (xy 53.942996 -359.8672) (xy 53.866796 -359.9434)
				(xy 53.866796 -361.4166) (xy 52.749196 -362.5342) (xy 49.116996 -362.5342) (xy 49.104296 -362.5469)
				(xy 49.002696 -362.5469) (xy 48.939196 -362.6104) (xy 48.939196 -365.3536) (xy 49.015396 -365.4298)
				(xy 52.850796 -365.4298) (xy 53.180996 -365.76) (xy 53.180996 -374.523) (xy 53.600096 -374.9421)
				(xy 56.800496 -374.9421) (xy 57.001156 -374.74144) (xy 57.001156 -358.65689) (xy 56.611266 -358.267)
			)
		)
		(polygon
			(pts
				(xy 56.52897 -364.446566) (xy 56.32577 -364.446566) (xy 56.32577 -364.649766) (xy 56.52897 -364.649766)
			)
		)
		(polygon
			(pts
				(xy 56.52897 -363.836966) (xy 56.32577 -363.836966) (xy 56.32577 -364.040166) (xy 56.52897 -364.040166)
			)
		)
		(polygon
			(pts
				(xy 56.203596 -363.5502) (xy 56.000396 -363.5502) (xy 56.000396 -363.7534) (xy 56.203596 -363.7534)
			)
		)
		(polygon
			(pts
				(xy 56.203596 -362.6866) (xy 56.000396 -362.6866) (xy 56.000396 -362.8898) (xy 56.203596 -362.8898)
			)
		)
	)
	(zone
		(layer "F.Cu")
		(hatch none 0.5)
		(connect_pads
			(clearance 0)
		)
		(min_thickness 0.25)
		(keepout
			(tracks not_allowed)
			(vias allowed)
			(pads allowed)
			(copperpour not_allowed)
			(footprints allowed)
		)
		(placement
			(enabled no)
			(sheetname "")
		)
		(fill
			(thermal_gap 0.5)
			(thermal_bridge_width 0.5)
			(island_removal_mode 0)
		)
		(polygon
			(pts
				(arc
					(start 64.54394 -248.115328)
					(mid 64.058927 -247.629934)
					(end 63.57366 -248.115074)
				)
				(xy 63.57366 -248.527824)
				(arc
					(start 63.9318 -248.527824)
					(mid 63.967721 -248.512945)
					(end 63.9826 -248.477024)
				)
				(arc
					(start 63.9826 -248.370598)
					(mid 64.0588 -247.84843)
					(end 64.135 -248.370598)
				)
				(xy 64.135 -248.50852)
				(arc
					(start 64.131952 -248.511568)
					(mid 64.075421 -248.620645)
					(end 63.966344 -248.677176)
				)
				(xy 63.963296 -248.680224) (xy 63.57366 -248.680224) (xy 63.57366 -248.819924) (xy 63.963296 -248.819924)
				(arc
					(start 63.966344 -248.822972)
					(mid 64.075421 -248.879503)
					(end 64.131952 -248.98858)
				)
				(xy 64.135 -248.991628)
				(arc
					(start 64.135 -249.12955)
					(mid 64.0588 -249.651718)
					(end 63.9826 -249.12955)
				)
				(arc
					(start 63.9826 -249.023124)
					(mid 63.967721 -248.987203)
					(end 63.9318 -248.972324)
				)
				(xy 63.57366 -248.972324)
				(arc
					(start 63.57366 -249.385074)
					(mid 64.0588 -249.870214)
					(end 64.54394 -249.385074)
				)
			)
		)
	)
	(zone
		(layer "F.Cu")
		(hatch none 0.5)
		(connect_pads
			(clearance 0)
		)
		(min_thickness 0.25)
		(keepout
			(tracks allowed)
			(vias allowed)
			(pads allowed)
			(copperpour allowed)
			(footprints allowed)
		)
		(placement
			(enabled no)
			(sheetname "")
		)
		(fill
			(thermal_gap 0.5)
			(thermal_bridge_width 0.5)
			(island_removal_mode 0)
		)
		(polygon
			(pts
				(xy 132.738876 -364.571026) (xy 132.738876 -362.817156) (xy 134.638542 -362.817156) (xy 134.638542 -364.571026)
			)
		)
	)
	(zone
		(layer "F.Cu")
		(hatch none 0.5)
		(connect_pads
			(clearance 0)
		)
		(min_thickness 0.25)
		(keepout
			(tracks allowed)
			(vias allowed)
			(pads allowed)
			(copperpour allowed)
			(footprints not_allowed)
		)
		(placement
			(enabled no)
			(sheetname "")
		)
		(fill
			(thermal_gap 0.5)
			(thermal_bridge_width 0.5)
			(island_removal_mode 0)
		)
		(polygon
			(pts
				(xy 291.599874 -259.999988) (xy 291.599874 -312.300112) (xy 288.619946 -312.300112) (xy 288.619946 -303.029874)
				(xy 280.999946 -303.029874) (xy 280.999946 -312.399934) (xy 288.619946 -312.399934) (xy 291.599874 -312.399934)
				(xy 291.599874 -385.99999)
				(arc
					(start 280.164286 -385.99999)
					(mid 279.781603 -385.92387)
					(end 279.45715 -385.707128)
				)
				(arc
					(start 277.04288 -383.292858)
					(mid 276.826098 -382.968421)
					(end 276.750018 -382.585722)
				)
				(xy 276.750018 -371.00002) (xy 289.699954 -371.00002) (xy 289.699954 -345.000072) (xy 251.000006 -345.000072)
				(xy 251.000006 -336.00009) (xy 239.00003 -336.00009) (xy 239.00003 -345.000072) (xy 200.300082 -345.000072)
				(xy 200.300082 -370.000022) (xy 198.399908 -370.000022) (xy 198.399908 -312.529982) (xy 199.719946 -312.529982)
				(xy 207.339946 -312.529982) (xy 207.339946 -303.159922) (xy 199.719946 -303.159922) (xy 199.719946 -312.429906)
				(xy 198.399908 -312.429906) (xy 198.399908 -220.000068) (xy 202.300078 -220.000068) (xy 202.300078 -194.00012)
				(xy 198.399908 -194.00012) (xy 198.399908 -149.969982) (xy 201.989944 -149.969982) (xy 209.609944 -149.969982)
				(xy 209.609944 -140.599922) (xy 201.989944 -140.599922) (xy 201.989944 -149.869906) (xy 198.399908 -149.869906)
				(xy 198.399908 -110.000034) (xy 202.300078 -110.000034) (xy 202.300078 -100.57003) (xy 203.160122 -100.57003)
				(xy 203.160122 -109.840014) (xy 210.780122 -109.840014) (xy 210.780122 -100.469954) (xy 203.160122 -100.469954)
				(xy 202.300078 -100.469954) (xy 202.300078 -84.000086) (xy 198.399908 -84.000086)
				(arc
					(start 198.399908 -0.083566)
					(mid 198.836695 -0.452275)
					(end 199.00011 -0.999998)
				)
				(arc
					(start 199.00011 -47.200058)
					(mid 199.293003 -47.907163)
					(end 200.000108 -48.200056)
				)
				(arc
					(start 206.000096 -48.200056)
					(mid 206.707201 -48.492949)
					(end 207.000094 -49.200054)
				)
				(arc
					(start 207.000094 -61.999876)
					(mid 207.292987 -62.706981)
					(end 208.000092 -62.999874)
				)
				(arc
					(start 267.999972 -62.999874)
					(mid 268.707077 -62.706981)
					(end 268.99997 -61.999876)
				)
				(arc
					(start 268.99997 -49.200054)
					(mid 269.292863 -48.492949)
					(end 269.999968 -48.200056)
				)
				(xy 291.599874 -48.200056) (xy 291.599874 -84.000086) (xy 287.699958 -84.000086) (xy 287.699958 -100.210112)
				(xy 286.429958 -100.210112) (xy 278.809958 -100.210112) (xy 278.809958 -109.579918) (xy 286.429958 -109.579918)
				(xy 286.429958 -100.309934) (xy 287.699958 -100.309934) (xy 287.699958 -110.000034) (xy 291.599874 -110.000034)
				(xy 291.599874 -203.069952) (xy 265.020044 -203.069952) (xy 265.020044 -193.799968) (xy 257.400044 -193.799968)
				(xy 257.400044 -203.170028) (xy 265.020044 -203.170028) (xy 291.599874 -203.170028) (xy 291.599874 -234.00004)
				(xy 287.699958 -234.00004) (xy 287.699958 -259.999988)
			)
		)
	)
	(zone
		(net "P5V_B_3")
		(layer "F.Cu")
		(hatch none 0.5)
		(connect_pads
			(clearance 0.5)
		)
		(min_thickness 0.25)
		(fill yes
			(thermal_gap 0.5)
			(thermal_bridge_width 0.5)
			(island_removal_mode 0)
		)
		(polygon
			(pts
				(xy 336.804 -251.333) (xy 336.55 -251.587) (xy 336.55 -256.286) (xy 336.804 -256.54) (xy 339.09 -256.54)
				(xy 339.344 -256.286) (xy 339.344 -251.587) (xy 339.09 -251.333)
			)
		)
	)
	(zone
		(layer "F.Cu")
		(hatch none 0.5)
		(connect_pads
			(clearance 0)
		)
		(min_thickness 0.25)
		(keepout
			(tracks allowed)
			(vias allowed)
			(pads allowed)
			(copperpour allowed)
			(footprints allowed)
		)
		(placement
			(enabled no)
			(sheetname "")
		)
		(fill
			(thermal_gap 0.5)
			(thermal_bridge_width 0.5)
			(island_removal_mode 0)
		)
		(polygon
			(pts
				(xy 252.476 -364.2106) (xy 252.476 -362.585) (xy 253.2634 -362.585) (xy 253.2634 -364.2106)
			)
		)
	)
	(zone
		(net "12V_PRE_27")
		(layer "F.Cu")
		(hatch none 0.5)
		(connect_pads
			(clearance 0.5)
		)
		(min_thickness 0.25)
		(fill yes
			(thermal_gap 0.5)
			(thermal_bridge_width 0.5)
			(island_removal_mode 0)
		)
		(polygon
			(pts
				(xy 114.3 -34.798) (xy 114.173 -34.925) (xy 114.173 -36.449) (xy 115.57 -37.846) (xy 116.967 -37.846)
				(xy 121.92 -42.799) (xy 125.857 -42.799) (xy 125.984 -42.672) (xy 125.984 -41.91) (xy 125.857 -41.783)
				(xy 122.555 -41.783) (xy 115.57 -34.798)
			)
		)
	)
	(zone
		(net "GND")
		(layer "F.Cu")
		(hatch none 0.5)
		(connect_pads
			(clearance 0.5)
		)
		(min_thickness 0.25)
		(fill yes
			(thermal_gap 0.5)
			(thermal_bridge_width 0.5)
			(island_removal_mode 0)
		)
		(polygon
			(pts
				(arc
					(start 216.003632 -252.408944)
					(mid 214.76487 -253.132748)
					(end 213.35238 -253.384304)
				)
				(arc
					(start 212.763862 -253.384304)
					(mid 212.214903 -253.792315)
					(end 211.605622 -254.103124)
				)
				(xy 211.605622 -255.201928)
				(arc
					(start 212.292946 -255.889252)
					(mid 216.674747 -259.845958)
					(end 212.538818 -264.058908)
				)
				(xy 211.605622 -264.992104) (xy 211.605622 -267.34008) (xy 212.54085 -268.275308)
				(arc
					(start 213.134702 -268.275308)
					(mid 218.127431 -272.52914)
					(end 212.624416 -276.098)
				)
				(xy 210.95208 -276.098)
				(arc
					(start 201.668888 -285.381192)
					(mid 200.850456 -286.545484)
					(end 199.686164 -287.363916)
				)
				(xy 199.213978 -287.836102) (xy 199.213978 -288.095944) (xy 199.59066 -288.472626)
				(arc
					(start 200.274682 -288.472626)
					(mid 201.387926 -288.150917)
					(end 202.546712 -288.154364)
				)
				(arc
					(start 202.546712 -288.154364)
					(mid 204.606168 -288.497933)
					(end 206.22768 -289.813238)
				)
				(arc
					(start 207.789272 -289.813238)
					(mid 211.5312 -287.374726)
					(end 215.273128 -289.813238)
				)
				(xy 229.073202 -289.813238) (xy 230.268018 -288.618422) (xy 230.268018 -283.154628) (xy 218.947746 -271.834356)
				(xy 218.947746 -253.910084) (xy 217.446606 -252.408944)
			)
		)
	)
	(zone
		(layer "F.Cu")
		(hatch none 0.5)
		(connect_pads
			(clearance 0)
		)
		(min_thickness 0.25)
		(keepout
			(tracks allowed)
			(vias allowed)
			(pads allowed)
			(copperpour allowed)
			(footprints not_allowed)
		)
		(placement
			(enabled no)
			(sheetname "")
		)
		(fill
			(thermal_gap 0.5)
			(thermal_bridge_width 0.5)
			(island_removal_mode 0)
		)
		(polygon
			(pts
				(xy 177.299874 -211.799932) (xy 177.299874 -220.000068) (xy 191.799972 -220.000068) (xy 191.799972 -276.800056)
				(xy 180.64988 -276.800056) (xy 180.64988 -266.800076) (xy 166.099998 -266.800076) (xy 166.099998 -276.800056)
				(xy 149.100032 -276.800056) (xy 149.100032 -266.800076) (xy 134.549896 -266.800076) (xy 134.549896 -276.800056)
				(xy 117.54993 -276.800056) (xy 117.54993 -266.800076) (xy 103.000048 -266.800076) (xy 103.000048 -276.800056)
				(xy 86.000082 -276.800056) (xy 86.000082 -266.800076) (xy 71.449946 -266.800076) (xy 71.449946 -276.800056)
				(xy 54.44998 -276.800056) (xy 54.44998 -266.800076) (xy 39.900098 -266.800076) (xy 39.900098 -276.800056)
				(xy 22.899878 -276.800056) (xy 22.899878 -266.800076) (xy 8.349996 -266.800076) (xy 8.349996 -276.800056)
				(xy 0 -276.800056) (xy 0 -211.799932)
			)
		)
	)
	(zone
		(net "GND")
		(layer "F.Cu")
		(hatch none 0.5)
		(connect_pads
			(clearance 0.5)
		)
		(min_thickness 0.25)
		(fill yes
			(thermal_gap 0.5)
			(thermal_bridge_width 0.5)
			(island_removal_mode 0)
		)
		(polygon
			(pts
				(xy 104.342946 -155.2702) (xy 103.46436 -156.148786)
				(arc
					(start 103.46436 -170.668442)
					(mid 104.98014 -172.305244)
					(end 106.128058 -174.218092)
				)
				(arc
					(start 112.395254 -174.218092)
					(mid 113.454485 -174.36331)
					(end 114.435636 -174.788068)
				)
				(arc
					(start 115.706398 -174.788068)
					(mid 116.636659 -173.382929)
					(end 117.729 -172.099732)
				)
				(xy 117.729 -167.254428) (xy 115.830096 -165.355524) (xy 114.628676 -165.355524) (xy 114.628676 -162.816286)
				(xy 114.513614 -162.701224) (xy 114.107976 -162.701224) (xy 114.107976 -162.295586) (xy 107.08259 -155.2702)
			)
		)
	)
	(zone
		(net "P5V_B_1")
		(layer "F.Cu")
		(hatch none 0.5)
		(connect_pads
			(clearance 0.5)
		)
		(min_thickness 0.25)
		(fill yes
			(thermal_gap 0.5)
			(thermal_bridge_width 0.5)
			(island_removal_mode 0)
		)
		(polygon
			(pts
				(xy 81.534 -136.779) (xy 81.28 -137.033) (xy 81.28 -139.319) (xy 81.534 -139.573) (xy 86.233 -139.573)
				(xy 86.487 -139.319) (xy 86.487 -137.033) (xy 86.233 -136.779)
			)
		)
	)
	(zone
		(layer "F.Cu")
		(hatch none 0.5)
		(connect_pads
			(clearance 0)
		)
		(min_thickness 0.25)
		(keepout
			(tracks allowed)
			(vias allowed)
			(pads allowed)
			(copperpour allowed)
			(footprints not_allowed)
		)
		(placement
			(enabled no)
			(sheetname "")
		)
		(fill
			(thermal_gap 0.5)
			(thermal_bridge_width 0.5)
			(island_removal_mode 0)
		)
		(polygon
			(pts
				(arc
					(start 462.7499 -13.999972)
					(mid 467.499954 -9.249918)
					(end 472.250008 -13.999972)
				)
				(arc
					(start 472.250008 -13.999972)
					(mid 467.499954 -18.750026)
					(end 462.7499 -13.999972)
				)
			)
		)
	)
	(zone
		(net "P5V_B_4")
		(layer "F.Cu")
		(hatch none 0.5)
		(connect_pads
			(clearance 0.5)
		)
		(min_thickness 0.25)
		(fill yes
			(thermal_gap 0.5)
			(thermal_bridge_width 0.5)
			(island_removal_mode 0)
		)
		(polygon
			(pts
				(xy 329.692 -19.05) (xy 329.438 -19.304) (xy 329.438 -21.59) (xy 329.692 -21.844) (xy 334.391 -21.844)
				(xy 334.645 -21.59) (xy 334.645 -19.304) (xy 334.391 -19.05)
			)
		)
	)
	(zone
		(net "GND")
		(layer "F.Cu")
		(hatch none 0.5)
		(connect_pads
			(clearance 0.5)
		)
		(min_thickness 0.25)
		(fill yes
			(thermal_gap 0.5)
			(thermal_bridge_width 0.5)
			(island_removal_mode 0)
		)
		(polygon
			(pts
				(xy 161.45129 -238.1123) (xy 161.21761 -238.34598) (xy 161.21761 -239.22609)
				(arc
					(start 161.444178 -239.452658)
					(mid 163.681342 -240.890344)
					(end 164.551106 -243.403374)
				)
				(arc
					(start 164.551106 -246.578374)
					(mid 164.079583 -248.478869)
					(end 162.774376 -249.93854)
				)
				(arc
					(start 162.774376 -250.401582)
					(mid 162.772911 -250.51046)
					(end 162.768534 -250.61926)
				)
				(xy 165.83025 -253.680976) (xy 166.299896 -253.680976) (xy 168.019476 -251.961396)
				(arc
					(start 168.019476 -251.10948)
					(mid 167.549953 -249.893126)
					(end 167.487092 -248.590816)
				)
				(arc
					(start 167.487092 -246.989092)
					(mid 167.635638 -245.900555)
					(end 168.070276 -244.89156)
				)
				(xy 168.070276 -242.543076) (xy 168.502076 -242.111276) (xy 175.712374 -242.111276)
				(arc
					(start 175.750982 -242.104672)
					(mid 177.300891 -241.807262)
					(end 178.849528 -242.111276)
				)
				(xy 180.240178 -242.111276) (xy 180.843936 -241.507518) (xy 180.843936 -238.76254) (xy 180.193696 -238.1123)
			)
		)
	)
	(zone
		(net "P12V_HDD21")
		(layer "F.Cu")
		(hatch none 0.5)
		(connect_pads
			(clearance 0.5)
		)
		(min_thickness 0.25)
		(fill yes
			(thermal_gap 0.5)
			(thermal_bridge_width 0.5)
			(island_removal_mode 0)
		)
		(polygon
			(pts
				(xy 429.26 -149.606) (xy 429.006 -149.86) (xy 429.006 -153.8224) (xy 428.4853 -154.3431) (xy 428.4853 -157.1371)
				(xy 427.5074 -158.115) (xy 420.878 -158.115) (xy 420.624 -158.369) (xy 420.624 -160.02) (xy 420.878 -160.274)
				(xy 424.815 -160.274) (xy 425.323 -159.766) (xy 433.07 -159.766) (xy 433.959 -158.877) (xy 433.959 -149.86)
				(xy 433.705 -149.606)
			)
		)
		(polygon
			(pts
				(xy 424.9674 -159.1564) (xy 424.7642 -159.1564) (xy 424.7642 -159.3596) (xy 424.9674 -159.3596)
			)
		)
		(polygon
			(pts
				(xy 424.1038 -159.1564) (xy 423.9006 -159.1564) (xy 423.9006 -159.3596) (xy 424.1038 -159.3596)
			)
		)
	)
	(zone
		(layer "F.Cu")
		(hatch none 0.5)
		(connect_pads
			(clearance 0)
		)
		(min_thickness 0.25)
		(keepout
			(tracks allowed)
			(vias allowed)
			(pads allowed)
			(copperpour allowed)
			(footprints not_allowed)
		)
		(placement
			(enabled no)
			(sheetname "")
		)
		(fill
			(thermal_gap 0.5)
			(thermal_bridge_width 0.5)
			(island_removal_mode 0)
		)
		(polygon
			(pts
				(xy 256.199894 -191.799972) (xy 231.199944 -191.799972) (xy 231.199944 -165.800024) (xy 256.199894 -165.800024)
			)
		)
	)
	(zone
		(net "P3V3_IN")
		(layer "F.Cu")
		(hatch none 0.5)
		(connect_pads
			(clearance 0.5)
		)
		(min_thickness 0.25)
		(fill yes
			(thermal_gap 0.5)
			(thermal_bridge_width 0.5)
			(island_removal_mode 0)
		)
		(polygon
			(pts
				(xy 297.608752 -330.525882) (xy 297.354752 -330.779882) (xy 297.354752 -332.557882) (xy 297.608752 -332.811882)
				(xy 301.926752 -332.811882) (xy 302.053752 -332.684882) (xy 302.053752 -330.652882) (xy 301.926752 -330.525882)
			)
		)
		(polygon
			(pts
				(xy 299.0596 -332.105) (xy 298.8564 -332.105) (xy 298.8564 -332.3082) (xy 299.0596 -332.3082)
			)
		)
		(polygon
			(pts
				(xy 298.45 -332.105) (xy 298.2468 -332.105) (xy 298.2468 -332.3082) (xy 298.45 -332.3082)
			)
		)
		(polygon
			(pts
				(xy 300.255686 -331.788262) (xy 300.052486 -331.788262) (xy 300.052486 -331.991462) (xy 300.255686 -331.991462)
			)
		)
		(polygon
			(pts
				(xy 299.392086 -331.788262) (xy 299.188886 -331.788262) (xy 299.188886 -331.991462) (xy 299.392086 -331.991462)
			)
		)
	)
	(zone
		(layer "F.Cu")
		(hatch none 0.5)
		(connect_pads
			(clearance 0)
		)
		(min_thickness 0.25)
		(keepout
			(tracks allowed)
			(vias allowed)
			(pads allowed)
			(copperpour allowed)
			(footprints allowed)
		)
		(placement
			(enabled no)
			(sheetname "")
		)
		(fill
			(thermal_gap 0.5)
			(thermal_bridge_width 0.5)
			(island_removal_mode 0)
		)
		(polygon
			(pts
				(xy 456.177904 -375.9962) (xy 457.168504 -375.9962) (xy 458.082904 -375.9962) (xy 458.082904 -377.2154)
				(xy 456.177904 -377.2154) (xy 456.177904 -376.7836)
			)
		)
	)
	(zone
		(net "P3V3_IN")
		(layer "F.Cu")
		(hatch none 0.5)
		(connect_pads
			(clearance 0.5)
		)
		(min_thickness 0.25)
		(fill yes
			(thermal_gap 0.5)
			(thermal_bridge_width 0.5)
			(island_removal_mode 0)
		)
		(polygon
			(pts
				(xy 282.702 -331.9018) (xy 282.575 -332.0288) (xy 282.575 -333.1718) (xy 282.770326 -333.367126)
				(xy 287.840674 -333.367126) (xy 288.036 -333.1718) (xy 288.036 -332.1558) (xy 287.782 -331.9018)
			)
		)
		(polygon
			(pts
				(xy 286.31261 -332.65618) (xy 286.10941 -332.65618) (xy 286.10941 -332.85938) (xy 286.31261 -332.85938)
			)
		)
		(polygon
			(pts
				(xy 285.70301 -332.65618) (xy 285.49981 -332.65618) (xy 285.49981 -332.85938) (xy 285.70301 -332.85938)
			)
		)
		(polygon
			(pts
				(xy 287.86201 -332.27518) (xy 287.65881 -332.27518) (xy 287.65881 -332.47838) (xy 287.86201 -332.47838)
			)
		)
		(polygon
			(pts
				(xy 286.99841 -332.27518) (xy 286.79521 -332.27518) (xy 286.79521 -332.47838) (xy 286.99841 -332.47838)
			)
		)
	)
	(zone
		(layer "F.Cu")
		(hatch none 0.5)
		(connect_pads
			(clearance 0)
		)
		(min_thickness 0.25)
		(keepout
			(tracks not_allowed)
			(vias allowed)
			(pads allowed)
			(copperpour not_allowed)
			(footprints allowed)
		)
		(placement
			(enabled no)
			(sheetname "")
		)
		(fill
			(thermal_gap 0.5)
			(thermal_bridge_width 0.5)
			(island_removal_mode 0)
		)
		(polygon
			(pts
				(arc
					(start 66.32067 -129.419604)
					(mid 65.835657 -128.93421)
					(end 65.35039 -129.41935)
				)
				(xy 65.35039 -129.7686)
				(arc
					(start 65.676526 -129.7686)
					(mid 65.735077 -129.744347)
					(end 65.75933 -129.685796)
				)
				(arc
					(start 65.75933 -129.674874)
					(mid 65.83553 -129.152706)
					(end 65.91173 -129.674874)
				)
				(xy 65.91173 -129.717292)
				(arc
					(start 65.90919 -129.719832)
					(mid 65.842795 -129.852065)
					(end 65.710562 -129.91846)
				)
				(xy 65.708022 -129.921) (xy 65.35039 -129.921) (xy 65.35039 -130.0607) (xy 65.708022 -130.0607)
				(arc
					(start 65.710562 -130.06324)
					(mid 65.842795 -130.129635)
					(end 65.90919 -130.261868)
				)
				(xy 65.91173 -130.264408)
				(arc
					(start 65.91173 -130.306826)
					(mid 65.83553 -130.828994)
					(end 65.75933 -130.306826)
				)
				(arc
					(start 65.75933 -130.295904)
					(mid 65.735077 -130.237353)
					(end 65.676526 -130.2131)
				)
				(xy 65.35039 -130.2131)
				(arc
					(start 65.35039 -130.56235)
					(mid 65.83553 -131.04749)
					(end 66.32067 -130.56235)
				)
			)
		)
	)
	(zone
		(net "P5V_B_2")
		(layer "F.Cu")
		(hatch none 0.5)
		(connect_pads
			(clearance 0.5)
		)
		(min_thickness 0.25)
		(fill yes
			(thermal_gap 0.5)
			(thermal_bridge_width 0.5)
			(island_removal_mode 0)
		)
		(polygon
			(pts
				(xy 113.1316 -22.7584) (xy 112.8776 -23.0124) (xy 112.8776 -25.2984) (xy 113.1316 -25.5524) (xy 117.8306 -25.5524)
				(xy 118.0846 -25.2984) (xy 118.0846 -23.0124) (xy 117.8306 -22.7584)
			)
		)
	)
	(zone
		(net "P12V_HDD11")
		(layer "F.Cu")
		(hatch none 0.5)
		(connect_pads
			(clearance 0.5)
		)
		(min_thickness 0.25)
		(fill yes
			(thermal_gap 0.5)
			(thermal_bridge_width 0.5)
			(island_removal_mode 0)
		)
		(polygon
			(pts
				(xy 467.36 -262.255) (xy 467.106 -262.509) (xy 467.106 -264.16) (xy 467.36 -264.414) (xy 469.519 -264.414)
				(xy 470.027 -264.922) (xy 470.027 -267.462) (xy 477.774 -275.209) (xy 486.283 -275.209) (xy 486.41 -275.082)
				(xy 486.41 -273.304) (xy 486.283 -273.177) (xy 480.314 -273.177) (xy 479.679 -272.542) (xy 478.028 -272.542)
				(xy 473.71 -268.224) (xy 473.71 -264.668) (xy 472.567 -263.525) (xy 472.567 -262.509) (xy 472.313 -262.255)
			)
		)
		(polygon
			(pts
				(xy 479.8314 -274.2184) (xy 479.6282 -274.2184) (xy 479.6282 -274.4216) (xy 479.8314 -274.4216)
			)
		)
		(polygon
			(pts
				(xy 478.9678 -274.2184) (xy 478.7646 -274.2184) (xy 478.7646 -274.4216) (xy 478.9678 -274.4216)
			)
		)
	)
	(zone
		(layer "F.Cu")
		(hatch none 0.5)
		(connect_pads
			(clearance 0)
		)
		(min_thickness 0.25)
		(keepout
			(tracks allowed)
			(vias allowed)
			(pads allowed)
			(copperpour allowed)
			(footprints allowed)
		)
		(placement
			(enabled no)
			(sheetname "")
		)
		(fill
			(thermal_gap 0.5)
			(thermal_bridge_width 0.5)
			(island_removal_mode 0)
		)
		(polygon
			(pts
				(xy 171.577 -367.411) (xy 173.355 -367.411) (xy 173.355 -370.9416) (xy 171.577 -370.9416)
			)
		)
	)
	(zone
		(layer "F.Cu")
		(hatch none 0.5)
		(connect_pads
			(clearance 0)
		)
		(min_thickness 0.25)
		(keepout
			(tracks allowed)
			(vias allowed)
			(pads allowed)
			(copperpour allowed)
			(footprints allowed)
		)
		(placement
			(enabled no)
			(sheetname "")
		)
		(fill
			(thermal_gap 0.5)
			(thermal_bridge_width 0.5)
			(island_removal_mode 0)
		)
		(polygon
			(pts
				(xy 321.124072 -374.825514) (xy 322.56349 -374.825514) (xy 322.56349 -375.905014) (xy 321.124072 -375.905014)
			)
		)
	)
	(zone
		(net "P12V_B")
		(layer "F.Cu")
		(hatch none 0.5)
		(connect_pads
			(clearance 0.5)
		)
		(min_thickness 0.25)
		(fill yes
			(thermal_gap 0.5)
			(thermal_bridge_width 0.5)
			(island_removal_mode 0)
		)
		(polygon
			(pts
				(xy 429.26 -27.432) (xy 428.752 -27.94) (xy 428.752 -31.369) (xy 429.006 -31.623) (xy 432.308 -31.623)
				(xy 432.562 -31.369) (xy 432.562 -29.337) (xy 432.689 -29.21) (xy 433.07 -29.21) (xy 433.197 -29.083)
				(xy 433.197 -27.559) (xy 433.07 -27.432)
			)
		)
		(polygon
			(pts
				(xy 432.6636 -28.4226) (xy 432.4604 -28.4226) (xy 432.4604 -28.6258) (xy 432.6636 -28.6258)
			)
		)
		(polygon
			(pts
				(xy 432.7144 -27.9908) (xy 432.5112 -27.9908) (xy 432.5112 -28.194) (xy 432.7144 -28.194)
			)
		)
	)
	(zone
		(net "GND")
		(layer "F.Cu")
		(hatch none 0.5)
		(connect_pads
			(clearance 0.5)
		)
		(min_thickness 0.25)
		(fill yes
			(thermal_gap 0.5)
			(thermal_bridge_width 0.5)
			(island_removal_mode 0)
		)
		(polygon
			(pts
				(arc
					(start 434.687726 -77.072236)
					(mid 426.048068 -80.773022)
					(end 417.014914 -78.176374)
				)
				(xy 415.285682 -78.176374) (xy 414.707324 -78.754732) (xy 414.707324 -104.141524) (xy 413.808926 -104.141524)
				(xy 411.616652 -106.333798) (xy 411.616652 -106.504486) (xy 409.509214 -106.504486) (xy 406.745694 -109.268006)
				(xy 406.745694 -110.354364) (xy 407.04262 -110.65129) (xy 411.508702 -110.65129) (xy 421.531796 -100.628196)
				(xy 435.292246 -100.628196) (xy 436.446676 -99.473766) (xy 436.446676 -77.45095) (xy 436.067962 -77.072236)
			)
		)
	)
	(zone
		(net "P12V_B")
		(layer "F.Cu")
		(hatch none 0.5)
		(connect_pads
			(clearance 0.5)
		)
		(min_thickness 0.25)
		(fill yes
			(thermal_gap 0.5)
			(thermal_bridge_width 0.5)
			(island_removal_mode 0)
		)
		(polygon
			(pts
				(xy 279.317958 -105.275888) (xy 278.892 -105.701846) (xy 278.892 -109.04093) (xy 279.317958 -109.466888)
				(xy 285.921958 -109.466888) (xy 286.175958 -109.212888) (xy 286.175958 -105.529888) (xy 285.921958 -105.275888)
			)
		)
	)
	(zone
		(net "P5V_HDD33")
		(layer "F.Cu")
		(hatch none 0.5)
		(connect_pads
			(clearance 0.5)
		)
		(min_thickness 0.25)
		(fill yes
			(thermal_gap 0.5)
			(thermal_bridge_width 0.5)
			(island_removal_mode 0)
		)
		(polygon
			(pts
				(xy 426.212 -22.733) (xy 425.958 -22.987) (xy 425.958 -33.782) (xy 424.307 -35.433) (xy 420.878 -35.433)
				(xy 420.624 -35.687) (xy 420.624 -37.338) (xy 420.878 -37.592) (xy 425.45 -37.592) (xy 426.085 -36.957)
				(xy 427.863 -36.957) (xy 428.371 -36.449) (xy 428.371 -22.987) (xy 428.117 -22.733)
			)
		)
		(polygon
			(pts
				(xy 424.9674 -36.6014) (xy 424.7642 -36.6014) (xy 424.7642 -36.8046) (xy 424.9674 -36.8046)
			)
		)
		(polygon
			(pts
				(xy 424.1038 -36.6014) (xy 423.9006 -36.6014) (xy 423.9006 -36.8046) (xy 424.1038 -36.8046)
			)
		)
	)
	(zone
		(net "P12V_HDD23")
		(layer "F.Cu")
		(hatch none 0.5)
		(connect_pads
			(clearance 0.5)
		)
		(min_thickness 0.25)
		(fill yes
			(thermal_gap 0.5)
			(thermal_bridge_width 0.5)
			(island_removal_mode 0)
		)
		(polygon
			(pts
				(xy 467.36 -147.193) (xy 467.106 -147.447) (xy 467.106 -149.098) (xy 467.36 -149.352) (xy 469.519 -149.352)
				(xy 470.027 -149.86) (xy 470.027 -152.4) (xy 477.774 -160.147) (xy 486.283 -160.147) (xy 486.41 -160.02)
				(xy 486.41 -158.242) (xy 486.283 -158.115) (xy 480.314 -158.115) (xy 479.679 -157.48) (xy 478.028 -157.48)
				(xy 473.71 -153.162) (xy 473.71 -149.606) (xy 472.567 -148.463) (xy 472.567 -147.447) (xy 472.313 -147.193)
			)
		)
		(polygon
			(pts
				(xy 479.8314 -159.1564) (xy 479.6282 -159.1564) (xy 479.6282 -159.3596) (xy 479.8314 -159.3596)
			)
		)
		(polygon
			(pts
				(xy 478.9678 -159.1564) (xy 478.7646 -159.1564) (xy 478.7646 -159.3596) (xy 478.9678 -159.3596)
			)
		)
	)
	(zone
		(layer "F.Cu")
		(hatch none 0.5)
		(connect_pads
			(clearance 0)
		)
		(min_thickness 0.25)
		(keepout
			(tracks allowed)
			(vias allowed)
			(pads allowed)
			(copperpour allowed)
			(footprints allowed)
		)
		(placement
			(enabled no)
			(sheetname "")
		)
		(fill
			(thermal_gap 0.5)
			(thermal_bridge_width 0.5)
			(island_removal_mode 0)
		)
		(polygon
			(pts
				(xy 393.089892 -249.152156) (xy 394.681202 -249.152156) (xy 394.681202 -251.060204) (xy 393.089892 -251.060204)
			)
		)
	)
	(zone
		(layer "F.Cu")
		(hatch none 0.5)
		(connect_pads
			(clearance 0)
		)
		(min_thickness 0.25)
		(keepout
			(tracks allowed)
			(vias allowed)
			(pads allowed)
			(copperpour allowed)
			(footprints not_allowed)
		)
		(placement
			(enabled no)
			(sheetname "")
		)
		(fill
			(thermal_gap 0.5)
			(thermal_bridge_width 0.5)
			(island_removal_mode 0)
		)
		(polygon
			(pts
				(arc
					(start 411.174946 -66.799968)
					(mid 425.174918 -52.799996)
					(end 439.17489 -66.799968)
				)
				(arc
					(start 439.17489 -66.799968)
					(mid 425.174918 -80.79994)
					(end 411.174946 -66.799968)
				)
			)
		)
	)
	(zone
		(net "12V_PRE_11")
		(layer "F.Cu")
		(hatch none 0.5)
		(connect_pads
			(clearance 0.5)
		)
		(min_thickness 0.25)
		(fill yes
			(thermal_gap 0.5)
			(thermal_bridge_width 0.5)
			(island_removal_mode 0)
		)
		(polygon
			(pts
				(xy 474.726 -264.795) (xy 474.599 -264.922) (xy 474.599 -268.2748) (xy 476.8723 -270.5481) (xy 480.0981 -270.5481)
				(xy 482.346 -272.796) (xy 486.283 -272.796) (xy 486.41 -272.669) (xy 486.41 -271.907) (xy 486.283 -271.78)
				(xy 482.981 -271.78) (xy 480.1108 -268.9098) (xy 477.0882 -268.9098) (xy 476.5675 -268.3891) (xy 476.5675 -265.3665)
				(xy 475.996 -264.795)
			)
		)
	)
	(zone
		(net "GND")
		(layer "F.Cu")
		(hatch none 0.5)
		(connect_pads
			(clearance 0.5)
		)
		(min_thickness 0.25)
		(fill yes
			(thermal_gap 0.5)
			(thermal_bridge_width 0.5)
			(island_removal_mode 0)
		)
		(polygon
			(pts
				(xy 205.159102 -119.726964)
				(arc
					(start 204.95006 -119.936006)
					(mid 204.883375 -120.090863)
					(end 204.81036 -120.242838)
				)
				(xy 204.81036 -120.454674) (xy 215.655652 -131.299966) (xy 215.655652 -138.91768) (xy 216.231724 -139.493752)
				(xy 217.517726 -139.493752) (xy 220.222572 -136.788906)
				(arc
					(start 220.222572 -133.274816)
					(mid 217.539948 -132.209642)
					(end 216.228422 -129.638552)
				)
				(arc
					(start 208.30921 -121.71934)
					(mid 207.182834 -120.888707)
					(end 206.402432 -119.726964)
				)
			)
		)
	)
	(zone
		(layer "F.Cu")
		(hatch none 0.5)
		(connect_pads
			(clearance 0)
		)
		(min_thickness 0.25)
		(keepout
			(tracks allowed)
			(vias allowed)
			(pads allowed)
			(copperpour allowed)
			(footprints not_allowed)
		)
		(placement
			(enabled no)
			(sheetname "")
		)
		(fill
			(thermal_gap 0.5)
			(thermal_bridge_width 0.5)
			(island_removal_mode 0)
		)
		(polygon
			(pts
				(xy 177.299874 -194.00012) (xy 177.299874 -211.799932) (xy 0 -211.799932) (xy 0 -161.800032) (xy 8.349996 -161.800032)
				(xy 8.349996 -151.800052) (xy 22.899878 -151.800052) (xy 22.899878 -161.800032) (xy 39.900098 -161.800032)
				(xy 39.900098 -151.800052) (xy 54.44998 -151.800052) (xy 54.44998 -161.800032) (xy 71.449946 -161.800032)
				(xy 71.449946 -151.800052) (xy 86.000082 -151.800052) (xy 86.000082 -161.800032) (xy 103.000048 -161.800032)
				(xy 103.000048 -151.800052) (xy 117.54993 -151.800052) (xy 117.54993 -161.800032) (xy 134.549896 -161.800032)
				(xy 134.549896 -151.800052) (xy 149.100032 -151.800052) (xy 149.100032 -161.800032) (xy 166.099998 -161.800032)
				(xy 166.099998 -151.800052) (xy 180.64988 -151.800052) (xy 180.64988 -161.800032) (xy 191.799972 -161.800032)
				(xy 191.799972 -194.00012)
			)
		)
	)
	(zone
		(layer "F.Cu")
		(hatch none 0.5)
		(connect_pads
			(clearance 0)
		)
		(min_thickness 0.25)
		(keepout
			(tracks not_allowed)
			(vias allowed)
			(pads allowed)
			(copperpour not_allowed)
			(footprints allowed)
		)
		(placement
			(enabled no)
			(sheetname "")
		)
		(fill
			(thermal_gap 0.5)
			(thermal_bridge_width 0.5)
			(island_removal_mode 0)
		)
		(polygon
			(pts
				(arc
					(start 418.724842 -248.115328)
					(mid 418.239829 -247.629934)
					(end 417.754562 -248.115074)
				)
				(arc
					(start 417.754562 -249.385074)
					(mid 418.239702 -249.870214)
					(end 418.724842 -249.385074)
				)
				(xy 418.724842 -248.972324)
				(arc
					(start 418.366702 -248.972324)
					(mid 418.330781 -248.987203)
					(end 418.315902 -249.023124)
				)
				(arc
					(start 418.315902 -249.12955)
					(mid 418.239702 -249.651718)
					(end 418.163502 -249.12955)
				)
				(xy 418.163502 -248.991628)
				(arc
					(start 418.16655 -248.98858)
					(mid 418.223081 -248.879503)
					(end 418.332158 -248.822972)
				)
				(xy 418.335206 -248.819924) (xy 418.724842 -248.819924) (xy 418.724842 -248.680224) (xy 418.335206 -248.680224)
				(arc
					(start 418.332158 -248.677176)
					(mid 418.223081 -248.620645)
					(end 418.16655 -248.511568)
				)
				(xy 418.163502 -248.50852)
				(arc
					(start 418.163502 -248.370598)
					(mid 418.239702 -247.84843)
					(end 418.315902 -248.370598)
				)
				(arc
					(start 418.315902 -248.477024)
					(mid 418.330781 -248.512945)
					(end 418.366702 -248.527824)
				)
				(xy 418.724842 -248.527824)
			)
		)
	)
	(zone
		(net "5V_PRE_23")
		(layer "F.Cu")
		(hatch none 0.5)
		(connect_pads
			(clearance 0.5)
		)
		(min_thickness 0.25)
		(fill yes
			(thermal_gap 0.5)
			(thermal_bridge_width 0.5)
			(island_removal_mode 0)
		)
		(polygon
			(pts
				(xy 478.05848 -145.962624) (xy 477.90608 -146.115024) (xy 477.90608 -147.512024) (xy 478.49028 -148.096224)
				(xy 479.76028 -148.096224) (xy 481.84308 -150.179024) (xy 486.28808 -150.179024) (xy 486.41508 -150.052024)
				(xy 486.41508 -149.290024) (xy 486.28808 -149.163024) (xy 483.26548 -149.163024) (xy 480.06508 -145.962624)
			)
		)
	)
	(zone
		(layer "F.Cu")
		(hatch none 0.5)
		(connect_pads
			(clearance 0)
		)
		(min_thickness 0.25)
		(keepout
			(tracks allowed)
			(vias allowed)
			(pads allowed)
			(copperpour allowed)
			(footprints not_allowed)
		)
		(placement
			(enabled no)
			(sheetname "")
		)
		(fill
			(thermal_gap 0.5)
			(thermal_bridge_width 0.5)
			(island_removal_mode 0)
		)
		(polygon
			(pts
				(arc
					(start 472.250008 -13.999972)
					(mid 467.499954 -18.750026)
					(end 462.7499 -13.999972)
				)
				(arc
					(start 462.7499 -13.999972)
					(mid 467.499954 -9.249918)
					(end 472.250008 -13.999972)
				)
			)
		)
	)
	(zone
		(net "P12V_HDD32")
		(layer "F.Cu")
		(hatch none 0.5)
		(connect_pads
			(clearance 0.5)
		)
		(min_thickness 0.25)
		(fill yes
			(thermal_gap 0.5)
			(thermal_bridge_width 0.5)
			(island_removal_mode 0)
		)
		(polygon
			(pts
				(xy 397.7132 -30.8356) (xy 397.51 -31.0388) (xy 397.51 -38.862) (xy 396.9893 -39.3827) (xy 396.9893 -41.7957)
				(xy 395.732 -43.053) (xy 389.382 -43.053) (xy 389.128 -43.307) (xy 389.128 -44.958) (xy 389.382 -45.212)
				(xy 393.319 -45.212) (xy 393.827 -44.704) (xy 399.4658 -44.704) (xy 400.5834 -43.5864) (xy 400.5834 -31.2674)
				(xy 400.1516 -30.8356)
			)
		)
		(polygon
			(pts
				(xy 393.4714 -44.0944) (xy 393.2682 -44.0944) (xy 393.2682 -44.2976) (xy 393.4714 -44.2976)
			)
		)
		(polygon
			(pts
				(xy 392.6078 -44.0944) (xy 392.4046 -44.0944) (xy 392.4046 -44.2976) (xy 392.6078 -44.2976)
			)
		)
	)
	(zone
		(net "P12V_B_1_VIN_U31")
		(layer "F.Cu")
		(hatch none 0.5)
		(connect_pads
			(clearance 0.5)
		)
		(min_thickness 0.25)
		(fill yes
			(thermal_gap 0.5)
			(thermal_bridge_width 0.5)
			(island_removal_mode 0)
		)
		(polygon
			(pts
				(xy 17.081754 -221.246192) (xy 16.023336 -222.30461) (xy 16.023336 -224.622106) (xy 16.224504 -224.823274)
				(xy 18.903442 -224.823274) (xy 18.984722 -224.741994) (xy 18.984722 -221.322646) (xy 18.908268 -221.246192)
			)
		)
	)
	(zone
		(layer "F.Cu")
		(hatch none 0.5)
		(connect_pads
			(clearance 0)
		)
		(min_thickness 0.25)
		(keepout
			(tracks not_allowed)
			(vias allowed)
			(pads allowed)
			(copperpour not_allowed)
			(footprints allowed)
		)
		(placement
			(enabled no)
			(sheetname "")
		)
		(fill
			(thermal_gap 0.5)
			(thermal_bridge_width 0.5)
			(island_removal_mode 0)
		)
		(polygon
			(pts
				(arc
					(start 293.200074 -94.000066)
					(mid 300.20006 -87.00008)
					(end 307.200046 -94.000066)
				)
				(arc
					(start 307.200046 -100.000054)
					(mid 300.20006 -107.00004)
					(end 293.200074 -100.000054)
				)
			)
		)
	)
	(zone
		(layer "F.Cu")
		(hatch none 0.5)
		(connect_pads
			(clearance 0)
		)
		(min_thickness 0.25)
		(keepout
			(tracks allowed)
			(vias allowed)
			(pads allowed)
			(copperpour allowed)
			(footprints not_allowed)
		)
		(placement
			(enabled no)
			(sheetname "")
		)
		(fill
			(thermal_gap 0.5)
			(thermal_bridge_width 0.5)
			(island_removal_mode 0)
		)
		(polygon
			(pts
				(arc
					(start 111.849916 -23.999952)
					(mid 107.100116 -28.749752)
					(end 102.350062 -23.999952)
				)
				(arc
					(start 102.350062 -23.999952)
					(mid 107.100116 -19.249898)
					(end 111.849916 -23.999952)
				)
			)
		)
	)
	(zone
		(net "MB3_P12V_IN_R")
		(layer "F.Cu")
		(hatch none 0.5)
		(connect_pads
			(clearance 0.5)
		)
		(min_thickness 0.25)
		(fill yes
			(thermal_gap 0.5)
			(thermal_bridge_width 0.5)
			(island_removal_mode 0)
		)
		(polygon
			(pts
				(xy 248.7676 -329.9206) (xy 247.7262 -330.962) (xy 247.7262 -343.2302) (xy 247.8278 -343.3318) (xy 250.6726 -343.3318)
				(xy 251.079 -343.7382) (xy 251.079 -345.9988) (xy 250.677172 -346.400628) (xy 250.677172 -352.721164)
				(xy 250.679458 -352.72345) (xy 250.679458 -353.910646) (xy 251.164344 -354.395532) (xy 258.228846 -354.395532)
				(xy 260.024372 -352.600006) (xy 260.024372 -331.41158) (xy 260.013196 -331.400404) (xy 260.0452 -331.3684)
				(xy 260.0452 -330.3778) (xy 259.588 -329.9206)
			)
		)
	)
	(zone
		(layer "F.Cu")
		(hatch none 0.5)
		(connect_pads
			(clearance 0)
		)
		(min_thickness 0.25)
		(keepout
			(tracks allowed)
			(vias allowed)
			(pads allowed)
			(copperpour allowed)
			(footprints not_allowed)
		)
		(placement
			(enabled no)
			(sheetname "")
		)
		(fill
			(thermal_gap 0.5)
			(thermal_bridge_width 0.5)
			(island_removal_mode 0)
		)
		(polygon
			(pts
				(xy 291.599874 -110.000034) (xy 298.200064 -110.000034) (xy 298.200064 -234.00004) (xy 291.599874 -234.00004)
			)
		)
	)
	(zone
		(net "P12V_B")
		(layer "F.Cu")
		(hatch none 0.5)
		(connect_pads
			(clearance 0.5)
		)
		(min_thickness 0.25)
		(fill yes
			(thermal_gap 0.5)
			(thermal_bridge_width 0.5)
			(island_removal_mode 0)
		)
		(polygon
			(pts
				(xy 366.141 -142.494) (xy 365.633 -143.002) (xy 365.633 -146.431) (xy 365.887 -146.685) (xy 369.189 -146.685)
				(xy 369.443 -146.431) (xy 369.443 -144.399) (xy 369.57 -144.272) (xy 369.951 -144.272) (xy 370.078 -144.145)
				(xy 370.078 -142.621) (xy 369.951 -142.494)
			)
		)
		(polygon
			(pts
				(xy 369.5446 -143.4846) (xy 369.3414 -143.4846) (xy 369.3414 -143.6878) (xy 369.5446 -143.6878)
			)
		)
		(polygon
			(pts
				(xy 369.5954 -143.0528) (xy 369.3922 -143.0528) (xy 369.3922 -143.256) (xy 369.5954 -143.256)
			)
		)
	)
	(zone
		(layer "F.Cu")
		(hatch none 0.5)
		(connect_pads
			(clearance 0)
		)
		(min_thickness 0.25)
		(keepout
			(tracks allowed)
			(vias allowed)
			(pads allowed)
			(copperpour allowed)
			(footprints allowed)
		)
		(placement
			(enabled no)
			(sheetname "")
		)
		(fill
			(thermal_gap 0.5)
			(thermal_bridge_width 0.5)
			(island_removal_mode 0)
		)
		(polygon
			(pts
				(xy 253.98476 -372.544086) (xy 253.98476 -374.017286) (xy 251.563124 -374.017286) (xy 251.563124 -372.544086)
			)
		)
	)
	(zone
		(net "P5V_B_1")
		(layer "F.Cu")
		(hatch none 0.5)
		(connect_pads
			(clearance 0.5)
		)
		(min_thickness 0.25)
		(fill yes
			(thermal_gap 0.5)
			(thermal_bridge_width 0.5)
			(island_removal_mode 0)
		)
		(polygon
			(pts
				(xy 18.415 -251.841) (xy 18.161 -252.095) (xy 18.161 -254.381) (xy 18.415 -254.635) (xy 23.114 -254.635)
				(xy 23.368 -254.381) (xy 23.368 -252.095) (xy 23.114 -251.841)
			)
		)
	)
	(zone
		(layer "F.Cu")
		(hatch none 0.5)
		(connect_pads
			(clearance 0)
		)
		(min_thickness 0.25)
		(keepout
			(tracks allowed)
			(vias allowed)
			(pads allowed)
			(copperpour allowed)
			(footprints allowed)
		)
		(placement
			(enabled no)
			(sheetname "")
		)
		(fill
			(thermal_gap 0.5)
			(thermal_bridge_width 0.5)
			(island_removal_mode 0)
		)
		(polygon
			(pts
				(xy 257.937 -222.885) (xy 257.937 -224.4344) (xy 254.508 -224.4344) (xy 254.508 -222.885)
			)
		)
	)
	(zone
		(net "5V_PRE_14")
		(layer "F.Cu")
		(hatch none 0.5)
		(connect_pads
			(clearance 0.5)
		)
		(min_thickness 0.25)
		(fill yes
			(thermal_gap 0.5)
			(thermal_bridge_width 0.5)
			(island_removal_mode 0)
		)
		(polygon
			(pts
				(xy 86.058502 -145.962624) (xy 85.906102 -146.115024) (xy 85.906102 -147.512024) (xy 86.490302 -148.096224)
				(xy 87.760302 -148.096224) (xy 89.843102 -150.179024) (xy 94.288102 -150.179024) (xy 94.415102 -150.052024)
				(xy 94.415102 -149.290024) (xy 94.288102 -149.163024) (xy 91.265502 -149.163024) (xy 88.065102 -145.962624)
			)
		)
	)
	(zone
		(net "P12V_B")
		(layer "F.Cu")
		(hatch none 0.5)
		(connect_pads
			(clearance 0.5)
		)
		(min_thickness 0.25)
		(fill yes
			(thermal_gap 0.5)
			(thermal_bridge_width 0.5)
			(island_removal_mode 0)
		)
		(polygon
			(pts
				(xy 202.5396 -145.669) (xy 202.2856 -145.923) (xy 202.2856 -149.606) (xy 202.5396 -149.86) (xy 209.1436 -149.86)
				(xy 209.3976 -149.606) (xy 209.3976 -145.923) (xy 209.1436 -145.669)
			)
		)
	)
	(zone
		(layer "F.Cu")
		(hatch none 0.5)
		(connect_pads
			(clearance 0)
		)
		(min_thickness 0.25)
		(keepout
			(tracks allowed)
			(vias allowed)
			(pads allowed)
			(copperpour allowed)
			(footprints not_allowed)
		)
		(placement
			(enabled no)
			(sheetname "")
		)
		(fill
			(thermal_gap 0.5)
			(thermal_bridge_width 0.5)
			(island_removal_mode 0)
		)
		(polygon
			(pts
				(xy 286.429958 -100.210112) (xy 278.809958 -100.210112) (xy 278.809958 -109.579918) (xy 286.429958 -109.579918)
			)
		)
	)
	(zone
		(net "P12V_B")
		(layer "F.Cu")
		(hatch none 0.5)
		(connect_pads
			(clearance 0.5)
		)
		(min_thickness 0.25)
		(fill yes
			(thermal_gap 0.5)
			(thermal_bridge_width 0.5)
			(island_removal_mode 0)
		)
		(polygon
			(pts
				(xy 77.343 -140.081) (xy 76.327 -141.097) (xy 75.692 -141.097) (xy 75.311 -141.478) (xy 75.311 -144.018)
				(xy 75.565 -144.272) (xy 78.867 -144.272) (xy 79.121 -144.018) (xy 79.121 -141.732) (xy 78.486 -141.097)
				(xy 78.105 -141.097) (xy 77.851 -140.843) (xy 77.851 -140.208) (xy 77.724 -140.081)
			)
		)
		(polygon
			(pts
				(xy 77.3176 -140.6652) (xy 77.1144 -140.6652) (xy 77.1144 -140.8684) (xy 77.3176 -140.8684)
			)
		)
	)
	(zone
		(layer "F.Cu")
		(hatch none 0.5)
		(connect_pads
			(clearance 0)
		)
		(min_thickness 0.25)
		(keepout
			(tracks not_allowed)
			(vias allowed)
			(pads allowed)
			(copperpour not_allowed)
			(footprints allowed)
		)
		(placement
			(enabled no)
			(sheetname "")
		)
		(fill
			(thermal_gap 0.5)
			(thermal_bridge_width 0.5)
			(island_removal_mode 0)
		)
		(polygon
			(pts
				(arc
					(start 32.994092 -133.11505)
					(mid 32.508952 -132.62991)
					(end 32.023812 -133.11505)
				)
				(xy 32.023812 -133.5278)
				(arc
					(start 32.381952 -133.5278)
					(mid 32.417873 -133.512921)
					(end 32.432752 -133.477)
				)
				(arc
					(start 32.432752 -133.370574)
					(mid 32.508952 -132.848406)
					(end 32.585152 -133.370574)
				)
				(xy 32.585152 -133.508496)
				(arc
					(start 32.582104 -133.511544)
					(mid 32.525573 -133.620621)
					(end 32.416496 -133.677152)
				)
				(xy 32.413448 -133.6802) (xy 32.023812 -133.6802) (xy 32.023812 -133.8199) (xy 32.413448 -133.8199)
				(arc
					(start 32.416496 -133.822948)
					(mid 32.525573 -133.879479)
					(end 32.582104 -133.988556)
				)
				(xy 32.585152 -133.991604)
				(arc
					(start 32.585152 -134.129526)
					(mid 32.508952 -134.651694)
					(end 32.432752 -134.129526)
				)
				(arc
					(start 32.432752 -134.0231)
					(mid 32.417873 -133.987179)
					(end 32.381952 -133.9723)
				)
				(xy 32.023812 -133.9723)
				(arc
					(start 32.023812 -134.384796)
					(mid 32.508825 -134.87019)
					(end 32.994092 -134.38505)
				)
			)
		)
	)
	(zone
		(net "5V_PRE_15")
		(layer "F.Cu")
		(hatch none 0.5)
		(connect_pads
			(clearance 0.5)
		)
		(min_thickness 0.25)
		(fill yes
			(thermal_gap 0.5)
			(thermal_bridge_width 0.5)
			(island_removal_mode 0)
		)
		(polygon
			(pts
				(xy 117.60835 -145.962624) (xy 117.45595 -146.115024) (xy 117.45595 -147.512024) (xy 118.04015 -148.096224)
				(xy 119.31015 -148.096224) (xy 121.39295 -150.179024) (xy 125.83795 -150.179024) (xy 125.96495 -150.052024)
				(xy 125.96495 -149.290024) (xy 125.83795 -149.163024) (xy 122.81535 -149.163024) (xy 119.61495 -145.962624)
			)
		)
	)
	(zone
		(net "5V_PRE_31")
		(layer "F.Cu")
		(hatch none 0.5)
		(connect_pads
			(clearance 0.5)
		)
		(min_thickness 0.25)
		(fill yes
			(thermal_gap 0.5)
			(thermal_bridge_width 0.5)
			(island_removal_mode 0)
		)
		(polygon
			(pts
				(xy 360.934 -30.988) (xy 360.68 -31.242) (xy 360.68 -33.782) (xy 360.299 -34.163) (xy 357.759 -34.163)
				(xy 357.505 -34.417) (xy 357.505 -34.798) (xy 357.759 -35.052) (xy 361.061 -35.052) (xy 362.331 -33.782)
				(xy 362.331 -31.242) (xy 362.077 -30.988)
			)
		)
	)
	(zone
		(layer "F.Cu")
		(hatch none 0.5)
		(connect_pads
			(clearance 0)
		)
		(min_thickness 0.25)
		(keepout
			(tracks allowed)
			(vias allowed)
			(pads allowed)
			(copperpour allowed)
			(footprints allowed)
		)
		(placement
			(enabled no)
			(sheetname "")
		)
		(fill
			(thermal_gap 0.5)
			(thermal_bridge_width 0.5)
			(island_removal_mode 0)
		)
		(polygon
			(pts
				(xy 329.827636 -249.025918) (xy 331.418946 -249.025918) (xy 331.418946 -250.933966) (xy 329.827636 -250.933966)
			)
		)
	)
	(zone
		(net "GND")
		(layer "F.Cu")
		(hatch none 0.5)
		(connect_pads
			(clearance 0.5)
		)
		(min_thickness 0.25)
		(fill yes
			(thermal_gap 0.5)
			(thermal_bridge_width 0.5)
			(island_removal_mode 0)
		)
		(polygon
			(pts
				(xy 306.54625 -333.065882) (xy 306.367688 -333.244444) (xy 306.367688 -335.714594) (xy 306.538122 -335.885028)
				(xy 314.01893 -335.885028) (xy 314.171076 -335.732882) (xy 314.171076 -333.573882) (xy 313.663076 -333.065882)
			)
		)
		(polygon
			(pts
				(xy 308.643782 -334.021176) (xy 308.440582 -334.021176) (xy 308.440582 -334.224376) (xy 308.643782 -334.224376)
			)
		)
		(polygon
			(pts
				(xy 307.780182 -334.021176) (xy 307.576982 -334.021176) (xy 307.576982 -334.224376) (xy 307.780182 -334.224376)
			)
		)
		(polygon
			(pts
				(xy 307.475382 -333.640176) (xy 307.272182 -333.640176) (xy 307.272182 -333.843376) (xy 307.475382 -333.843376)
			)
		)
		(polygon
			(pts
				(xy 306.865782 -333.640176) (xy 306.662582 -333.640176) (xy 306.662582 -333.843376) (xy 306.865782 -333.843376)
			)
		)
	)
	(zone
		(net "P5V_HDD12")
		(layer "F.Cu")
		(hatch none 0.5)
		(connect_pads
			(clearance 0.5)
		)
		(min_thickness 0.25)
		(fill yes
			(thermal_gap 0.5)
			(thermal_bridge_width 0.5)
			(island_removal_mode 0)
		)
		(polygon
			(pts
				(xy 19.685 -142.621) (xy 19.431 -142.875) (xy 19.431 -145.161) (xy 19.685 -145.415) (xy 19.685 -147.447)
				(xy 20.447 -148.209) (xy 20.447 -149.110954) (xy 20.688046 -149.352) (xy 21.209 -149.352) (xy 24.384 -152.527)
				(xy 31.242 -152.527) (xy 31.369 -152.4) (xy 31.369 -150.622) (xy 31.242 -150.495) (xy 26.162 -150.495)
				(xy 24.257 -148.59) (xy 23.368 -148.59) (xy 22.479 -147.701) (xy 22.479 -145.161) (xy 23.114 -144.526)
				(xy 23.114 -142.875) (xy 22.86 -142.621)
			)
		)
		(polygon
			(pts
				(xy 21.4122 -148.1836) (xy 21.209 -148.1836) (xy 21.209 -148.3868) (xy 21.4122 -148.3868)
			)
		)
	)
	(zone
		(net "GND")
		(layer "F.Cu")
		(hatch none 0.5)
		(connect_pads
			(clearance 0.5)
		)
		(min_thickness 0.25)
		(fill yes
			(thermal_gap 0.5)
			(thermal_bridge_width 0.5)
			(island_removal_mode 0)
		)
		(polygon
			(pts
				(xy 58.375042 -358.70515) (xy 58.032904 -359.047288) (xy 58.032904 -362.279692) (xy 57.371996 -362.9406)
				(xy 57.371996 -364.4646) (xy 57.524396 -364.617) (xy 60.877196 -364.617) (xy 61.258196 -364.236)
				(xy 61.258196 -359.285032) (xy 60.678314 -358.70515)
			)
		)
		(polygon
			(pts
				(xy 58.05297 -363.836966) (xy 57.84977 -363.836966) (xy 57.84977 -364.040166) (xy 58.05297 -364.040166)
			)
		)
		(polygon
			(pts
				(xy 58.489596 -363.5502) (xy 58.286396 -363.5502) (xy 58.286396 -363.7534) (xy 58.489596 -363.7534)
			)
		)
		(polygon
			(pts
				(xy 58.489596 -362.6866) (xy 58.286396 -362.6866) (xy 58.286396 -362.8898) (xy 58.489596 -362.8898)
			)
		)
	)
	(zone
		(layer "F.Cu")
		(hatch none 0.5)
		(connect_pads
			(clearance 0)
		)
		(min_thickness 0.25)
		(keepout
			(tracks allowed)
			(vias allowed)
			(pads allowed)
			(copperpour allowed)
			(footprints allowed)
		)
		(placement
			(enabled no)
			(sheetname "")
		)
		(fill
			(thermal_gap 0.5)
			(thermal_bridge_width 0.5)
			(island_removal_mode 0)
		)
		(polygon
			(pts
				(xy 251.1806 -212.0392) (xy 251.7902 -212.0392) (xy 251.9426 -211.8868) (xy 251.9426 -210.5152)
				(xy 251.7648 -210.3374) (xy 251.2314 -210.3374) (xy 251.0282 -210.5406) (xy 251.0282 -211.8868)
			)
		)
	)
	(zone
		(net "GND")
		(layer "F.Cu")
		(hatch none 0.5)
		(connect_pads
			(clearance 0.5)
		)
		(min_thickness 0.25)
		(fill yes
			(thermal_gap 0.5)
			(thermal_bridge_width 0.5)
			(island_removal_mode 0)
		)
		(polygon
			(pts
				(xy 17.705832 -120.675908) (xy 8.73506 -129.646934) (xy 8.73506 -138.212068) (xy 9.141968 -138.618976)
				(xy 9.662414 -138.618976) (xy 10.285476 -137.995914)
				(arc
					(start 10.285476 -134.069582)
					(mid 9.667883 -130.210215)
					(end 12.571476 -127.593852)
				)
				(xy 12.571476 -127.125476) (xy 14.324076 -127.125476) (xy 14.324076 -127.049276)
				(arc
					(start 17.931638 -127.049276)
					(mid 19.582352 -126.694518)
					(end 21.237448 -127.028194)
				)
				(xy 21.329142 -127.049276) (xy 22.505924 -127.049276) (xy 23.093934 -126.461266) (xy 23.093934 -121.321576)
				(xy 22.448266 -120.675908)
			)
		)
	)
	(zone
		(layer "F.Cu")
		(hatch none 0.5)
		(connect_pads
			(clearance 0)
		)
		(min_thickness 0.25)
		(keepout
			(tracks allowed)
			(vias allowed)
			(pads allowed)
			(copperpour allowed)
			(footprints not_allowed)
		)
		(placement
			(enabled no)
			(sheetname "")
		)
		(fill
			(thermal_gap 0.5)
			(thermal_bridge_width 0.5)
			(island_removal_mode 0)
		)
		(polygon
			(pts
				(xy 312.699908 -234.00004) (xy 287.699958 -234.00004) (xy 287.699958 -259.999988) (xy 312.699908 -259.999988)
			)
		)
	)
	(zone
		(net "P5V_HDD14")
		(layer "F.Cu")
		(hatch none 0.5)
		(connect_pads
			(clearance 0.5)
		)
		(min_thickness 0.25)
		(fill yes
			(thermal_gap 0.5)
			(thermal_bridge_width 0.5)
			(island_removal_mode 0)
		)
		(polygon
			(pts
				(xy 82.804 -142.621) (xy 82.55 -142.875) (xy 82.55 -145.161) (xy 82.804 -145.415) (xy 82.804 -147.447)
				(xy 83.566 -148.209) (xy 83.566 -148.971) (xy 84.0232 -149.4282) (xy 84.4042 -149.4282) (xy 87.503 -152.527)
				(xy 94.361 -152.527) (xy 94.488 -152.4) (xy 94.488 -150.622) (xy 94.361 -150.495) (xy 89.281 -150.495)
				(xy 87.376 -148.59) (xy 86.487 -148.59) (xy 85.598 -147.701) (xy 85.598 -145.161) (xy 86.233 -144.526)
				(xy 86.233 -142.875) (xy 85.979 -142.621)
			)
		)
		(polygon
			(pts
				(xy 84.582 -149.0472) (xy 84.3788 -149.0472) (xy 84.3788 -149.2504) (xy 84.582 -149.2504)
			)
		)
		(polygon
			(pts
				(xy 84.582 -148.1836) (xy 84.3788 -148.1836) (xy 84.3788 -148.3868) (xy 84.582 -148.3868)
			)
		)
	)
	(zone
		(net "GND")
		(layer "F.Cu")
		(hatch none 0.5)
		(connect_pads
			(clearance 0.5)
		)
		(min_thickness 0.25)
		(fill yes
			(thermal_gap 0.5)
			(thermal_bridge_width 0.5)
			(island_removal_mode 0)
		)
		(polygon
			(pts
				(xy 341.522304 -44.866306) (xy 338.012024 -48.376586) (xy 338.012024 -50.433224)
				(arc
					(start 335.897474 -50.433224)
					(mid 334.760814 -51.009432)
					(end 333.502 -51.207924)
				)
				(xy 332.172056 -51.207924) (xy 331.691488 -51.688492) (xy 331.691488 -52.6034)
				(arc
					(start 332.170532 -53.082444)
					(mid 336.348504 -54.585177)
					(end 339.57133 -57.639204)
				)
				(xy 340.15172 -57.639204) (xy 342.71204 -55.078884)
				(arc
					(start 342.71204 -49.56048)
					(mid 342.467452 -48.1584)
					(end 342.71204 -46.75632)
				)
				(xy 342.71204 -45.503338) (xy 342.075008 -44.866306)
			)
		)
	)
	(zone
		(net "5V_PRE_11")
		(layer "F.Cu")
		(hatch none 0.5)
		(connect_pads
			(clearance 0.5)
		)
		(min_thickness 0.25)
		(fill yes
			(thermal_gap 0.5)
			(thermal_bridge_width 0.5)
			(island_removal_mode 0)
		)
		(polygon
			(pts
				(xy 478.05848 -260.962648) (xy 477.90608 -261.115048) (xy 477.90608 -262.512048) (xy 478.49028 -263.096248)
				(xy 479.76028 -263.096248) (xy 481.84308 -265.179048) (xy 486.28808 -265.179048) (xy 486.41508 -265.052048)
				(xy 486.41508 -264.290048) (xy 486.28808 -264.163048) (xy 483.26548 -264.163048) (xy 480.06508 -260.962648)
			)
		)
	)
	(zone
		(net "P12V_HDD8")
		(layer "F.Cu")
		(hatch none 0.5)
		(connect_pads
			(clearance 0.5)
		)
		(min_thickness 0.25)
		(fill yes
			(thermal_gap 0.5)
			(thermal_bridge_width 0.5)
			(island_removal_mode 0)
		)
		(polygon
			(pts
				(xy 397.764 -264.541) (xy 397.51 -264.795) (xy 397.51 -268.859) (xy 397.002 -269.367) (xy 397.002 -271.8054)
				(xy 395.7574 -273.05) (xy 389.382 -273.05) (xy 389.128 -273.304) (xy 389.128 -274.955) (xy 389.382 -275.209)
				(xy 393.319 -275.209) (xy 393.827 -274.701) (xy 401.574 -274.701) (xy 402.463 -273.812) (xy 402.463 -264.795)
				(xy 402.209 -264.541)
			)
		)
		(polygon
			(pts
				(xy 393.4714 -274.0914) (xy 393.2682 -274.0914) (xy 393.2682 -274.2946) (xy 393.4714 -274.2946)
			)
		)
		(polygon
			(pts
				(xy 392.6078 -274.0914) (xy 392.4046 -274.0914) (xy 392.4046 -274.2946) (xy 392.6078 -274.2946)
			)
		)
	)
	(zone
		(layer "F.Cu")
		(hatch none 0.5)
		(connect_pads
			(clearance 0)
		)
		(min_thickness 0.25)
		(keepout
			(tracks not_allowed)
			(vias allowed)
			(pads allowed)
			(copperpour not_allowed)
			(footprints allowed)
		)
		(placement
			(enabled no)
			(sheetname "")
		)
		(fill
			(thermal_gap 0.5)
			(thermal_bridge_width 0.5)
			(island_removal_mode 0)
		)
		(polygon
			(pts
				(arc
					(start 190.744094 -18.11528)
					(mid 190.259081 -17.629886)
					(end 189.773814 -18.115026)
				)
				(xy 189.773814 -18.527776)
				(arc
					(start 190.131954 -18.527776)
					(mid 190.167875 -18.512897)
					(end 190.182754 -18.476976)
				)
				(arc
					(start 190.182754 -18.37055)
					(mid 190.258954 -17.848382)
					(end 190.335154 -18.37055)
				)
				(xy 190.335154 -18.508472)
				(arc
					(start 190.332106 -18.51152)
					(mid 190.275575 -18.620597)
					(end 190.166498 -18.677128)
				)
				(xy 190.16345 -18.680176) (xy 189.773814 -18.680176) (xy 189.773814 -18.819876) (xy 190.16345 -18.819876)
				(arc
					(start 190.166498 -18.822924)
					(mid 190.275575 -18.879455)
					(end 190.332106 -18.988532)
				)
				(xy 190.335154 -18.99158)
				(arc
					(start 190.335154 -19.129502)
					(mid 190.258954 -19.65167)
					(end 190.182754 -19.129502)
				)
				(arc
					(start 190.182754 -19.023076)
					(mid 190.167875 -18.987155)
					(end 190.131954 -18.972276)
				)
				(xy 189.773814 -18.972276)
				(arc
					(start 189.773814 -19.385026)
					(mid 190.258954 -19.870166)
					(end 190.744094 -19.385026)
				)
			)
		)
	)
	(zone
		(layer "F.Cu")
		(hatch none 0.5)
		(connect_pads
			(clearance 0)
		)
		(min_thickness 0.25)
		(keepout
			(tracks allowed)
			(vias allowed)
			(pads allowed)
			(copperpour allowed)
			(footprints allowed)
		)
		(placement
			(enabled no)
			(sheetname "")
		)
		(fill
			(thermal_gap 0.5)
			(thermal_bridge_width 0.5)
			(island_removal_mode 0)
		)
		(polygon
			(pts
				(xy 35.121596 -360.4006) (xy 37.026596 -360.4006) (xy 37.026596 -362.6866) (xy 35.121596 -362.6866)
			)
		)
	)
	(zone
		(net "P5V_HDD30")
		(layer "F.Cu")
		(hatch none 0.5)
		(connect_pads
			(clearance 0.5)
		)
		(min_thickness 0.25)
		(fill yes
			(thermal_gap 0.5)
			(thermal_bridge_width 0.5)
			(island_removal_mode 0)
		)
		(polygon
			(pts
				(xy 331.216 -24.765) (xy 330.708 -25.273) (xy 330.708 -30.607) (xy 331.343 -31.242) (xy 331.343 -33.782)
				(xy 329.692 -35.433) (xy 326.263 -35.433) (xy 326.009 -35.687) (xy 326.009 -37.338) (xy 326.263 -37.592)
				(xy 330.835 -37.592) (xy 331.47 -36.957) (xy 333.248 -36.957) (xy 333.756 -36.449) (xy 333.756 -27.559)
				(xy 334.899 -26.416) (xy 334.899 -25.019) (xy 334.645 -24.765)
			)
		)
		(polygon
			(pts
				(xy 330.3524 -36.6014) (xy 330.1492 -36.6014) (xy 330.1492 -36.8046) (xy 330.3524 -36.8046)
			)
		)
		(polygon
			(pts
				(xy 329.4888 -36.6014) (xy 329.2856 -36.6014) (xy 329.2856 -36.8046) (xy 329.4888 -36.8046)
			)
		)
	)
	(zone
		(layer "F.Cu")
		(hatch none 0.5)
		(connect_pads
			(clearance 0)
		)
		(min_thickness 0.25)
		(keepout
			(tracks allowed)
			(vias allowed)
			(pads allowed)
			(copperpour allowed)
			(footprints not_allowed)
		)
		(placement
			(enabled no)
			(sheetname "")
		)
		(fill
			(thermal_gap 0.5)
			(thermal_bridge_width 0.5)
			(island_removal_mode 0)
		)
		(polygon
			(pts
				(xy 177.299874 -84.000086) (xy 177.299874 -96.799908) (xy 0 -96.799908) (xy 0 -46.800008) (xy 8.349996 -46.800008)
				(xy 8.349996 -36.800028) (xy 22.899878 -36.800028) (xy 22.899878 -46.800008) (xy 39.900098 -46.800008)
				(xy 39.900098 -36.800028) (xy 54.44998 -36.800028) (xy 54.44998 -46.800008) (xy 71.449946 -46.800008)
				(xy 71.449946 -36.800028) (xy 86.000082 -36.800028) (xy 86.000082 -46.800008) (xy 103.000048 -46.800008)
				(xy 103.000048 -36.800028) (xy 117.54993 -36.800028) (xy 117.54993 -46.800008) (xy 134.549896 -46.800008)
				(xy 134.549896 -36.800028) (xy 149.100032 -36.800028) (xy 149.100032 -46.800008) (xy 166.099998 -46.800008)
				(xy 166.099998 -36.800028) (xy 180.64988 -36.800028) (xy 180.64988 -46.800008) (xy 191.799972 -46.800008)
				(xy 191.799972 -84.000086)
			)
		)
	)
	(zone
		(net "P12V_HDD18")
		(layer "F.Cu")
		(hatch none 0.5)
		(connect_pads
			(clearance 0.5)
		)
		(min_thickness 0.25)
		(fill yes
			(thermal_gap 0.5)
			(thermal_bridge_width 0.5)
			(island_removal_mode 0)
		)
		(polygon
			(pts
				(xy 334.645 -149.606) (xy 334.391 -149.86) (xy 334.391 -153.924) (xy 333.9338 -154.3812) (xy 333.9338 -156.6672)
				(xy 332.486 -158.115) (xy 326.263 -158.115) (xy 326.009 -158.369) (xy 326.009 -160.02) (xy 326.263 -160.274)
				(xy 330.2 -160.274) (xy 330.708 -159.766) (xy 338.455 -159.766) (xy 339.344 -158.877) (xy 339.344 -149.86)
				(xy 339.09 -149.606)
			)
		)
		(polygon
			(pts
				(xy 330.3524 -159.1564) (xy 330.1492 -159.1564) (xy 330.1492 -159.3596) (xy 330.3524 -159.3596)
			)
		)
		(polygon
			(pts
				(xy 329.4888 -159.1564) (xy 329.2856 -159.1564) (xy 329.2856 -159.3596) (xy 329.4888 -159.3596)
			)
		)
	)
	(zone
		(net "GND")
		(layer "F.Cu")
		(hatch none 0.5)
		(connect_pads
			(clearance 0.5)
		)
		(min_thickness 0.25)
		(fill yes
			(thermal_gap 0.5)
			(thermal_bridge_width 0.5)
			(island_removal_mode 0)
		)
		(polygon
			(pts
				(xy 46.627796 -290.34232) (xy 44.145962 -292.824154) (xy 44.145962 -304.43678) (xy 48.064928 -308.355746)
				(xy 83.406488 -308.355746) (xy 85.503766 -306.258468) (xy 85.503766 -292.336474) (xy 83.509612 -290.34232)
			)
		)
	)
	(zone
		(net "P5V_B_3")
		(layer "F.Cu")
		(hatch none 0.5)
		(connect_pads
			(clearance 0.5)
		)
		(min_thickness 0.25)
		(fill yes
			(thermal_gap 0.5)
			(thermal_bridge_width 0.5)
			(island_removal_mode 0)
		)
		(polygon
			(pts
				(xy 399.923 -251.333) (xy 399.669 -251.587) (xy 399.669 -256.286) (xy 399.923 -256.54) (xy 402.209 -256.54)
				(xy 402.463 -256.286) (xy 402.463 -251.587) (xy 402.209 -251.333)
			)
		)
	)
	(zone
		(net "12V_PRE_34")
		(layer "F.Cu")
		(hatch none 0.5)
		(connect_pads
			(clearance 0.5)
		)
		(min_thickness 0.25)
		(fill yes
			(thermal_gap 0.5)
			(thermal_bridge_width 0.5)
			(island_removal_mode 0)
		)
		(polygon
			(pts
				(xy 456.7936 -39.685976) (xy 454.7616 -41.717976) (xy 452.1962 -41.717976) (xy 451.9422 -41.971976)
				(xy 451.9422 -42.505376) (xy 452.1708 -42.733976) (xy 458.1652 -42.733976) (xy 459.1812 -41.717976)
				(xy 459.1812 -39.812976) (xy 459.0542 -39.685976)
			)
		)
	)
	(zone
		(net "IR_SWITCH_E")
		(layer "F.Cu")
		(hatch none 0.5)
		(connect_pads
			(clearance 0.5)
		)
		(min_thickness 0.25)
		(fill yes
			(thermal_gap 0.5)
			(thermal_bridge_width 0.5)
			(island_removal_mode 0)
		)
		(polygon
			(pts
				(xy 265.3665 -378.412756) (xy 265.2141 -378.565156) (xy 265.2141 -379.428756) (xy 265.3411 -379.555756)
				(xy 266.0269 -379.555756) (xy 266.1031 -379.631956) (xy 266.1031 -380.216156) (xy 266.2301 -380.343156)
				(xy 271.1831 -380.343156) (xy 271.3609 -380.165356) (xy 271.3609 -378.565156) (xy 271.2085 -378.412756)
			)
		)
		(polygon
			(pts
				(xy 265.8745 -378.793756) (xy 265.6713 -378.793756) (xy 265.6713 -378.996956) (xy 265.8745 -378.996956)
			)
		)
	)
	(zone
		(layer "F.Cu")
		(hatch none 0.5)
		(connect_pads
			(clearance 0)
		)
		(min_thickness 0.25)
		(keepout
			(tracks allowed)
			(vias allowed)
			(pads allowed)
			(copperpour allowed)
			(footprints not_allowed)
		)
		(placement
			(enabled no)
			(sheetname "")
		)
		(fill
			(thermal_gap 0.5)
			(thermal_bridge_width 0.5)
			(island_removal_mode 0)
		)
		(polygon
			(pts
				(arc
					(start 174.95012 -13.999972)
					(mid 170.200066 -18.750026)
					(end 165.450012 -13.999972)
				)
				(arc
					(start 165.450012 -13.999972)
					(mid 170.200066 -9.249918)
					(end 174.95012 -13.999972)
				)
			)
		)
	)
	(zone
		(net "GND")
		(layer "F.Cu")
		(hatch none 0.5)
		(connect_pads
			(clearance 0.5)
		)
		(min_thickness 0.25)
		(fill yes
			(thermal_gap 0.5)
			(thermal_bridge_width 0.5)
			(island_removal_mode 0)
		)
		(polygon
			(pts
				(xy 436.989474 -110.517178) (xy 436.481474 -111.025178) (xy 436.481474 -116.11229) (xy 437.277256 -116.908072)
				(xy 439.738262 -116.908072) (xy 439.926984 -116.71935) (xy 439.926984 -110.694978) (xy 439.749184 -110.517178)
			)
		)
	)
	(zone
		(net "GND")
		(layer "F.Cu")
		(hatch none 0.5)
		(connect_pads
			(clearance 0.5)
		)
		(min_thickness 0.25)
		(fill yes
			(thermal_gap 0.5)
			(thermal_bridge_width 0.5)
			(island_removal_mode 0)
		)
		(polygon
			(pts
				(xy 183.924956 -170.8912) (xy 183.509158 -171.306998)
				(arc
					(start 183.509158 -171.761404)
					(mid 184.102596 -175.83127)
					(end 180.858414 -178.359308)
				)
				(xy 180.293772 -178.92395) (xy 180.293772 -183.199786) (xy 180.582824 -183.488838) (xy 182.381906 -183.488838)
				(xy 182.412894 -183.488838) (xy 184.837324 -183.488838)
				(arc
					(start 186.242706 -182.083456)
					(mid 186.30735 -181.390784)
					(end 186.487054 -180.718714)
				)
				(xy 186.487054 -171.395898) (xy 185.982356 -170.8912)
			)
		)
	)
	(zone
		(net "P3V3_IN")
		(layer "F.Cu")
		(hatch none 0.5)
		(connect_pads
			(clearance 0.5)
		)
		(min_thickness 0.25)
		(fill yes
			(thermal_gap 0.5)
			(thermal_bridge_width 0.5)
			(island_removal_mode 0)
		)
		(polygon
			(pts
				(xy 225.7298 -301.9044) (xy 225.2345 -302.3997) (xy 225.2345 -303.4157) (xy 225.3488 -303.53) (xy 226.1616 -303.53)
				(xy 226.5934 -303.9618) (xy 228.8794 -303.9618) (xy 228.981 -303.8602) (xy 228.981 -303.4792) (xy 228.9302 -303.4284)
				(xy 228.219 -303.4284) (xy 228.0158 -303.2252) (xy 228.0158 -301.9552) (xy 227.965 -301.9044)
			)
		)
		(polygon
			(pts
				(xy 227.5078 -302.895) (xy 227.3046 -302.895) (xy 227.3046 -303.0982) (xy 227.5078 -303.0982)
			)
		)
		(polygon
			(pts
				(xy 225.933 -302.8696) (xy 225.7298 -302.8696) (xy 225.7298 -303.0728) (xy 225.933 -303.0728)
			)
		)
		(polygon
			(pts
				(xy 227.5078 -302.2854) (xy 227.3046 -302.2854) (xy 227.3046 -302.4886) (xy 227.5078 -302.4886)
			)
		)
	)
	(zone
		(layer "F.Cu")
		(hatch none 0.5)
		(connect_pads
			(clearance 0)
		)
		(min_thickness 0.25)
		(keepout
			(tracks not_allowed)
			(vias allowed)
			(pads allowed)
			(copperpour not_allowed)
			(footprints allowed)
		)
		(placement
			(enabled no)
			(sheetname "")
		)
		(fill
			(thermal_gap 0.5)
			(thermal_bridge_width 0.5)
			(island_removal_mode 0)
		)
		(polygon
			(pts
				(xy 351.405952 -13.770356)
				(arc
					(start 351.408238 -13.76807)
					(mid 351.479455 -13.624403)
					(end 351.623122 -13.553186)
				)
				(xy 351.625408 -13.5509)
				(arc
					(start 351.652078 -13.5509)
					(mid 352.174246 -13.6271)
					(end 351.652078 -13.7033)
				)
				(arc
					(start 351.652078 -13.7033)
					(mid 351.585448 -13.733809)
					(end 351.558352 -13.801852)
				)
				(xy 351.558352 -14.11224)
				(arc
					(start 351.907602 -14.11224)
					(mid 352.392742 -13.6271)
					(end 351.907602 -13.14196)
				)
				(arc
					(start 350.764856 -13.14196)
					(mid 350.279462 -13.626973)
					(end 350.764602 -14.11224)
				)
				(xy 351.113852 -14.11224)
				(arc
					(start 351.113852 -13.801852)
					(mid 351.086671 -13.733891)
					(end 351.020126 -13.7033)
				)
				(arc
					(start 351.020126 -13.7033)
					(mid 350.497958 -13.6271)
					(end 351.020126 -13.5509)
				)
				(xy 351.046796 -13.5509)
				(arc
					(start 351.049082 -13.553186)
					(mid 351.192749 -13.624403)
					(end 351.263966 -13.76807)
				)
				(xy 351.266252 -13.770356) (xy 351.266252 -14.11224) (xy 351.405952 -14.11224)
			)
		)
	)
	(zone
		(net "P12V_HDD14")
		(layer "F.Cu")
		(hatch none 0.5)
		(connect_pads
			(clearance 0.5)
		)
		(min_thickness 0.25)
		(fill yes
			(thermal_gap 0.5)
			(thermal_bridge_width 0.5)
			(island_removal_mode 0)
		)
		(polygon
			(pts
				(xy 75.438 -147.193) (xy 75.184 -147.447) (xy 75.184 -149.098) (xy 75.438 -149.352) (xy 77.597 -149.352)
				(xy 78.105 -149.86) (xy 78.105 -152.4) (xy 85.852 -160.147) (xy 94.361 -160.147) (xy 94.488 -160.02)
				(xy 94.488 -158.242) (xy 94.361 -158.115) (xy 88.392 -158.115) (xy 87.757 -157.48) (xy 86.106 -157.48)
				(xy 81.788 -153.162) (xy 81.788 -149.606) (xy 80.645 -148.463) (xy 80.645 -147.447) (xy 80.391 -147.193)
			)
		)
		(polygon
			(pts
				(xy 87.9094 -159.1564) (xy 87.7062 -159.1564) (xy 87.7062 -159.3596) (xy 87.9094 -159.3596)
			)
		)
		(polygon
			(pts
				(xy 87.0458 -159.1564) (xy 86.8426 -159.1564) (xy 86.8426 -159.3596) (xy 87.0458 -159.3596)
			)
		)
	)
	(zone
		(net "MB0_12V_CTRL_GATE4")
		(layer "F.Cu")
		(hatch none 0.5)
		(connect_pads
			(clearance 0.5)
		)
		(min_thickness 0.25)
		(fill yes
			(thermal_gap 0.5)
			(thermal_bridge_width 0.5)
			(island_removal_mode 0)
		)
		(polygon
			(pts
				(xy 205.105 -345.567) (xy 204.978 -345.694) (xy 204.978 -349.631) (xy 205.486 -350.139) (xy 206.258668 -350.139)
				(xy 206.629 -349.768668) (xy 206.629 -345.821) (xy 206.375 -345.567)
			)
		)
	)
	(zone
		(layer "F.Cu")
		(hatch none 0.5)
		(connect_pads
			(clearance 0)
		)
		(min_thickness 0.25)
		(keepout
			(tracks allowed)
			(vias allowed)
			(pads allowed)
			(copperpour allowed)
			(footprints allowed)
		)
		(placement
			(enabled no)
			(sheetname "")
		)
		(fill
			(thermal_gap 0.5)
			(thermal_bridge_width 0.5)
			(island_removal_mode 0)
		)
		(polygon
			(pts
				(xy 43.690032 -113.741962) (xy 43.690032 -109.643672) (xy 44.940982 -109.643672) (xy 44.940982 -113.741962)
			)
		)
	)
	(zone
		(layer "F.Cu")
		(hatch none 0.5)
		(connect_pads
			(clearance 0)
		)
		(min_thickness 0.25)
		(keepout
			(tracks allowed)
			(vias allowed)
			(pads allowed)
			(copperpour allowed)
			(footprints not_allowed)
		)
		(placement
			(enabled no)
			(sheetname "")
		)
		(fill
			(thermal_gap 0.5)
			(thermal_bridge_width 0.5)
			(island_removal_mode 0)
		)
		(polygon
			(pts
				(arc
					(start 336.55 -13.999972)
					(mid 341.300054 -9.249918)
					(end 346.050108 -13.999972)
				)
				(arc
					(start 346.050108 -13.999972)
					(mid 341.300054 -18.750026)
					(end 336.55 -13.999972)
				)
			)
		)
	)
	(zone
		(net "GND")
		(layer "F.Cu")
		(hatch none 0.5)
		(connect_pads
			(clearance 0.5)
		)
		(min_thickness 0.25)
		(fill yes
			(thermal_gap 0.5)
			(thermal_bridge_width 0.5)
			(island_removal_mode 0)
		)
		(polygon
			(pts
				(xy 297.608752 -333.065882) (xy 297.354752 -333.319882) (xy 297.354752 -335.732882) (xy 297.506898 -335.885028)
				(xy 305.584606 -335.885028) (xy 305.736752 -335.732882) (xy 305.736752 -333.573882) (xy 305.228752 -333.065882)
			)
		)
		(polygon
			(pts
				(xy 300.255686 -334.074262) (xy 300.052486 -334.074262) (xy 300.052486 -334.277462) (xy 300.255686 -334.277462)
			)
		)
		(polygon
			(pts
				(xy 299.392086 -334.074262) (xy 299.188886 -334.074262) (xy 299.188886 -334.277462) (xy 299.392086 -334.277462)
			)
		)
		(polygon
			(pts
				(xy 299.0596 -333.629) (xy 298.8564 -333.629) (xy 298.8564 -333.8322) (xy 299.0596 -333.8322)
			)
		)
		(polygon
			(pts
				(xy 298.45 -333.629) (xy 298.2468 -333.629) (xy 298.2468 -333.8322) (xy 298.45 -333.8322)
			)
		)
	)
	(zone
		(net "GND")
		(layer "F.Cu")
		(hatch none 0.5)
		(connect_pads
			(clearance 0.5)
		)
		(min_thickness 0.25)
		(fill yes
			(thermal_gap 0.5)
			(thermal_bridge_width 0.5)
			(island_removal_mode 0)
		)
		(polygon
			(pts
				(xy 281.5844 -303.1236) (xy 281.3304 -303.3776) (xy 281.3304 -306.9336) (xy 281.7114 -307.3146)
				(xy 288.1884 -307.3146) (xy 288.4424 -307.0606) (xy 288.4424 -303.3776) (xy 288.1884 -303.1236)
			)
		)
	)
	(zone
		(layer "F.Cu")
		(hatch none 0.5)
		(connect_pads
			(clearance 0)
		)
		(min_thickness 0.25)
		(keepout
			(tracks not_allowed)
			(vias allowed)
			(pads allowed)
			(copperpour not_allowed)
			(footprints allowed)
		)
		(placement
			(enabled no)
			(sheetname "")
		)
		(fill
			(thermal_gap 0.5)
			(thermal_bridge_width 0.5)
			(island_removal_mode 0)
		)
		(polygon
			(pts
				(arc
					(start 385.78155 -16.95196)
					(mid 385.29641 -17.4371)
					(end 385.78155 -17.92224)
				)
				(xy 386.1943 -17.92224)
				(arc
					(start 386.1943 -17.599152)
					(mid 386.169155 -17.538445)
					(end 386.108448 -17.5133)
				)
				(arc
					(start 386.037074 -17.5133)
					(mid 385.514906 -17.4371)
					(end 386.037074 -17.3609)
				)
				(xy 386.139944 -17.3609)
				(arc
					(start 386.142484 -17.36344)
					(mid 386.27685 -17.43075)
					(end 386.34416 -17.565116)
				)
				(xy 386.3467 -17.567656) (xy 386.3467 -17.92224) (xy 386.4864 -17.92224) (xy 386.4864 -17.567656)
				(arc
					(start 386.48894 -17.565116)
					(mid 386.55625 -17.43075)
					(end 386.690616 -17.36344)
				)
				(xy 386.693156 -17.3609)
				(arc
					(start 386.796026 -17.3609)
					(mid 387.318194 -17.4371)
					(end 386.796026 -17.5133)
				)
				(arc
					(start 386.724652 -17.5133)
					(mid 386.663945 -17.538445)
					(end 386.6388 -17.599152)
				)
				(xy 386.6388 -17.92224)
				(arc
					(start 387.051296 -17.92224)
					(mid 387.53669 -17.437227)
					(end 387.05155 -16.95196)
				)
			)
		)
	)
	(zone
		(net "GND")
		(layer "F.Cu")
		(hatch none 0.5)
		(connect_pads
			(clearance 0.5)
		)
		(min_thickness 0.25)
		(fill yes
			(thermal_gap 0.5)
			(thermal_bridge_width 0.5)
			(island_removal_mode 0)
		)
		(polygon
			(pts
				(xy 203.668122 -100.582984) (xy 203.414122 -100.836984) (xy 203.414122 -104.392984) (xy 203.714096 -104.692958)
				(xy 210.041236 -104.692958) (xy 210.526122 -104.208072) (xy 210.526122 -100.917502) (xy 210.191604 -100.582984)
			)
		)
	)
	(zone
		(layer "F.Cu")
		(hatch none 0.5)
		(connect_pads
			(clearance 0)
		)
		(min_thickness 0.25)
		(keepout
			(tracks not_allowed)
			(vias allowed)
			(pads allowed)
			(copperpour not_allowed)
			(footprints allowed)
		)
		(placement
			(enabled no)
			(sheetname "")
		)
		(fill
			(thermal_gap 0.5)
			(thermal_bridge_width 0.5)
			(island_removal_mode 0)
		)
		(polygon
			(pts
				(arc
					(start 190.744094 -133.115304)
					(mid 190.259081 -132.62991)
					(end 189.773814 -133.11505)
				)
				(xy 189.773814 -133.5278)
				(arc
					(start 190.131954 -133.5278)
					(mid 190.167875 -133.512921)
					(end 190.182754 -133.477)
				)
				(arc
					(start 190.182754 -133.370574)
					(mid 190.258954 -132.848406)
					(end 190.335154 -133.370574)
				)
				(xy 190.335154 -133.508496)
				(arc
					(start 190.332106 -133.511544)
					(mid 190.275575 -133.620621)
					(end 190.166498 -133.677152)
				)
				(xy 190.16345 -133.6802) (xy 189.773814 -133.6802) (xy 189.773814 -133.8199) (xy 190.16345 -133.8199)
				(arc
					(start 190.166498 -133.822948)
					(mid 190.275575 -133.879479)
					(end 190.332106 -133.988556)
				)
				(xy 190.335154 -133.991604)
				(arc
					(start 190.335154 -134.129526)
					(mid 190.258954 -134.651694)
					(end 190.182754 -134.129526)
				)
				(arc
					(start 190.182754 -134.0231)
					(mid 190.167875 -133.987179)
					(end 190.131954 -133.9723)
				)
				(xy 189.773814 -133.9723)
				(arc
					(start 189.773814 -134.38505)
					(mid 190.258954 -134.87019)
					(end 190.744094 -134.38505)
				)
			)
		)
	)
	(zone
		(net "12V_PRE_23")
		(layer "F.Cu")
		(hatch none 0.5)
		(connect_pads
			(clearance 0.5)
		)
		(min_thickness 0.25)
		(fill yes
			(thermal_gap 0.5)
			(thermal_bridge_width 0.5)
			(island_removal_mode 0)
		)
		(polygon
			(pts
				(xy 474.726 -149.733) (xy 474.599 -149.86) (xy 474.599 -153.4922) (xy 476.4278 -155.321) (xy 479.933 -155.321)
				(xy 482.346 -157.734) (xy 486.283 -157.734) (xy 486.41 -157.607) (xy 486.41 -156.845) (xy 486.283 -156.718)
				(xy 482.981 -156.718) (xy 480.1362 -153.8732) (xy 476.9866 -153.8732) (xy 476.5294 -153.416) (xy 476.5294 -150.2664)
				(xy 475.996 -149.733)
			)
		)
	)
	(zone
		(layer "F.Cu")
		(hatch none 0.5)
		(connect_pads
			(clearance 0)
		)
		(min_thickness 0.25)
		(keepout
			(tracks not_allowed)
			(vias allowed)
			(pads allowed)
			(copperpour not_allowed)
			(footprints allowed)
		)
		(placement
			(enabled no)
			(sheetname "")
		)
		(fill
			(thermal_gap 0.5)
			(thermal_bridge_width 0.5)
			(island_removal_mode 0)
		)
		(polygon
			(pts
				(arc
					(start 439.17489 -66.799968)
					(mid 425.174918 -80.79994)
					(end 411.174946 -66.799968)
				)
				(arc
					(start 411.174946 -66.799968)
					(mid 425.174918 -52.799996)
					(end 439.17489 -66.799968)
				)
			)
		)
	)
	(zone
		(net "P5V_HDD7")
		(layer "F.Cu")
		(hatch none 0.5)
		(connect_pads
			(clearance 0.5)
		)
		(min_thickness 0.25)
		(fill yes
			(thermal_gap 0.5)
			(thermal_bridge_width 0.5)
			(island_removal_mode 0)
		)
		(polygon
			(pts
				(xy 363.093 -252.73) (xy 362.839 -252.984) (xy 362.839 -263.779) (xy 361.188 -265.43) (xy 357.759 -265.43)
				(xy 357.505 -265.684) (xy 357.505 -267.335) (xy 357.759 -267.589) (xy 362.331 -267.589) (xy 362.966 -266.954)
				(xy 364.744 -266.954) (xy 365.252 -266.446) (xy 365.252 -252.984) (xy 364.998 -252.73)
			)
		)
		(polygon
			(pts
				(xy 361.8484 -266.5984) (xy 361.6452 -266.5984) (xy 361.6452 -266.8016) (xy 361.8484 -266.8016)
			)
		)
		(polygon
			(pts
				(xy 360.9848 -266.5984) (xy 360.7816 -266.5984) (xy 360.7816 -266.8016) (xy 360.9848 -266.8016)
			)
		)
	)
	(zone
		(net "GND")
		(layer "F.Cu")
		(hatch none 0.5)
		(connect_pads
			(clearance 0.5)
		)
		(min_thickness 0.25)
		(fill yes
			(thermal_gap 0.5)
			(thermal_bridge_width 0.5)
			(island_removal_mode 0)
		)
		(polygon
			(pts
				(xy 406.370282 -173.26991) (xy 406.05456 -173.585632) (xy 406.05456 -174.252636) (xy 406.34793 -174.546006)
				(arc
					(start 406.540462 -174.546006)
					(mid 407.221651 -174.357735)
					(end 407.925524 -174.294292)
				)
				(arc
					(start 409.983178 -174.294292)
					(mid 411.476145 -174.588289)
					(end 412.74619 -175.42637)
				)
				(xy 414.543748 -175.42637) (xy 414.707324 -175.589946) (xy 414.707324 -219.203524) (xy 412.406338 -221.50451)
				(xy 409.577794 -221.50451) (xy 408.618944 -222.46336) (xy 400.716242 -222.46336) (xy 397.039846 -218.786964)
				(xy 397.039846 -207.583278) (xy 398.26184 -206.361284) (xy 398.26184 -195.777358) (xy 397.803878 -195.319396)
				(arc
					(start 396.1892 -195.319396)
					(mid 388.889062 -194.499743)
					(end 383.794508 -189.207394)
				)
				(xy 382.954276 -189.207394) (xy 382.688084 -189.473586) (xy 382.688084 -190.985394) (xy 383.211324 -191.508634)
				(arc
					(start 383.211324 -215.341454)
					(mid 383.439124 -216.6874)
					(end 383.211324 -218.033346)
				)
				(xy 383.211324 -219.203524) (xy 380.910338 -221.50451) (xy 377.957842 -221.50451) (xy 376.96521 -222.497142)
				(xy 368.497866 -222.497142) (xy 364.14964 -218.148916) (xy 364.14964 -177.178716) (xy 361.269534 -174.29861)
				(xy 349.92564 -174.29861) (xy 349.747586 -174.476664) (xy 349.747586 -175.114204) (xy 350.059752 -175.42637)
				(xy 351.443798 -175.42637) (xy 351.443798 -185.373518) (xy 351.138236 -185.67908) (xy 351.138236 -199.152764)
				(xy 351.588324 -199.602852) (xy 351.588324 -209.421476) (xy 351.588324 -219.330524) (xy 349.414338 -221.50451)
				(xy 348.516702 -221.50451) (xy 346.924376 -221.50451) (xy 345.819984 -222.608902) (xy 337.545426 -222.608902)
				(xy 334.105504 -219.16898) (xy 334.105504 -197.234556) (xy 332.406752 -195.535804)
				(arc
					(start 331.985874 -195.535804)
					(mid 328.893822 -195.467977)
					(end 325.947278 -194.528186)
				)
				(xy 324.520306 -194.528186) (xy 323.70776 -195.340732) (xy 323.70776 -218.174316) (xy 320.57213 -221.309946)
				(xy 320.57213 -222.53956) (xy 321.770248 -223.737678) (xy 436.519828 -223.737678) (xy 436.69204 -223.565466)
				(xy 436.69204 -223.14027) (xy 435.993032 -222.441262) (xy 433.305204 -222.441262) (xy 431.091594 -220.227652)
				(xy 430.96307 -220.227652) (xy 430.96307 -220.099128) (xy 420.84244 -209.978498) (xy 420.84244 -173.820328)
				(xy 420.292022 -173.26991)
			)
		)
	)
	(zone
		(layer "F.Cu")
		(hatch none 0.5)
		(connect_pads
			(clearance 0)
		)
		(min_thickness 0.25)
		(keepout
			(tracks allowed)
			(vias allowed)
			(pads allowed)
			(copperpour allowed)
			(footprints allowed)
		)
		(placement
			(enabled no)
			(sheetname "")
		)
		(fill
			(thermal_gap 0.5)
			(thermal_bridge_width 0.5)
			(island_removal_mode 0)
		)
		(polygon
			(pts
				(xy 247.8786 -364.1344) (xy 251.46 -364.1344) (xy 251.46 -368.0968) (xy 250.5202 -368.0968) (xy 249.9868 -368.6302)
				(xy 247.8786 -368.6302)
			)
		)
	)
	(zone
		(net "P12V_B")
		(layer "F.Cu")
		(hatch none 0.5)
		(connect_pads
			(clearance 0.5)
		)
		(min_thickness 0.25)
		(fill yes
			(thermal_gap 0.5)
			(thermal_bridge_width 0.5)
			(island_removal_mode 0)
		)
		(polygon
			(pts
				(xy 429.26 -142.494) (xy 428.752 -143.002) (xy 428.752 -146.431) (xy 429.006 -146.685) (xy 432.308 -146.685)
				(xy 432.562 -146.431) (xy 432.562 -144.399) (xy 432.689 -144.272) (xy 433.07 -144.272) (xy 433.197 -144.145)
				(xy 433.197 -142.621) (xy 433.07 -142.494)
			)
		)
		(polygon
			(pts
				(xy 432.6636 -143.4846) (xy 432.4604 -143.4846) (xy 432.4604 -143.6878) (xy 432.6636 -143.6878)
			)
		)
		(polygon
			(pts
				(xy 432.7144 -143.0528) (xy 432.5112 -143.0528) (xy 432.5112 -143.256) (xy 432.7144 -143.256)
			)
		)
	)
	(zone
		(layer "F.Cu")
		(hatch none 0.5)
		(connect_pads
			(clearance 0)
		)
		(min_thickness 0.25)
		(keepout
			(tracks not_allowed)
			(vias allowed)
			(pads allowed)
			(copperpour not_allowed)
			(footprints allowed)
		)
		(placement
			(enabled no)
			(sheetname "")
		)
		(fill
			(thermal_gap 0.5)
			(thermal_bridge_width 0.5)
			(island_removal_mode 0)
		)
		(polygon
			(pts
				(arc
					(start 129.42062 -14.41958)
					(mid 128.935607 -13.934186)
					(end 128.45034 -14.419326)
				)
				(xy 128.45034 -14.768576)
				(arc
					(start 128.776476 -14.768576)
					(mid 128.835027 -14.744323)
					(end 128.85928 -14.685772)
				)
				(arc
					(start 128.85928 -14.67485)
					(mid 128.93548 -14.152682)
					(end 129.01168 -14.67485)
				)
				(xy 129.01168 -14.717268)
				(arc
					(start 129.00914 -14.719808)
					(mid 128.942745 -14.852041)
					(end 128.810512 -14.918436)
				)
				(xy 128.807972 -14.920976) (xy 128.45034 -14.920976) (xy 128.45034 -15.060676) (xy 128.807972 -15.060676)
				(arc
					(start 128.810512 -15.063216)
					(mid 128.942745 -15.129611)
					(end 129.00914 -15.261844)
				)
				(xy 129.01168 -15.264384)
				(arc
					(start 129.01168 -15.306802)
					(mid 128.93548 -15.82897)
					(end 128.85928 -15.306802)
				)
				(arc
					(start 128.85928 -15.29588)
					(mid 128.835027 -15.237329)
					(end 128.776476 -15.213076)
				)
				(xy 128.45034 -15.213076)
				(arc
					(start 128.45034 -15.562326)
					(mid 128.93548 -16.047466)
					(end 129.42062 -15.562326)
				)
			)
		)
	)
	(zone
		(layer "F.Cu")
		(hatch none 0.5)
		(connect_pads
			(clearance 0)
		)
		(min_thickness 0.25)
		(keepout
			(tracks allowed)
			(vias allowed)
			(pads allowed)
			(copperpour allowed)
			(footprints allowed)
		)
		(placement
			(enabled no)
			(sheetname "")
		)
		(fill
			(thermal_gap 0.5)
			(thermal_bridge_width 0.5)
			(island_removal_mode 0)
		)
		(polygon
			(pts
				(xy 244.348 -132.3848) (xy 244.348 -133.4516) (xy 242.697 -133.4516) (xy 242.697 -132.3848)
			)
		)
	)
	(zone
		(net "GND")
		(layer "F.Cu")
		(hatch none 0.5)
		(connect_pads
			(clearance 0.5)
		)
		(min_thickness 0.25)
		(fill yes
			(thermal_gap 0.5)
			(thermal_bridge_width 0.5)
			(island_removal_mode 0)
		)
		(polygon
			(pts
				(xy 129.808986 -124.160534)
				(arc
					(start 130.182366 -124.533914)
					(mid 132.221655 -126.009744)
					(end 133.001004 -128.40335)
				)
				(arc
					(start 133.001004 -131.57835)
					(mid 132.529481 -133.478845)
					(end 131.224274 -134.938516)
				)
				(arc
					(start 131.224274 -135.40105)
					(mid 130.814428 -137.179956)
					(end 129.667508 -138.60018)
				)
				(xy 129.667508 -141.14907)
				(arc
					(start 130.289046 -141.770608)
					(mid 131.786869 -142.02471)
					(end 133.088634 -142.807944)
				)
				(xy 134.070344 -142.807944) (xy 134.554976 -142.323312) (xy 134.554976 -138.618976) (xy 135.225028 -138.618976)
				(xy 136.523476 -137.320528)
				(arc
					(start 136.523476 -134.069582)
					(mid 135.905883 -130.210215)
					(end 138.809476 -127.593852)
				)
				(xy 138.809476 -127.125476) (xy 140.562076 -127.125476) (xy 140.562076 -127.049276)
				(arc
					(start 144.286732 -127.049276)
					(mid 145.242983 -125.364179)
					(end 146.867372 -124.308108)
				)
				(xy 147.0152 -124.16028) (xy 147.0152 -123.579128) (xy 146.6723 -123.236228) (xy 130.329686 -123.236228)
				(xy 129.808986 -123.756928)
			)
		)
	)
	(zone
		(net "P3V3_IN")
		(layer "F.Cu")
		(hatch none 0.5)
		(connect_pads
			(clearance 0.5)
		)
		(min_thickness 0.25)
		(fill yes
			(thermal_gap 0.5)
			(thermal_bridge_width 0.5)
			(island_removal_mode 0)
		)
		(polygon
			(pts
				(xy 304.536348 -355.428042) (xy 304.447448 -355.516942) (xy 304.447448 -357.167942) (xy 304.650648 -357.371142)
				(xy 306.200048 -357.371142) (xy 306.936648 -356.634542) (xy 306.936648 -355.821742) (xy 306.542948 -355.428042)
			)
		)
		(polygon
			(pts
				(xy 305.450748 -356.667308) (xy 305.247548 -356.667308) (xy 305.247548 -356.870508) (xy 305.450748 -356.870508)
			)
		)
		(polygon
			(pts
				(xy 304.841148 -356.667308) (xy 304.637948 -356.667308) (xy 304.637948 -356.870508) (xy 304.841148 -356.870508)
			)
		)
		(polygon
			(pts
				(xy 306.479448 -356.238556) (xy 306.276248 -356.238556) (xy 306.276248 -356.441756) (xy 306.479448 -356.441756)
			)
		)
		(polygon
			(pts
				(xy 306.479448 -355.679756) (xy 306.276248 -355.679756) (xy 306.276248 -355.882956) (xy 306.479448 -355.882956)
			)
		)
	)
	(zone
		(net "P12V_HDD19")
		(layer "F.Cu")
		(hatch none 0.5)
		(connect_pads
			(clearance 0.5)
		)
		(min_thickness 0.25)
		(fill yes
			(thermal_gap 0.5)
			(thermal_bridge_width 0.5)
			(island_removal_mode 0)
		)
		(polygon
			(pts
				(xy 366.141 -149.606) (xy 365.887 -149.86) (xy 365.887 -153.924) (xy 365.4298 -154.3812) (xy 365.4298 -156.9212)
				(xy 364.236 -158.115) (xy 357.759 -158.115) (xy 357.505 -158.369) (xy 357.505 -160.02) (xy 357.759 -160.274)
				(xy 361.696 -160.274) (xy 362.204 -159.766) (xy 369.951 -159.766) (xy 370.84 -158.877) (xy 370.84 -149.86)
				(xy 370.586 -149.606)
			)
		)
		(polygon
			(pts
				(xy 361.8484 -159.1564) (xy 361.6452 -159.1564) (xy 361.6452 -159.3596) (xy 361.8484 -159.3596)
			)
		)
		(polygon
			(pts
				(xy 360.9848 -159.1564) (xy 360.7816 -159.1564) (xy 360.7816 -159.3596) (xy 360.9848 -159.3596)
			)
		)
	)
	(zone
		(net "P12V_B")
		(layer "F.Cu")
		(hatch none 0.5)
		(connect_pads
			(clearance 0.5)
		)
		(min_thickness 0.25)
		(fill yes
			(thermal_gap 0.5)
			(thermal_bridge_width 0.5)
			(island_removal_mode 0)
		)
		(polygon
			(pts
				(xy 403.0726 -31.242) (xy 402.8186 -31.496) (xy 402.8186 -34.798) (xy 403.0726 -35.052) (xy 405.9936 -35.052)
				(xy 407.0096 -34.036) (xy 407.0096 -31.75) (xy 406.5016 -31.242)
			)
		)
		(polygon
			(pts
				(xy 406.4762 -33.9852) (xy 406.273 -33.9852) (xy 406.273 -34.1884) (xy 406.4762 -34.1884)
			)
		)
		(polygon
			(pts
				(xy 406.4762 -33.3756) (xy 406.273 -33.3756) (xy 406.273 -33.5788) (xy 406.4762 -33.5788)
			)
		)
		(polygon
			(pts
				(xy 406.527 -32.9438) (xy 406.3238 -32.9438) (xy 406.3238 -33.147) (xy 406.527 -33.147)
			)
		)
		(polygon
			(pts
				(xy 406.527 -32.385) (xy 406.3238 -32.385) (xy 406.3238 -32.5882) (xy 406.527 -32.5882)
			)
		)
	)
	(zone
		(net "P12V_B")
		(layer "F.Cu")
		(hatch none 0.5)
		(connect_pads
			(clearance 0.5)
		)
		(min_thickness 0.25)
		(fill yes
			(thermal_gap 0.5)
			(thermal_bridge_width 0.5)
			(island_removal_mode 0)
		)
		(polygon
			(pts
				(xy 366.141 -257.429) (xy 365.633 -257.937) (xy 365.633 -261.366) (xy 365.887 -261.62) (xy 369.189 -261.62)
				(xy 369.443 -261.366) (xy 369.443 -259.334) (xy 369.57 -259.207) (xy 369.951 -259.207) (xy 370.078 -259.08)
				(xy 370.078 -257.556) (xy 369.951 -257.429)
			)
		)
		(polygon
			(pts
				(xy 369.5446 -258.4196) (xy 369.3414 -258.4196) (xy 369.3414 -258.6228) (xy 369.5446 -258.6228)
			)
		)
		(polygon
			(pts
				(xy 369.5954 -257.9878) (xy 369.3922 -257.9878) (xy 369.3922 -258.191) (xy 369.5954 -258.191)
			)
		)
	)
	(zone
		(layer "F.Cu")
		(hatch none 0.5)
		(connect_pads
			(clearance 0)
		)
		(min_thickness 0.25)
		(keepout
			(tracks not_allowed)
			(vias allowed)
			(pads allowed)
			(copperpour not_allowed)
			(footprints allowed)
		)
		(placement
			(enabled no)
			(sheetname "")
		)
		(fill
			(thermal_gap 0.5)
			(thermal_bridge_width 0.5)
			(island_removal_mode 0)
		)
		(polygon
			(pts
				(arc
					(start 480.431856 -16.95196)
					(mid 479.946462 -17.436973)
					(end 480.431602 -17.92224)
				)
				(xy 480.844352 -17.92224)
				(arc
					(start 480.844352 -17.599152)
					(mid 480.819207 -17.538445)
					(end 480.7585 -17.5133)
				)
				(arc
					(start 480.687126 -17.5133)
					(mid 480.164958 -17.4371)
					(end 480.687126 -17.3609)
				)
				(xy 480.789996 -17.3609)
				(arc
					(start 480.792536 -17.36344)
					(mid 480.926902 -17.43075)
					(end 480.994212 -17.565116)
				)
				(xy 480.996752 -17.567656) (xy 480.996752 -17.92224) (xy 481.136452 -17.92224) (xy 481.136452 -17.586452)
				(arc
					(start 481.138738 -17.584166)
					(mid 481.211779 -17.436227)
					(end 481.359718 -17.363186)
				)
				(xy 481.362004 -17.3609)
				(arc
					(start 481.446078 -17.3609)
					(mid 481.968246 -17.4371)
					(end 481.446078 -17.5133)
				)
				(arc
					(start 481.3935 -17.5133)
					(mid 481.319503 -17.543951)
					(end 481.288852 -17.617948)
				)
				(xy 481.288852 -17.92224)
				(arc
					(start 481.701602 -17.92224)
					(mid 482.186742 -17.4371)
					(end 481.701602 -16.95196)
				)
			)
		)
	)
	(zone
		(layer "F.Cu")
		(hatch none 0.5)
		(connect_pads
			(clearance 0)
		)
		(min_thickness 0.25)
		(keepout
			(tracks not_allowed)
			(vias allowed)
			(pads allowed)
			(copperpour not_allowed)
			(footprints allowed)
		)
		(placement
			(enabled no)
			(sheetname "")
		)
		(fill
			(thermal_gap 0.5)
			(thermal_bridge_width 0.5)
			(island_removal_mode 0)
		)
		(polygon
			(pts
				(arc
					(start 96.094042 -133.11505)
					(mid 95.608902 -132.62991)
					(end 95.123762 -133.11505)
				)
				(xy 95.123762 -133.5278)
				(arc
					(start 95.481902 -133.5278)
					(mid 95.517823 -133.512921)
					(end 95.532702 -133.477)
				)
				(arc
					(start 95.532702 -133.370574)
					(mid 95.608902 -132.848406)
					(end 95.685102 -133.370574)
				)
				(xy 95.685102 -133.508496)
				(arc
					(start 95.682054 -133.511544)
					(mid 95.625523 -133.620621)
					(end 95.516446 -133.677152)
				)
				(xy 95.513398 -133.6802) (xy 95.123762 -133.6802) (xy 95.123762 -133.8199) (xy 95.513398 -133.8199)
				(arc
					(start 95.516446 -133.822948)
					(mid 95.625523 -133.879479)
					(end 95.682054 -133.988556)
				)
				(xy 95.685102 -133.991604)
				(arc
					(start 95.685102 -134.129526)
					(mid 95.608902 -134.651694)
					(end 95.532702 -134.129526)
				)
				(arc
					(start 95.532702 -134.0231)
					(mid 95.517823 -133.987179)
					(end 95.481902 -133.9723)
				)
				(xy 95.123762 -133.9723)
				(arc
					(start 95.123762 -134.384796)
					(mid 95.608775 -134.87019)
					(end 96.094042 -134.38505)
				)
			)
		)
	)
	(zone
		(net "5V_PRE_16")
		(layer "F.Cu")
		(hatch none 0.5)
		(connect_pads
			(clearance 0.5)
		)
		(min_thickness 0.25)
		(fill yes
			(thermal_gap 0.5)
			(thermal_bridge_width 0.5)
			(island_removal_mode 0)
		)
		(polygon
			(pts
				(xy 149.158452 -145.962624) (xy 149.006052 -146.115024) (xy 149.006052 -147.512024) (xy 149.590252 -148.096224)
				(xy 150.860252 -148.096224) (xy 152.943052 -150.179024) (xy 157.388052 -150.179024) (xy 157.515052 -150.052024)
				(xy 157.515052 -149.290024) (xy 157.388052 -149.163024) (xy 154.365452 -149.163024) (xy 151.165052 -145.962624)
			)
		)
	)
	(zone
		(net "P12V_B")
		(layer "F.Cu")
		(hatch none 0.5)
		(connect_pads
			(clearance 0.5)
		)
		(min_thickness 0.25)
		(fill yes
			(thermal_gap 0.5)
			(thermal_bridge_width 0.5)
			(island_removal_mode 0)
		)
		(polygon
			(pts
				(xy 266.134088 -195.3006) (xy 265.849608 -195.58508) (xy 265.849608 -198.415656) (xy 265.085068 -199.18045)
				(xy 260.327648 -199.18045) (xy 260.019546 -199.488552) (xy 260.019546 -202.555602) (xy 260.26999 -202.806046)
				(xy 271.818354 -202.806046) (xy 272.034 -202.5904) (xy 272.034 -196.27342) (xy 271.06118 -195.3006)
			)
		)
	)
	(zone
		(net "P12V_B")
		(layer "F.Cu")
		(hatch none 0.5)
		(connect_pads
			(clearance 0.5)
		)
		(min_thickness 0.25)
		(fill yes
			(thermal_gap 0.5)
			(thermal_bridge_width 0.5)
			(island_removal_mode 0)
		)
		(polygon
			(pts
				(xy 366.141 -27.432) (xy 365.633 -27.94) (xy 365.633 -31.369) (xy 365.887 -31.623) (xy 369.189 -31.623)
				(xy 369.443 -31.369) (xy 369.443 -29.337) (xy 369.57 -29.21) (xy 369.951 -29.21) (xy 370.078 -29.083)
				(xy 370.078 -27.559) (xy 369.951 -27.432)
			)
		)
		(polygon
			(pts
				(xy 369.5446 -28.4226) (xy 369.3414 -28.4226) (xy 369.3414 -28.6258) (xy 369.5446 -28.6258)
			)
		)
		(polygon
			(pts
				(xy 369.5954 -27.9908) (xy 369.3922 -27.9908) (xy 369.3922 -28.194) (xy 369.5954 -28.194)
			)
		)
	)
	(zone
		(layer "F.Cu")
		(hatch none 0.5)
		(connect_pads
			(clearance 0)
		)
		(min_thickness 0.25)
		(keepout
			(tracks not_allowed)
			(vias allowed)
			(pads allowed)
			(copperpour not_allowed)
			(footprints allowed)
		)
		(placement
			(enabled no)
			(sheetname "")
		)
		(fill
			(thermal_gap 0.5)
			(thermal_bridge_width 0.5)
			(island_removal_mode 0)
		)
		(polygon
			(pts
				(arc
					(start 462.7499 -13.999972)
					(mid 467.499954 -9.249918)
					(end 472.250008 -13.999972)
				)
				(arc
					(start 472.250008 -13.999972)
					(mid 467.499954 -18.750026)
					(end 462.7499 -13.999972)
				)
			)
		)
	)
	(zone
		(net "P12V_B")
		(layer "F.Cu")
		(hatch none 0.5)
		(connect_pads
			(clearance 0.5)
		)
		(min_thickness 0.25)
		(fill yes
			(thermal_gap 0.5)
			(thermal_bridge_width 0.5)
			(island_removal_mode 0)
		)
		(polygon
			(pts
				(xy 140.462 -255.143) (xy 139.446 -256.159) (xy 138.811 -256.159) (xy 138.43 -256.54) (xy 138.43 -259.08)
				(xy 138.684 -259.334) (xy 141.986 -259.334) (xy 142.24 -259.08) (xy 142.24 -256.794) (xy 141.605 -256.159)
				(xy 141.224 -256.159) (xy 140.97 -255.905) (xy 140.97 -255.27) (xy 140.843 -255.143)
			)
		)
		(polygon
			(pts
				(xy 140.4366 -255.7272) (xy 140.2334 -255.7272) (xy 140.2334 -255.9304) (xy 140.4366 -255.9304)
			)
		)
	)
	(zone
		(net "GND")
		(layer "F.Cu")
		(hatch none 0.5)
		(connect_pads
			(clearance 0.5)
		)
		(min_thickness 0.25)
		(fill yes
			(thermal_gap 0.5)
			(thermal_bridge_width 0.5)
			(island_removal_mode 0)
		)
		(polygon
			(pts
				(xy 333.80045 -100.885498) (xy 333.27467 -101.411278) (xy 333.27467 -104.163622) (xy 329.603608 -107.834684)
				(xy 329.603608 -108.643674) (xy 330.068174 -109.10824) (xy 334.502506 -109.10824) (xy 336.120994 -107.489752)
				(arc
					(start 336.120994 -103.326438)
					(mid 335.150446 -102.362469)
					(end 334.55991 -101.128576)
				)
				(xy 334.316832 -100.885498)
			)
		)
	)
	(zone
		(net "MB0_12V_CTRL_GATE2")
		(layer "F.Cu")
		(hatch none 0.5)
		(connect_pads
			(clearance 0.5)
		)
		(min_thickness 0.25)
		(fill yes
			(thermal_gap 0.5)
			(thermal_bridge_width 0.5)
			(island_removal_mode 0)
		)
		(polygon
			(pts
				(xy 204.978 -334.899) (xy 204.851 -335.026) (xy 204.851 -339.09) (xy 205.232 -339.471) (xy 206.375 -339.471)
				(xy 206.629 -339.217) (xy 206.629 -335.026) (xy 206.502 -334.899)
			)
		)
	)
	(zone
		(net "P12V_HDD12")
		(layer "F.Cu")
		(hatch none 0.5)
		(connect_pads
			(clearance 0.5)
		)
		(min_thickness 0.25)
		(fill yes
			(thermal_gap 0.5)
			(thermal_bridge_width 0.5)
			(island_removal_mode 0)
		)
		(polygon
			(pts
				(xy 12.319 -147.193) (xy 12.065 -147.447) (xy 12.065 -149.098) (xy 12.319 -149.352) (xy 14.478 -149.352)
				(xy 14.986 -149.86) (xy 14.986 -152.4) (xy 22.733 -160.147) (xy 31.242 -160.147) (xy 31.369 -160.02)
				(xy 31.369 -158.242) (xy 31.242 -158.115) (xy 25.273 -158.115) (xy 24.638 -157.48) (xy 22.987 -157.48)
				(xy 18.669 -153.162) (xy 18.669 -149.744938) (xy 17.526 -148.601938) (xy 17.526 -147.447) (xy 17.272 -147.193)
			)
		)
		(polygon
			(pts
				(xy 24.7904 -159.1564) (xy 24.5872 -159.1564) (xy 24.5872 -159.3596) (xy 24.7904 -159.3596)
			)
		)
		(polygon
			(pts
				(xy 23.9268 -159.1564) (xy 23.7236 -159.1564) (xy 23.7236 -159.3596) (xy 23.9268 -159.3596)
			)
		)
	)
	(zone
		(layer "F.Cu")
		(hatch none 0.5)
		(connect_pads
			(clearance 0)
		)
		(min_thickness 0.25)
		(keepout
			(tracks allowed)
			(vias allowed)
			(pads allowed)
			(copperpour allowed)
			(footprints allowed)
		)
		(placement
			(enabled no)
			(sheetname "")
		)
		(fill
			(thermal_gap 0.5)
			(thermal_bridge_width 0.5)
			(island_removal_mode 0)
		)
		(polygon
			(pts
				(xy 458.353922 -19.667728) (xy 458.353922 -21.259038) (xy 456.445874 -21.259038) (xy 456.445874 -19.667728)
			)
		)
	)
	(zone
		(net "P12V_B")
		(layer "F.Cu")
		(hatch none 0.5)
		(connect_pads
			(clearance 0.5)
		)
		(min_thickness 0.25)
		(fill yes
			(thermal_gap 0.5)
			(thermal_bridge_width 0.5)
			(island_removal_mode 0)
		)
		(polygon
			(pts
				(xy 169.799 -19.812) (xy 169.545 -20.066) (xy 169.545 -22.606) (xy 169.799 -22.86) (xy 173.101 -22.86)
				(xy 173.355 -22.606) (xy 173.355 -20.32) (xy 172.847 -19.812)
			)
		)
	)
	(zone
		(layer "F.Cu")
		(hatch none 0.5)
		(connect_pads
			(clearance 0)
		)
		(min_thickness 0.25)
		(keepout
			(tracks not_allowed)
			(vias allowed)
			(pads allowed)
			(copperpour not_allowed)
			(footprints allowed)
		)
		(placement
			(enabled no)
			(sheetname "")
		)
		(fill
			(thermal_gap 0.5)
			(thermal_bridge_width 0.5)
			(island_removal_mode 0)
		)
		(polygon
			(pts
				(arc
					(start 355.624892 -248.115328)
					(mid 355.139879 -247.629934)
					(end 354.654612 -248.115074)
				)
				(arc
					(start 354.654612 -249.385074)
					(mid 355.139752 -249.870214)
					(end 355.624892 -249.385074)
				)
				(xy 355.624892 -248.972324)
				(arc
					(start 355.266752 -248.972324)
					(mid 355.230831 -248.987203)
					(end 355.215952 -249.023124)
				)
				(arc
					(start 355.215952 -249.12955)
					(mid 355.139752 -249.651718)
					(end 355.063552 -249.12955)
				)
				(xy 355.063552 -248.991628)
				(arc
					(start 355.0666 -248.98858)
					(mid 355.123131 -248.879503)
					(end 355.232208 -248.822972)
				)
				(xy 355.235256 -248.819924) (xy 355.624892 -248.819924) (xy 355.624892 -248.680224) (xy 355.235256 -248.680224)
				(arc
					(start 355.232208 -248.677176)
					(mid 355.123131 -248.620645)
					(end 355.0666 -248.511568)
				)
				(xy 355.063552 -248.50852)
				(arc
					(start 355.063552 -248.370598)
					(mid 355.139752 -247.84843)
					(end 355.215952 -248.370598)
				)
				(arc
					(start 355.215952 -248.477024)
					(mid 355.230831 -248.512945)
					(end 355.266752 -248.527824)
				)
				(xy 355.624892 -248.527824)
			)
		)
	)
	(zone
		(layer "F.Cu")
		(hatch none 0.5)
		(connect_pads
			(clearance 0)
		)
		(min_thickness 0.25)
		(keepout
			(tracks allowed)
			(vias allowed)
			(pads allowed)
			(copperpour allowed)
			(footprints not_allowed)
		)
		(placement
			(enabled no)
			(sheetname "")
		)
		(fill
			(thermal_gap 0.5)
			(thermal_bridge_width 0.5)
			(island_removal_mode 0)
		)
		(polygon
			(pts
				(xy 417.699952 -370.000022) (xy 363.70006 -370.000022) (xy 363.70006 -380.000002) (xy 417.699952 -380.000002)
			)
		)
	)
	(zone
		(layer "F.Cu")
		(hatch none 0.5)
		(connect_pads
			(clearance 0)
		)
		(min_thickness 0.25)
		(keepout
			(tracks allowed)
			(vias allowed)
			(pads allowed)
			(copperpour allowed)
			(footprints allowed)
		)
		(placement
			(enabled no)
			(sheetname "")
		)
		(fill
			(thermal_gap 0.5)
			(thermal_bridge_width 0.5)
			(island_removal_mode 0)
		)
		(polygon
			(pts
				(xy 244.856 -304.6476) (xy 244.856 -305.3334) (xy 242.3414 -305.3334) (xy 242.3414 -303.7078) (xy 244.475 -303.7078)
				(xy 244.602 -303.5808) (xy 244.602 -302.2092) (xy 244.8052 -302.006) (xy 245.2116 -302.006) (xy 245.364 -302.1584)
				(xy 245.364 -304.2412) (xy 245.237 -304.3682) (xy 245.1354 -304.3682)
			)
		)
	)
	(zone
		(net "GND")
		(layer "F.Cu")
		(hatch none 0.5)
		(connect_pads
			(clearance 0.5)
		)
		(min_thickness 0.25)
		(fill yes
			(thermal_gap 0.5)
			(thermal_bridge_width 0.5)
			(island_removal_mode 0)
		)
		(polygon
			(pts
				(xy 268.821916 -126.70536) (xy 259.627624 -135.899652) (xy 259.627624 -140.058902) (xy 259.910072 -140.34135)
				(xy 261.19582 -140.34135) (xy 264.287 -137.25017) (xy 271.449038 -137.25017)
				(arc
					(start 272.94459 -135.754618)
					(mid 273.040458 -134.801276)
					(end 273.350228 -133.894576)
				)
				(arc
					(start 273.350228 -133.894576)
					(mid 273.592321 -129.855046)
					(end 277.136606 -127.901954)
				)
				(xy 277.860252 -127.901954) (xy 278.029416 -127.73279)
				(arc
					(start 278.029416 -127.266446)
					(mid 277.636572 -127.007603)
					(end 277.276052 -126.70536)
				)
			)
		)
	)
	(zone
		(net "P12V_HDD5")
		(layer "F.Cu")
		(hatch none 0.5)
		(connect_pads
			(clearance 0.5)
		)
		(min_thickness 0.25)
		(fill yes
			(thermal_gap 0.5)
			(thermal_bridge_width 0.5)
			(island_removal_mode 0)
		)
		(polygon
			(pts
				(xy 170.053 -262.255) (xy 169.799 -262.509) (xy 169.799 -264.16) (xy 170.053 -264.414) (xy 172.212 -264.414)
				(xy 172.72 -264.922) (xy 172.72 -267.462) (xy 180.467 -275.209) (xy 188.976 -275.209) (xy 189.103 -275.082)
				(xy 189.103 -273.304) (xy 188.976 -273.177) (xy 183.007 -273.177) (xy 182.372 -272.542) (xy 180.721 -272.542)
				(xy 176.403 -268.224) (xy 176.403 -264.668) (xy 175.26 -263.525) (xy 175.26 -262.509) (xy 175.006 -262.255)
			)
		)
		(polygon
			(pts
				(xy 182.5244 -274.2184) (xy 182.3212 -274.2184) (xy 182.3212 -274.4216) (xy 182.5244 -274.4216)
			)
		)
		(polygon
			(pts
				(xy 181.6608 -274.2184) (xy 181.4576 -274.2184) (xy 181.4576 -274.4216) (xy 181.6608 -274.4216)
			)
		)
	)
	(zone
		(net "P12V_B")
		(layer "F.Cu")
		(hatch none 0.5)
		(connect_pads
			(clearance 0.5)
		)
		(min_thickness 0.25)
		(fill yes
			(thermal_gap 0.5)
			(thermal_bridge_width 0.5)
			(island_removal_mode 0)
		)
		(polygon
			(pts
				(xy 203.668122 -105.535984) (xy 203.414122 -105.789984) (xy 203.414122 -109.472984) (xy 203.668122 -109.726984)
				(xy 210.272122 -109.726984) (xy 210.526122 -109.472984) (xy 210.526122 -105.789984) (xy 210.272122 -105.535984)
			)
		)
	)
	(zone
		(net "P3V3_STBY_B")
		(layer "F.Cu")
		(hatch none 0.5)
		(connect_pads
			(clearance 0.5)
		)
		(min_thickness 0.25)
		(fill yes
			(thermal_gap 0.5)
			(thermal_bridge_width 0.5)
			(island_removal_mode 0)
		)
		(polygon
			(pts
				(xy 246.761 -133.731) (xy 246.38 -134.112) (xy 246.38 -136.8806) (xy 246.53113 -137.03173) (xy 248.25833 -137.03173)
				(xy 248.3739 -136.91616) (xy 248.3739 -135.0899) (xy 248.92 -134.5438) (xy 248.92 -133.8707) (xy 248.7803 -133.731)
			)
		)
		(polygon
			(pts
				(xy 247.400572 -135.995918) (xy 247.197372 -135.995918) (xy 247.197372 -136.199118) (xy 247.400572 -136.199118)
			)
		)
		(polygon
			(pts
				(xy 247.865138 -135.682482) (xy 247.661938 -135.682482) (xy 247.661938 -135.885682) (xy 247.865138 -135.885682)
			)
		)
		(polygon
			(pts
				(xy 247.400572 -135.132318) (xy 247.197372 -135.132318) (xy 247.197372 -135.335518) (xy 247.400572 -135.335518)
			)
		)
		(polygon
			(pts
				(xy 247.865138 -135.072882) (xy 247.661938 -135.072882) (xy 247.661938 -135.276082) (xy 247.865138 -135.276082)
			)
		)
	)
	(zone
		(net "5V_PRE_30")
		(layer "F.Cu")
		(hatch none 0.5)
		(connect_pads
			(clearance 0.5)
		)
		(min_thickness 0.25)
		(fill yes
			(thermal_gap 0.5)
			(thermal_bridge_width 0.5)
			(island_removal_mode 0)
		)
		(polygon
			(pts
				(xy 329.438 -30.988) (xy 329.184 -31.242) (xy 329.184 -33.782) (xy 328.803 -34.163) (xy 326.263 -34.163)
				(xy 326.009 -34.417) (xy 326.009 -34.798) (xy 326.263 -35.052) (xy 329.565 -35.052) (xy 330.835 -33.782)
				(xy 330.835 -31.242) (xy 330.581 -30.988)
			)
		)
	)
	(zone
		(net "5V_PRE_22")
		(layer "F.Cu")
		(hatch none 0.5)
		(connect_pads
			(clearance 0.5)
		)
		(min_thickness 0.25)
		(fill yes
			(thermal_gap 0.5)
			(thermal_bridge_width 0.5)
			(island_removal_mode 0)
		)
		(polygon
			(pts
				(xy 455.549 -146.05) (xy 455.295 -146.304) (xy 455.295 -148.844) (xy 454.914 -149.225) (xy 452.374 -149.225)
				(xy 452.12 -149.479) (xy 452.12 -149.86) (xy 452.374 -150.114) (xy 455.676 -150.114) (xy 456.946 -148.844)
				(xy 456.946 -146.304) (xy 456.692 -146.05)
			)
		)
	)
	(zone
		(net "P5V_HDD17")
		(layer "F.Cu")
		(hatch none 0.5)
		(connect_pads
			(clearance 0.5)
		)
		(min_thickness 0.25)
		(fill yes
			(thermal_gap 0.5)
			(thermal_bridge_width 0.5)
			(island_removal_mode 0)
		)
		(polygon
			(pts
				(xy 177.419 -142.621) (xy 177.165 -142.875) (xy 177.165 -145.161) (xy 177.419 -145.415) (xy 177.419 -147.447)
				(xy 178.181 -148.209) (xy 178.181 -148.971) (xy 178.562 -149.352) (xy 178.943 -149.352) (xy 182.118 -152.527)
				(xy 188.976 -152.527) (xy 189.103 -152.4) (xy 189.103 -150.622) (xy 188.976 -150.495) (xy 183.896 -150.495)
				(xy 181.991 -148.59) (xy 181.102 -148.59) (xy 180.213 -147.701) (xy 180.213 -145.161) (xy 180.848 -144.526)
				(xy 180.848 -142.875) (xy 180.594 -142.621)
			)
		)
		(polygon
			(pts
				(xy 179.2478 -149.0472) (xy 179.0446 -149.0472) (xy 179.0446 -149.2504) (xy 179.2478 -149.2504)
			)
		)
		(polygon
			(pts
				(xy 179.2478 -148.1836) (xy 179.0446 -148.1836) (xy 179.0446 -148.3868) (xy 179.2478 -148.3868)
			)
		)
	)
	(zone
		(net "P12V_HDD22")
		(layer "F.Cu")
		(hatch none 0.5)
		(connect_pads
			(clearance 0.5)
		)
		(min_thickness 0.25)
		(fill yes
			(thermal_gap 0.5)
			(thermal_bridge_width 0.5)
			(island_removal_mode 0)
		)
		(polygon
			(pts
				(xy 460.756 -149.606) (xy 460.502 -149.86) (xy 460.502 -153.6446) (xy 459.9559 -154.1907) (xy 459.9559 -156.4259)
				(xy 458.2668 -158.115) (xy 452.374 -158.115) (xy 452.12 -158.369) (xy 452.12 -160.02) (xy 452.374 -160.274)
				(xy 456.311 -160.274) (xy 456.819 -159.766) (xy 464.566 -159.766) (xy 465.455 -158.877) (xy 465.455 -149.86)
				(xy 465.201 -149.606)
			)
		)
		(polygon
			(pts
				(xy 456.4634 -159.1564) (xy 456.2602 -159.1564) (xy 456.2602 -159.3596) (xy 456.4634 -159.3596)
			)
		)
		(polygon
			(pts
				(xy 455.5998 -159.1564) (xy 455.3966 -159.1564) (xy 455.3966 -159.3596) (xy 455.5998 -159.3596)
			)
		)
	)
	(zone
		(net "P12V_B")
		(layer "F.Cu")
		(hatch none 0.5)
		(connect_pads
			(clearance 0.5)
		)
		(min_thickness 0.25)
		(fill yes
			(thermal_gap 0.5)
			(thermal_bridge_width 0.5)
			(island_removal_mode 0)
		)
		(polygon
			(pts
				(xy 45.847 -255.143) (xy 44.831 -256.159) (xy 44.196 -256.159) (xy 43.815 -256.54) (xy 43.815 -259.08)
				(xy 44.069 -259.334) (xy 47.371 -259.334) (xy 47.625 -259.08) (xy 47.625 -256.794) (xy 46.99 -256.159)
				(xy 46.609 -256.159) (xy 46.355 -255.905) (xy 46.355 -255.27) (xy 46.228 -255.143)
			)
		)
		(polygon
			(pts
				(xy 45.8216 -255.7272) (xy 45.6184 -255.7272) (xy 45.6184 -255.9304) (xy 45.8216 -255.9304)
			)
		)
	)
	(zone
		(layer "F.Cu")
		(hatch none 0.5)
		(connect_pads
			(clearance 0)
		)
		(min_thickness 0.25)
		(keepout
			(tracks not_allowed)
			(vias allowed)
			(pads allowed)
			(copperpour not_allowed)
			(footprints allowed)
		)
		(placement
			(enabled no)
			(sheetname "")
		)
		(fill
			(thermal_gap 0.5)
			(thermal_bridge_width 0.5)
			(island_removal_mode 0)
		)
		(polygon
			(pts
				(arc
					(start 64.54394 -18.11528)
					(mid 64.058927 -17.629886)
					(end 63.57366 -18.115026)
				)
				(xy 63.57366 -18.527776)
				(arc
					(start 63.9318 -18.527776)
					(mid 63.967721 -18.512897)
					(end 63.9826 -18.476976)
				)
				(arc
					(start 63.9826 -18.37055)
					(mid 64.0588 -17.848382)
					(end 64.135 -18.37055)
				)
				(xy 64.135 -18.508472)
				(arc
					(start 64.131952 -18.51152)
					(mid 64.075421 -18.620597)
					(end 63.966344 -18.677128)
				)
				(xy 63.963296 -18.680176) (xy 63.57366 -18.680176) (xy 63.57366 -18.819876) (xy 63.963296 -18.819876)
				(arc
					(start 63.966344 -18.822924)
					(mid 64.075421 -18.879455)
					(end 64.131952 -18.988532)
				)
				(xy 64.135 -18.99158)
				(arc
					(start 64.135 -19.129502)
					(mid 64.0588 -19.65167)
					(end 63.9826 -19.129502)
				)
				(arc
					(start 63.9826 -19.023076)
					(mid 63.967721 -18.987155)
					(end 63.9318 -18.972276)
				)
				(xy 63.57366 -18.972276)
				(arc
					(start 63.57366 -19.385026)
					(mid 64.0588 -19.870166)
					(end 64.54394 -19.385026)
				)
			)
		)
	)
	(zone
		(net "P5V_HDD16")
		(layer "F.Cu")
		(hatch none 0.5)
		(connect_pads
			(clearance 0.5)
		)
		(min_thickness 0.25)
		(fill yes
			(thermal_gap 0.5)
			(thermal_bridge_width 0.5)
			(island_removal_mode 0)
		)
		(polygon
			(pts
				(xy 145.923 -142.621) (xy 145.669 -142.875) (xy 145.669 -145.161) (xy 145.923 -145.415) (xy 145.923 -147.447)
				(xy 146.685 -148.209) (xy 146.685 -149.0726) (xy 147.0406 -149.4282) (xy 147.5232 -149.4282) (xy 150.622 -152.527)
				(xy 157.48 -152.527) (xy 157.607 -152.4) (xy 157.607 -150.622) (xy 157.48 -150.495) (xy 152.4 -150.495)
				(xy 150.495 -148.59) (xy 149.606 -148.59) (xy 148.717 -147.701) (xy 148.717 -145.161) (xy 149.352 -144.526)
				(xy 149.352 -142.875) (xy 149.098 -142.621)
			)
		)
		(polygon
			(pts
				(xy 147.6756 -149.0472) (xy 147.4724 -149.0472) (xy 147.4724 -149.2504) (xy 147.6756 -149.2504)
			)
		)
		(polygon
			(pts
				(xy 147.6756 -148.1836) (xy 147.4724 -148.1836) (xy 147.4724 -148.3868) (xy 147.6756 -148.3868)
			)
		)
	)
	(zone
		(net "P5V_B_4")
		(layer "F.Cu")
		(hatch none 0.5)
		(connect_pads
			(clearance 0.5)
		)
		(min_thickness 0.25)
		(fill yes
			(thermal_gap 0.5)
			(thermal_bridge_width 0.5)
			(island_removal_mode 0)
		)
		(polygon
			(pts
				(xy 473.456 -136.779) (xy 473.202 -137.033) (xy 473.202 -139.319) (xy 473.456 -139.573) (xy 478.155 -139.573)
				(xy 478.409 -139.319) (xy 478.409 -137.033) (xy 478.155 -136.779)
			)
		)
	)
	(zone
		(net "GND")
		(layer "F.Cu")
		(hatch none 0.5)
		(connect_pads
			(clearance 0.5)
		)
		(min_thickness 0.25)
		(fill yes
			(thermal_gap 0.5)
			(thermal_bridge_width 0.5)
			(island_removal_mode 0)
		)
		(polygon
			(pts
				(xy 284.615128 -333.671672) (xy 284.353 -333.9338) (xy 284.353 -335.3308) (xy 284.48 -335.4578)
				(xy 287.909 -335.4578) (xy 288.036 -335.3308) (xy 288.036 -334.0608) (xy 287.646872 -333.671672)
			)
		)
		(polygon
			(pts
				(xy 287.86201 -334.56118) (xy 287.65881 -334.56118) (xy 287.65881 -334.76438) (xy 287.86201 -334.76438)
			)
		)
		(polygon
			(pts
				(xy 286.99841 -334.56118) (xy 286.79521 -334.56118) (xy 286.79521 -334.76438) (xy 286.99841 -334.76438)
			)
		)
		(polygon
			(pts
				(xy 286.31261 -334.18018) (xy 286.10941 -334.18018) (xy 286.10941 -334.38338) (xy 286.31261 -334.38338)
			)
		)
		(polygon
			(pts
				(xy 285.70301 -334.18018) (xy 285.49981 -334.18018) (xy 285.49981 -334.38338) (xy 285.70301 -334.38338)
			)
		)
	)
	(zone
		(layer "F.Cu")
		(hatch none 0.5)
		(connect_pads
			(clearance 0)
		)
		(min_thickness 0.25)
		(keepout
			(tracks allowed)
			(vias allowed)
			(pads allowed)
			(copperpour allowed)
			(footprints not_allowed)
		)
		(placement
			(enabled no)
			(sheetname "")
		)
		(fill
			(thermal_gap 0.5)
			(thermal_bridge_width 0.5)
			(island_removal_mode 0)
		)
		(polygon
			(pts
				(arc
					(start 113.82502 -181.799992)
					(mid 127.824992 -167.80002)
					(end 141.824964 -181.799992)
				)
				(arc
					(start 141.824964 -181.799992)
					(mid 127.824992 -195.799964)
					(end 113.82502 -181.799992)
				)
			)
		)
	)
	(zone
		(layer "F.Cu")
		(hatch none 0.5)
		(connect_pads
			(clearance 0)
		)
		(min_thickness 0.25)
		(keepout
			(tracks not_allowed)
			(vias allowed)
			(pads allowed)
			(copperpour not_allowed)
			(footprints allowed)
		)
		(placement
			(enabled no)
			(sheetname "")
		)
		(fill
			(thermal_gap 0.5)
			(thermal_bridge_width 0.5)
			(island_removal_mode 0)
		)
		(polygon
			(pts
				(arc
					(start 159.193992 -133.11505)
					(mid 158.708852 -132.62991)
					(end 158.223712 -133.11505)
				)
				(xy 158.223712 -133.5278)
				(arc
					(start 158.581852 -133.5278)
					(mid 158.617773 -133.512921)
					(end 158.632652 -133.477)
				)
				(arc
					(start 158.632652 -133.370574)
					(mid 158.708852 -132.848406)
					(end 158.785052 -133.370574)
				)
				(xy 158.785052 -133.508496)
				(arc
					(start 158.782004 -133.511544)
					(mid 158.725473 -133.620621)
					(end 158.616396 -133.677152)
				)
				(xy 158.613348 -133.6802) (xy 158.223712 -133.6802) (xy 158.223712 -133.8199) (xy 158.613348 -133.8199)
				(arc
					(start 158.616396 -133.822948)
					(mid 158.725473 -133.879479)
					(end 158.782004 -133.988556)
				)
				(xy 158.785052 -133.991604)
				(arc
					(start 158.785052 -134.129526)
					(mid 158.708852 -134.651694)
					(end 158.632652 -134.129526)
				)
				(arc
					(start 158.632652 -134.0231)
					(mid 158.617773 -133.987179)
					(end 158.581852 -133.9723)
				)
				(xy 158.223712 -133.9723)
				(arc
					(start 158.223712 -134.384796)
					(mid 158.708725 -134.87019)
					(end 159.193992 -134.38505)
				)
			)
		)
	)
	(zone
		(net "P5V_HDD24")
		(layer "F.Cu")
		(hatch none 0.5)
		(connect_pads
			(clearance 0.5)
		)
		(min_thickness 0.25)
		(fill yes
			(thermal_gap 0.5)
			(thermal_bridge_width 0.5)
			(island_removal_mode 0)
		)
		(polygon
			(pts
				(xy 19.685 -27.686) (xy 19.431 -27.94) (xy 19.431 -30.226) (xy 19.685 -30.48) (xy 19.685 -32.512)
				(xy 20.447 -33.274) (xy 20.447 -34.277808) (xy 20.713192 -34.544) (xy 21.336 -34.544) (xy 24.384 -37.592)
				(xy 31.242 -37.592) (xy 31.369 -37.465) (xy 31.369 -35.687) (xy 31.242 -35.56) (xy 26.162 -35.56)
				(xy 24.257 -33.655) (xy 23.368 -33.655) (xy 22.479 -32.766) (xy 22.479 -30.226) (xy 23.114 -29.591)
				(xy 23.114 -27.94) (xy 22.86 -27.686)
			)
		)
		(polygon
			(pts
				(xy 21.4376 -34.1122) (xy 21.2344 -34.1122) (xy 21.2344 -34.3154) (xy 21.4376 -34.3154)
			)
		)
		(polygon
			(pts
				(xy 21.4376 -33.2486) (xy 21.2344 -33.2486) (xy 21.2344 -33.4518) (xy 21.4376 -33.4518)
			)
		)
	)
	(zone
		(layer "F.Cu")
		(hatch none 0.5)
		(connect_pads
			(clearance 0)
		)
		(min_thickness 0.25)
		(keepout
			(tracks allowed)
			(vias allowed)
			(pads allowed)
			(copperpour allowed)
			(footprints allowed)
		)
		(placement
			(enabled no)
			(sheetname "")
		)
		(fill
			(thermal_gap 0.5)
			(thermal_bridge_width 0.5)
			(island_removal_mode 0)
		)
		(polygon
			(pts
				(xy 99.840796 -358.223312) (xy 99.840796 -357.05288) (xy 102.262432 -357.05288) (xy 102.262432 -358.223312)
			)
		)
	)
	(zone
		(net "P3V3_STBY_B")
		(layer "F.Cu")
		(hatch none 0.5)
		(connect_pads
			(clearance 0.5)
		)
		(min_thickness 0.25)
		(fill yes
			(thermal_gap 0.5)
			(thermal_bridge_width 0.5)
			(island_removal_mode 0)
		)
		(polygon
			(pts
				(xy 247.82018 -140.32992) (xy 247.75922 -140.39088) (xy 247.60428 -140.39088) (xy 247.09374 -140.90142)
				(xy 247.09374 -143.50746) (xy 247.26519 -143.67891) (xy 247.56745 -143.67891) (xy 247.57634 -143.6878)
				(xy 248.97334 -143.6878) (xy 249.01398 -143.64716) (xy 249.01398 -142.72514) (xy 248.75998 -142.47114)
				(xy 248.75998 -141.23924) (xy 249.3645 -140.63472) (xy 249.3645 -140.37818) (xy 249.31624 -140.32992)
			)
		)
		(polygon
			(pts
				(xy 248.219214 -142.674594) (xy 248.016014 -142.674594) (xy 248.016014 -142.877794) (xy 248.219214 -142.877794)
			)
		)
		(polygon
			(pts
				(xy 248.229374 -142.359634) (xy 248.026174 -142.359634) (xy 248.026174 -142.562834) (xy 248.229374 -142.562834)
			)
		)
		(polygon
			(pts
				(xy 248.229374 -141.750034) (xy 248.026174 -141.750034) (xy 248.026174 -141.953234) (xy 248.229374 -141.953234)
			)
		)
	)
	(zone
		(layer "F.Cu")
		(hatch none 0.5)
		(connect_pads
			(clearance 0)
		)
		(min_thickness 0.25)
		(keepout
			(tracks not_allowed)
			(vias allowed)
			(pads allowed)
			(copperpour not_allowed)
			(footprints allowed)
		)
		(placement
			(enabled no)
			(sheetname "")
		)
		(fill
			(thermal_gap 0.5)
			(thermal_bridge_width 0.5)
			(island_removal_mode 0)
		)
		(polygon
			(pts
				(arc
					(start 414.527492 -244.444774)
					(mid 414.042352 -243.959634)
					(end 413.557212 -244.444774)
				)
				(arc
					(start 413.557212 -245.58752)
					(mid 414.042225 -246.072914)
					(end 414.527492 -245.587774)
				)
				(xy 414.527492 -245.238524)
				(arc
					(start 414.208976 -245.238524)
					(mid 414.145037 -245.265009)
					(end 414.118552 -245.328948)
				)
				(arc
					(start 414.118552 -245.33225)
					(mid 414.042352 -245.854418)
					(end 413.966152 -245.33225)
				)
				(xy 413.966152 -245.297452)
				(arc
					(start 413.968438 -245.294912)
					(mid 414.037196 -245.157168)
					(end 414.17494 -245.08841)
				)
				(xy 414.17748 -245.086124) (xy 414.527492 -245.086124) (xy 414.527492 -244.946424) (xy 414.17748 -244.946424)
				(arc
					(start 414.17494 -244.944138)
					(mid 414.037196 -244.87538)
					(end 413.968438 -244.737636)
				)
				(xy 413.966152 -244.735096)
				(arc
					(start 413.966152 -244.700298)
					(mid 414.042352 -244.17813)
					(end 414.118552 -244.700298)
				)
				(arc
					(start 414.118552 -244.7036)
					(mid 414.145037 -244.767539)
					(end 414.208976 -244.794024)
				)
				(xy 414.527492 -244.794024)
			)
		)
	)
	(zone
		(net "GND")
		(layer "F.Cu")
		(hatch none 0.5)
		(connect_pads
			(clearance 0.5)
		)
		(min_thickness 0.25)
		(fill yes
			(thermal_gap 0.5)
			(thermal_bridge_width 0.5)
			(island_removal_mode 0)
		)
		(polygon
			(pts
				(xy 344.163142 -250.423426) (xy 344.163142 -250.43765)
				(arc
					(start 343.85504 -250.745752)
					(mid 343.815772 -251.087055)
					(end 343.74836 -251.423932)
				)
				(arc
					(start 343.74836 -257.1115)
					(mid 343.646445 -257.996861)
					(end 343.346024 -258.835906)
				)
				(xy 343.346024 -275.198586) (xy 340.031578 -278.513032)
				(arc
					(start 340.031578 -288.36366)
					(mid 341.123576 -290.9848)
					(end 341.496142 -293.799768)
				)
				(xy 341.496142 -307.555392) (xy 343.947496 -310.006746) (xy 380.355602 -310.006746) (xy 382.853692 -307.508656)
				(arc
					(start 382.853692 -293.799768)
					(mid 383.02665 -291.872731)
					(end 383.54 -290.007294)
				)
				(xy 383.54 -276.991572) (xy 376.934476 -270.386048) (xy 376.934476 -257.092196) (xy 376.32386 -256.48158)
				(xy 375.626884 -256.48158) (xy 375.24436 -256.864104)
				(arc
					(start 375.24436 -257.1115)
					(mid 375.142445 -257.996861)
					(end 374.842024 -258.835906)
				)
				(xy 374.842024 -275.198586) (xy 369.610386 -280.430224)
				(arc
					(start 367.393474 -280.430224)
					(mid 366.256814 -281.006432)
					(end 364.998 -281.204924)
				)
				(xy 363.717586 -281.204924)
				(arc
					(start 362.872782 -282.049728)
					(mid 362.594332 -282.705491)
					(end 362.206286 -283.302964)
				)
				(xy 362.206286 -285.891224) (xy 351.993962 -285.891224) (xy 351.993962 -275.6789) (xy 350.400874 -274.085812)
				(xy 349.037402 -274.085812) (xy 346.616274 -271.664684) (xy 346.616274 -270.505936)
				(arc
					(start 346.624148 -270.498062)
					(mid 346.555842 -269.946565)
					(end 346.560648 -269.390876)
				)
				(xy 346.560648 -267.341096) (xy 345.489276 -266.269724) (xy 345.489276 -255.674368) (xy 345.83624 -255.327404)
				(xy 345.83624 -251.220478) (xy 345.039188 -250.423426)
			)
		)
	)
	(zone
		(layer "F.Cu")
		(hatch none 0.5)
		(connect_pads
			(clearance 0)
		)
		(min_thickness 0.25)
		(keepout
			(tracks allowed)
			(vias allowed)
			(pads allowed)
			(copperpour allowed)
			(footprints allowed)
		)
		(placement
			(enabled no)
			(sheetname "")
		)
		(fill
			(thermal_gap 0.5)
			(thermal_bridge_width 0.5)
			(island_removal_mode 0)
		)
		(polygon
			(pts
				(xy 284.075632 -355.9302) (xy 284.075632 -354.3046) (xy 286.590232 -354.3046) (xy 286.590232 -355.9302)
			)
		)
	)
	(zone
		(layer "F.Cu")
		(hatch none 0.5)
		(connect_pads
			(clearance 0)
		)
		(min_thickness 0.25)
		(keepout
			(tracks not_allowed)
			(vias allowed)
			(pads allowed)
			(copperpour not_allowed)
			(footprints allowed)
		)
		(placement
			(enabled no)
			(sheetname "")
		)
		(fill
			(thermal_gap 0.5)
			(thermal_bridge_width 0.5)
			(island_removal_mode 0)
		)
		(polygon
			(pts
				(arc
					(start 237.199932 -175.800004)
					(mid 244.199918 -168.800018)
					(end 251.199904 -175.800004)
				)
				(arc
					(start 251.199904 -181.799992)
					(mid 244.199918 -188.799978)
					(end 237.199932 -181.799992)
				)
			)
		)
	)
	(zone
		(net "GND")
		(layer "F.Cu")
		(hatch none 0.5)
		(connect_pads
			(clearance 0.5)
		)
		(min_thickness 0.25)
		(fill yes
			(thermal_gap 0.5)
			(thermal_bridge_width 0.5)
			(island_removal_mode 0)
		)
		(polygon
			(pts
				(xy 148.76907 -73.682606) (xy 148.438108 -74.013568)
				(arc
					(start 148.438108 -89.079324)
					(mid 148.641443 -90.361008)
					(end 148.438108 -91.642692)
				)
				(xy 148.438108 -94.3356) (xy 148.7932 -94.3356) (xy 148.7932 -103.486712) (xy 150.858728 -105.55224)
				(xy 160.807654 -105.55224) (xy 161.7726 -104.587294)
				(arc
					(start 161.7726 -103.377238)
					(mid 160.392209 -101.919792)
					(end 159.890206 -99.976178)
				)
				(arc
					(start 159.890206 -99.620578)
					(mid 160.003003 -98.675951)
					(end 160.33496 -97.784412)
				)
				(arc
					(start 160.33496 -94.731078)
					(mid 160.634651 -93.224342)
					(end 161.48812 -91.946984)
				)
				(arc
					(start 162.34918 -91.085924)
					(mid 163.064496 -90.083824)
					(end 164.042852 -89.336372)
				)
				(xy 164.042852 -80.504538) (xy 163.720526 -80.182212)
				(arc
					(start 162.3568 -80.182212)
					(mid 154.623815 -79.541215)
					(end 149.308058 -73.8886)
				)
				(xy 149.102064 -73.682606)
			)
		)
	)
	(zone
		(net "5V_PRE_1")
		(layer "F.Cu")
		(hatch none 0.5)
		(connect_pads
			(clearance 0.5)
		)
		(min_thickness 0.25)
		(fill yes
			(thermal_gap 0.5)
			(thermal_bridge_width 0.5)
			(island_removal_mode 0)
		)
		(polygon
			(pts
				(xy 54.5084 -260.962648) (xy 54.356 -261.115048) (xy 54.356 -262.512048) (xy 54.9402 -263.096248)
				(xy 56.2102 -263.096248) (xy 58.293 -265.179048) (xy 62.738 -265.179048) (xy 62.865 -265.052048)
				(xy 62.865 -264.290048) (xy 62.738 -264.163048) (xy 59.7154 -264.163048) (xy 56.515 -260.962648)
			)
		)
	)
	(zone
		(layer "F.Cu")
		(hatch none 0.5)
		(connect_pads
			(clearance 0)
		)
		(min_thickness 0.25)
		(keepout
			(tracks not_allowed)
			(vias allowed)
			(pads allowed)
			(copperpour not_allowed)
			(footprints allowed)
		)
		(placement
			(enabled no)
			(sheetname "")
		)
		(fill
			(thermal_gap 0.5)
			(thermal_bridge_width 0.5)
			(island_removal_mode 0)
		)
		(polygon
			(pts
				(arc
					(start 32.994092 -248.115328)
					(mid 32.509079 -247.629934)
					(end 32.023812 -248.115074)
				)
				(xy 32.023812 -248.527824)
				(arc
					(start 32.381952 -248.527824)
					(mid 32.417873 -248.512945)
					(end 32.432752 -248.477024)
				)
				(arc
					(start 32.432752 -248.370598)
					(mid 32.508952 -247.84843)
					(end 32.585152 -248.370598)
				)
				(xy 32.585152 -248.50852)
				(arc
					(start 32.582104 -248.511568)
					(mid 32.525573 -248.620645)
					(end 32.416496 -248.677176)
				)
				(xy 32.413448 -248.680224) (xy 32.023812 -248.680224) (xy 32.023812 -248.819924) (xy 32.413448 -248.819924)
				(arc
					(start 32.416496 -248.822972)
					(mid 32.525573 -248.879503)
					(end 32.582104 -248.98858)
				)
				(xy 32.585152 -248.991628)
				(arc
					(start 32.585152 -249.12955)
					(mid 32.508952 -249.651718)
					(end 32.432752 -249.12955)
				)
				(arc
					(start 32.432752 -249.023124)
					(mid 32.417873 -248.987203)
					(end 32.381952 -248.972324)
				)
				(xy 32.023812 -248.972324)
				(arc
					(start 32.023812 -249.385074)
					(mid 32.508952 -249.870214)
					(end 32.994092 -249.385074)
				)
			)
		)
	)
	(zone
		(net "P5V_HDD31")
		(layer "F.Cu")
		(hatch none 0.5)
		(connect_pads
			(clearance 0.5)
		)
		(min_thickness 0.25)
		(fill yes
			(thermal_gap 0.5)
			(thermal_bridge_width 0.5)
			(island_removal_mode 0)
		)
		(polygon
			(pts
				(xy 363.093 -22.733) (xy 362.839 -22.987) (xy 362.839 -33.782) (xy 361.188 -35.433) (xy 357.759 -35.433)
				(xy 357.505 -35.687) (xy 357.505 -37.338) (xy 357.759 -37.592) (xy 362.331 -37.592) (xy 362.966 -36.957)
				(xy 364.744 -36.957) (xy 365.252 -36.449) (xy 365.252 -22.987) (xy 364.998 -22.733)
			)
		)
		(polygon
			(pts
				(xy 361.8484 -36.6014) (xy 361.6452 -36.6014) (xy 361.6452 -36.8046) (xy 361.8484 -36.8046)
			)
		)
		(polygon
			(pts
				(xy 360.9848 -36.6014) (xy 360.7816 -36.6014) (xy 360.7816 -36.8046) (xy 360.9848 -36.8046)
			)
		)
	)
	(zone
		(layer "F.Cu")
		(hatch none 0.5)
		(connect_pads
			(clearance 0)
		)
		(min_thickness 0.25)
		(keepout
			(tracks allowed)
			(vias allowed)
			(pads allowed)
			(copperpour allowed)
			(footprints not_allowed)
		)
		(placement
			(enabled no)
			(sheetname "")
		)
		(fill
			(thermal_gap 0.5)
			(thermal_bridge_width 0.5)
			(island_removal_mode 0)
		)
		(polygon
			(pts
				(arc
					(start 490.450124 0)
					(mid 491.157229 -0.292893)
					(end 491.450122 -0.999998)
				)
				(xy 491.450122 -46.800008) (xy 478.00006 -46.800008) (xy 478.00006 -36.800028) (xy 463.449924 -36.800028)
				(xy 463.449924 -46.800008) (xy 446.449958 -46.800008) (xy 446.449958 -36.800028) (xy 431.900076 -36.800028)
				(xy 431.900076 -46.800008) (xy 414.90011 -46.800008) (xy 414.90011 -36.800028) (xy 400.349974 -36.800028)
				(xy 400.349974 -46.800008) (xy 383.350008 -46.800008) (xy 383.350008 -36.800028) (xy 368.800126 -36.800028)
				(xy 368.800126 -46.800008) (xy 351.799906 -46.800008) (xy 351.799906 -36.800028) (xy 337.250024 -36.800028)
				(xy 337.250024 -46.800008) (xy 320.250058 -46.800008) (xy 320.250058 -36.800028) (xy 310.999886 -36.800028)
				(arc
					(start 310.999886 -0.999998)
					(mid 311.292779 -0.292893)
					(end 311.999884 0)
				)
			)
		)
	)
	(zone
		(net "GND")
		(layer "F.Cu")
		(hatch none 0.5)
		(connect_pads
			(clearance 0.5)
		)
		(min_thickness 0.25)
		(fill yes
			(thermal_gap 0.5)
			(thermal_bridge_width 0.5)
			(island_removal_mode 0)
		)
		(polygon
			(pts
				(xy 72.441816 -155.1432) (xy 71.84136 -155.743656) (xy 71.84136 -164.48405) (xy 72.9996 -165.64229)
				(xy 82.532474 -165.64229) (xy 83.1088 -165.065964) (xy 83.1088 -162.79241) (xy 83.017614 -162.701224)
				(xy 82.484976 -162.701224) (xy 82.484976 -162.168586) (xy 75.45959 -155.1432)
			)
		)
	)
	(zone
		(layer "F.Cu")
		(hatch none 0.5)
		(connect_pads
			(clearance 0)
		)
		(min_thickness 0.25)
		(keepout
			(tracks not_allowed)
			(vias allowed)
			(pads allowed)
			(copperpour not_allowed)
			(footprints allowed)
		)
		(placement
			(enabled no)
			(sheetname "")
		)
		(fill
			(thermal_gap 0.5)
			(thermal_bridge_width 0.5)
			(island_removal_mode 0)
		)
		(polygon
			(pts
				(arc
					(start 129.42062 -129.419604)
					(mid 128.935607 -128.93421)
					(end 128.45034 -129.41935)
				)
				(xy 128.45034 -129.7686)
				(arc
					(start 128.776476 -129.7686)
					(mid 128.835027 -129.744347)
					(end 128.85928 -129.685796)
				)
				(arc
					(start 128.85928 -129.674874)
					(mid 128.93548 -129.152706)
					(end 129.01168 -129.674874)
				)
				(xy 129.01168 -129.717292)
				(arc
					(start 129.00914 -129.719832)
					(mid 128.942745 -129.852065)
					(end 128.810512 -129.91846)
				)
				(xy 128.807972 -129.921) (xy 128.45034 -129.921) (xy 128.45034 -130.0607) (xy 128.807972 -130.0607)
				(arc
					(start 128.810512 -130.06324)
					(mid 128.942745 -130.129635)
					(end 129.00914 -130.261868)
				)
				(xy 129.01168 -130.264408)
				(arc
					(start 129.01168 -130.306826)
					(mid 128.93548 -130.828994)
					(end 128.85928 -130.306826)
				)
				(arc
					(start 128.85928 -130.295904)
					(mid 128.835027 -130.237353)
					(end 128.776476 -130.2131)
				)
				(xy 128.45034 -130.2131)
				(arc
					(start 128.45034 -130.56235)
					(mid 128.93548 -131.04749)
					(end 129.42062 -130.56235)
				)
			)
		)
	)
	(zone
		(layer "F.Cu")
		(hatch none 0.5)
		(connect_pads
			(clearance 0)
		)
		(min_thickness 0.25)
		(keepout
			(tracks allowed)
			(vias allowed)
			(pads allowed)
			(copperpour allowed)
			(footprints allowed)
		)
		(placement
			(enabled no)
			(sheetname "")
		)
		(fill
			(thermal_gap 0.5)
			(thermal_bridge_width 0.5)
			(island_removal_mode 0)
		)
		(polygon
			(pts
				(xy 456.057 -134.097776) (xy 457.64831 -134.097776) (xy 457.64831 -136.005824) (xy 456.057 -136.005824)
			)
		)
	)
	(zone
		(layer "F.Cu")
		(hatch none 0.5)
		(connect_pads
			(clearance 0)
		)
		(min_thickness 0.25)
		(keepout
			(tracks allowed)
			(vias allowed)
			(pads allowed)
			(copperpour allowed)
			(footprints allowed)
		)
		(placement
			(enabled no)
			(sheetname "")
		)
		(fill
			(thermal_gap 0.5)
			(thermal_bridge_width 0.5)
			(island_removal_mode 0)
		)
		(polygon
			(pts
				(xy 424.531536 -249.131328) (xy 426.122846 -249.131328) (xy 426.122846 -251.039376) (xy 424.531536 -251.039376)
			)
		)
	)
	(zone
		(layer "F.Cu")
		(hatch none 0.5)
		(connect_pads
			(clearance 0)
		)
		(min_thickness 0.25)
		(keepout
			(tracks not_allowed)
			(vias allowed)
			(pads allowed)
			(copperpour not_allowed)
			(footprints allowed)
		)
		(placement
			(enabled no)
			(sheetname "")
		)
		(fill
			(thermal_gap 0.5)
			(thermal_bridge_width 0.5)
			(island_removal_mode 0)
		)
		(polygon
			(pts
				(arc
					(start 351.427542 -244.317774)
					(mid 350.942402 -243.832634)
					(end 350.457262 -244.317774)
				)
				(arc
					(start 350.457262 -245.46052)
					(mid 350.942275 -245.945914)
					(end 351.427542 -245.460774)
				)
				(xy 351.427542 -245.111524)
				(arc
					(start 351.1169 -245.111524)
					(mid 351.049027 -245.138718)
					(end 351.018602 -245.20525)
				)
				(arc
					(start 351.018602 -245.20525)
					(mid 350.942402 -245.727418)
					(end 350.866202 -245.20525)
				)
				(xy 350.866202 -245.178326)
				(arc
					(start 350.868488 -245.17604)
					(mid 350.939629 -245.032551)
					(end 351.083118 -244.96141)
				)
				(xy 351.085404 -244.959124) (xy 351.427542 -244.959124) (xy 351.427542 -244.819424) (xy 351.085404 -244.819424)
				(arc
					(start 351.083118 -244.817138)
					(mid 350.939629 -244.745997)
					(end 350.868488 -244.602508)
				)
				(xy 350.866202 -244.600222)
				(arc
					(start 350.866202 -244.573298)
					(mid 350.942402 -244.05113)
					(end 351.018602 -244.573298)
				)
				(arc
					(start 351.018602 -244.573298)
					(mid 351.048953 -244.639906)
					(end 351.1169 -244.667024)
				)
				(xy 351.427542 -244.667024)
			)
		)
	)
	(zone
		(net "P12V_B")
		(layer "F.Cu")
		(hatch none 0.5)
		(connect_pads
			(clearance 0.5)
		)
		(min_thickness 0.25)
		(fill yes
			(thermal_gap 0.5)
			(thermal_bridge_width 0.5)
			(island_removal_mode 0)
		)
		(polygon
			(pts
				(xy 397.764 -257.429) (xy 397.256 -257.937) (xy 397.256 -261.366) (xy 397.51 -261.62) (xy 400.812 -261.62)
				(xy 401.066 -261.366) (xy 401.066 -259.334) (xy 401.193 -259.207) (xy 401.574 -259.207) (xy 401.675092 -259.105908)
				(xy 401.675092 -257.530092) (xy 401.574 -257.429)
			)
		)
		(polygon
			(pts
				(xy 401.1676 -258.4196) (xy 400.9644 -258.4196) (xy 400.9644 -258.6228) (xy 401.1676 -258.6228)
			)
		)
		(polygon
			(pts
				(xy 401.2184 -257.9878) (xy 401.0152 -257.9878) (xy 401.0152 -258.191) (xy 401.2184 -258.191)
			)
		)
	)
	(zone
		(net "GND")
		(layer "F.Cu")
		(hatch none 0.5)
		(connect_pads
			(clearance 0.5)
		)
		(min_thickness 0.25)
		(fill yes
			(thermal_gap 0.5)
			(thermal_bridge_width 0.5)
			(island_removal_mode 0)
		)
		(polygon
			(pts
				(xy 97.247456 -117.990112) (xy 96.406208 -118.83136)
				(arc
					(start 96.406208 -119.51716)
					(mid 97.075142 -120.778056)
					(end 97.270062 -122.192034)
				)
				(xy 98.11766 -123.039632)
				(arc
					(start 98.11766 -124.404374)
					(mid 100.508425 -125.800307)
					(end 101.451156 -128.40335)
				)
				(arc
					(start 101.451156 -131.57835)
					(mid 100.979633 -133.478845)
					(end 99.674426 -134.938516)
				)
				(arc
					(start 99.674426 -135.40105)
					(mid 99.26458 -137.179956)
					(end 98.11766 -138.60018)
				)
				(xy 98.11766 -141.294358)
				(arc
					(start 98.91014 -142.086838)
					(mid 100.217137 -142.315098)
					(end 101.382322 -142.949676)
				)
				(xy 102.169722 -142.949676) (xy 102.931976 -142.187422) (xy 102.931976 -138.618976) (xy 104.277414 -138.618976)
				(xy 104.900476 -137.995914) (xy 104.900476 -136.345676) (xy 104.951276 -136.345676)
				(arc
					(start 104.951276 -130.724656)
					(mid 104.929168 -130.299968)
					(end 104.951276 -129.87528)
				)
				(xy 104.951276 -127.481076)
				(arc
					(start 106.055668 -127.481076)
					(mid 108.696023 -126.222595)
					(end 111.501682 -127.049276)
				)
				(xy 112.732058 -127.049276)
				(arc
					(start 112.76457 -127.044958)
					(mid 114.255055 -126.76983)
					(end 115.744752 -127.049276)
				)
				(xy 116.574062 -127.049276) (xy 117.743732 -125.879606) (xy 117.743732 -118.965726) (xy 116.768118 -117.990112)
			)
		)
	)
	(zone
		(layer "F.Cu")
		(hatch none 0.5)
		(connect_pads
			(clearance 0)
		)
		(min_thickness 0.25)
		(keepout
			(tracks allowed)
			(vias allowed)
			(pads allowed)
			(copperpour allowed)
			(footprints not_allowed)
		)
		(placement
			(enabled no)
			(sheetname "")
		)
		(fill
			(thermal_gap 0.5)
			(thermal_bridge_width 0.5)
			(island_removal_mode 0)
		)
		(polygon
			(pts
				(arc
					(start 468.900002 -30.999938)
					(mid 467.499954 -32.399986)
					(end 466.099906 -30.999938)
				)
				(arc
					(start 466.099906 -30.999938)
					(mid 467.499954 -29.59989)
					(end 468.900002 -30.999938)
				)
			)
		)
	)
	(zone
		(layer "F.Cu")
		(hatch none 0.5)
		(connect_pads
			(clearance 0)
		)
		(min_thickness 0.25)
		(keepout
			(tracks allowed)
			(vias allowed)
			(pads allowed)
			(copperpour allowed)
			(footprints allowed)
		)
		(placement
			(enabled no)
			(sheetname "")
		)
		(fill
			(thermal_gap 0.5)
			(thermal_bridge_width 0.5)
			(island_removal_mode 0)
		)
		(polygon
			(pts
				(xy 187.40628 -366.126522) (xy 187.40628 -367.117122) (xy 187.40628 -368.031522) (xy 186.18708 -368.031522)
				(xy 186.18708 -366.126522) (xy 186.61888 -366.126522)
			)
		)
	)
	(zone
		(layer "F.Cu")
		(hatch none 0.5)
		(connect_pads
			(clearance 0)
		)
		(min_thickness 0.25)
		(keepout
			(tracks allowed)
			(vias allowed)
			(pads allowed)
			(copperpour allowed)
			(footprints allowed)
		)
		(placement
			(enabled no)
			(sheetname "")
		)
		(fill
			(thermal_gap 0.5)
			(thermal_bridge_width 0.5)
			(island_removal_mode 0)
		)
		(polygon
			(pts
				(xy 460.394304 -376.428) (xy 461.384904 -376.428) (xy 462.299304 -376.428) (xy 462.299304 -377.6472)
				(xy 460.394304 -377.6472) (xy 460.394304 -377.2154)
			)
		)
	)
	(zone
		(net "12V_PRE_18")
		(layer "F.Cu")
		(hatch none 0.5)
		(connect_pads
			(clearance 0.5)
		)
		(min_thickness 0.25)
		(fill yes
			(thermal_gap 0.5)
			(thermal_bridge_width 0.5)
			(island_removal_mode 0)
		)
		(polygon
			(pts
				(xy 331.028548 -154.686) (xy 329.098148 -156.6164) (xy 326.100948 -156.6164) (xy 325.846948 -156.8704)
				(xy 325.846948 -157.5816) (xy 325.986648 -157.7213) (xy 328.272648 -157.7213) (xy 328.285348 -157.734)
				(xy 331.968348 -157.734) (xy 332.984348 -156.718) (xy 332.984348 -154.813) (xy 332.857348 -154.686)
			)
		)
	)
	(zone
		(net "GND")
		(layer "F.Cu")
		(hatch none 0.5)
		(connect_pads
			(clearance 0.5)
		)
		(min_thickness 0.25)
		(fill yes
			(thermal_gap 0.5)
			(thermal_bridge_width 0.5)
			(island_removal_mode 0)
		)
		(polygon
			(pts
				(xy 22.790658 -191.00419) (xy 22.238208 -191.55664)
				(arc
					(start 22.238208 -203.976986)
					(mid 22.441543 -205.25867)
					(end 22.238208 -206.540354)
				)
				(xy 22.238208 -206.992982) (xy 22.606508 -207.361536) (xy 22.606508 -209.294476) (xy 22.912324 -209.294476)
				(xy 22.912324 -210.444842) (xy 23.836122 -211.36864) (xy 35.421062 -211.36864) (xy 35.421316 -211.368894)
				(xy 36.098226 -211.368894) (xy 36.78936 -210.67776)
				(arc
					(start 36.78936 -210.11261)
					(mid 37.089051 -208.605874)
					(end 37.94252 -207.328516)
				)
				(arc
					(start 38.34638 -206.924656)
					(mid 39.108874 -205.874606)
					(end 40.158924 -205.112112)
				)
				(xy 40.903652 -204.367638) (xy 40.903652 -194.988688) (xy 40.341296 -194.426332)
				(arc
					(start 38.256972 -194.426332)
					(mid 30.719258 -195.297332)
					(end 24.46274 -191.00419)
				)
			)
		)
	)
	(zone
		(layer "F.Cu")
		(hatch none 0.5)
		(connect_pads
			(clearance 0)
		)
		(min_thickness 0.25)
		(keepout
			(tracks not_allowed)
			(vias allowed)
			(pads allowed)
			(copperpour not_allowed)
			(footprints allowed)
		)
		(placement
			(enabled no)
			(sheetname "")
		)
		(fill
			(thermal_gap 0.5)
			(thermal_bridge_width 0.5)
			(island_removal_mode 0)
		)
		(polygon
			(pts
				(arc
					(start 127.64389 -248.115328)
					(mid 127.158877 -247.629934)
					(end 126.67361 -248.115074)
				)
				(xy 126.67361 -248.527824)
				(arc
					(start 127.03175 -248.527824)
					(mid 127.067671 -248.512945)
					(end 127.08255 -248.477024)
				)
				(arc
					(start 127.08255 -248.370598)
					(mid 127.15875 -247.84843)
					(end 127.23495 -248.370598)
				)
				(xy 127.23495 -248.50852)
				(arc
					(start 127.231902 -248.511568)
					(mid 127.175371 -248.620645)
					(end 127.066294 -248.677176)
				)
				(xy 127.063246 -248.680224) (xy 126.67361 -248.680224) (xy 126.67361 -248.819924) (xy 127.063246 -248.819924)
				(arc
					(start 127.066294 -248.822972)
					(mid 127.175371 -248.879503)
					(end 127.231902 -248.98858)
				)
				(xy 127.23495 -248.991628)
				(arc
					(start 127.23495 -249.12955)
					(mid 127.15875 -249.651718)
					(end 127.08255 -249.12955)
				)
				(arc
					(start 127.08255 -249.023124)
					(mid 127.067671 -248.987203)
					(end 127.03175 -248.972324)
				)
				(xy 126.67361 -248.972324)
				(arc
					(start 126.67361 -249.385074)
					(mid 127.15875 -249.870214)
					(end 127.64389 -249.385074)
				)
			)
		)
	)
	(zone
		(layer "F.Cu")
		(hatch none 0.5)
		(connect_pads
			(clearance 0)
		)
		(min_thickness 0.25)
		(keepout
			(tracks allowed)
			(vias allowed)
			(pads allowed)
			(copperpour allowed)
			(footprints allowed)
		)
		(placement
			(enabled no)
			(sheetname "")
		)
		(fill
			(thermal_gap 0.5)
			(thermal_bridge_width 0.5)
			(island_removal_mode 0)
		)
		(polygon
			(pts
				(xy 203.523596 -356.419912) (xy 203.523596 -330.073) (xy 205.945232 -330.073) (xy 205.945232 -356.419912)
			)
		)
	)
	(zone
		(layer "F.Cu")
		(hatch none 0.5)
		(connect_pads
			(clearance 0)
		)
		(min_thickness 0.25)
		(keepout
			(tracks allowed)
			(vias allowed)
			(pads allowed)
			(copperpour allowed)
			(footprints allowed)
		)
		(placement
			(enabled no)
			(sheetname "")
		)
		(fill
			(thermal_gap 0.5)
			(thermal_bridge_width 0.5)
			(island_removal_mode 0)
		)
		(polygon
			(pts
				(xy 239.837976 -353.314508) (xy 239.837976 -351.163636) (xy 242.259612 -351.163636) (xy 242.259612 -353.314508)
			)
		)
	)
	(zone
		(layer "F.Cu")
		(hatch none 0.5)
		(connect_pads
			(clearance 0)
		)
		(min_thickness 0.25)
		(keepout
			(tracks allowed)
			(vias allowed)
			(pads allowed)
			(copperpour allowed)
			(footprints allowed)
		)
		(placement
			(enabled no)
			(sheetname "")
		)
		(fill
			(thermal_gap 0.5)
			(thermal_bridge_width 0.5)
			(island_removal_mode 0)
		)
		(polygon
			(pts
				(xy 26.561796 -371.9195) (xy 26.561796 -370.9289) (xy 26.561796 -370.0145) (xy 27.780996 -370.0145)
				(xy 27.780996 -371.9195) (xy 27.349196 -371.9195)
			)
		)
	)
	(zone
		(net "P5V_HDD10")
		(layer "F.Cu")
		(hatch none 0.5)
		(connect_pads
			(clearance 0.5)
		)
		(min_thickness 0.25)
		(fill yes
			(thermal_gap 0.5)
			(thermal_bridge_width 0.5)
			(island_removal_mode 0)
		)
		(polygon
			(pts
				(xy 457.708 -252.73) (xy 457.454 -252.984) (xy 457.454 -263.779) (xy 455.803 -265.43) (xy 452.374 -265.43)
				(xy 452.12 -265.684) (xy 452.12 -267.335) (xy 452.374 -267.589) (xy 456.946 -267.589) (xy 457.581 -266.954)
				(xy 459.359 -266.954) (xy 459.867 -266.446) (xy 459.867 -252.984) (xy 459.613 -252.73)
			)
		)
		(polygon
			(pts
				(xy 456.4634 -266.5984) (xy 456.2602 -266.5984) (xy 456.2602 -266.8016) (xy 456.4634 -266.8016)
			)
		)
		(polygon
			(pts
				(xy 455.5998 -266.5984) (xy 455.3966 -266.5984) (xy 455.3966 -266.8016) (xy 455.5998 -266.8016)
			)
		)
	)
	(zone
		(net "GND")
		(layer "F.Cu")
		(hatch none 0.5)
		(connect_pads
			(clearance 0.5)
		)
		(min_thickness 0.25)
		(fill yes
			(thermal_gap 0.5)
			(thermal_bridge_width 0.5)
			(island_removal_mode 0)
		)
		(polygon
			(pts
				(xy 40.770302 -155.2702) (xy 40.34536 -155.695142) (xy 40.34536 -164.333682) (xy 41.029128 -165.01745)
				(xy 51.102006 -165.01745) (xy 51.509676 -164.60978) (xy 51.509676 -162.816286) (xy 51.394614 -162.701224)
				(xy 50.988976 -162.701224) (xy 50.988976 -162.295586) (xy 43.96359 -155.2702)
			)
		)
	)
	(zone
		(net "P5V_HDD19")
		(layer "F.Cu")
		(hatch none 0.5)
		(connect_pads
			(clearance 0.5)
		)
		(min_thickness 0.25)
		(fill yes
			(thermal_gap 0.5)
			(thermal_bridge_width 0.5)
			(island_removal_mode 0)
		)
		(polygon
			(pts
				(xy 363.093 -137.795) (xy 362.839 -138.049) (xy 362.839 -148.844) (xy 361.188 -150.495) (xy 357.759 -150.495)
				(xy 357.505 -150.749) (xy 357.505 -152.4) (xy 357.759 -152.654) (xy 362.331 -152.654) (xy 362.966 -152.019)
				(xy 364.744 -152.019) (xy 365.252 -151.511) (xy 365.252 -138.049) (xy 364.998 -137.795)
			)
		)
		(polygon
			(pts
				(xy 361.8484 -151.6634) (xy 361.6452 -151.6634) (xy 361.6452 -151.8666) (xy 361.8484 -151.8666)
			)
		)
		(polygon
			(pts
				(xy 360.9848 -151.6634) (xy 360.7816 -151.6634) (xy 360.7816 -151.8666) (xy 360.9848 -151.8666)
			)
		)
	)
	(zone
		(net "P12V_B")
		(layer "F.Cu")
		(hatch none 0.5)
		(connect_pads
			(clearance 0.5)
		)
		(min_thickness 0.25)
		(fill yes
			(thermal_gap 0.5)
			(thermal_bridge_width 0.5)
			(island_removal_mode 0)
		)
		(polygon
			(pts
				(xy 139.150852 -25.146) (xy 138.43 -25.866852) (xy 138.43 -29.083) (xy 138.684 -29.337) (xy 141.986 -29.337)
				(xy 142.24 -29.083) (xy 142.24 -26.797) (xy 141.605 -26.162) (xy 141.224 -26.162) (xy 140.97 -25.908)
				(xy 140.97 -25.273) (xy 140.843 -25.146)
			)
		)
		(polygon
			(pts
				(xy 140.4366 -25.7302) (xy 140.2334 -25.7302) (xy 140.2334 -25.9334) (xy 140.4366 -25.9334)
			)
		)
	)
	(zone
		(layer "F.Cu")
		(hatch none 0.5)
		(connect_pads
			(clearance 0)
		)
		(min_thickness 0.25)
		(keepout
			(tracks allowed)
			(vias allowed)
			(pads allowed)
			(copperpour allowed)
			(footprints not_allowed)
		)
		(placement
			(enabled no)
			(sheetname "")
		)
		(fill
			(thermal_gap 0.5)
			(thermal_bridge_width 0.5)
			(island_removal_mode 0)
		)
		(polygon
			(pts
				(xy 312.699908 -96.799908) (xy 491.450122 -96.799908) (xy 491.450122 -46.800008) (xy 478.00006 -46.800008)
				(xy 478.00006 -36.800028) (xy 463.449924 -36.800028) (xy 463.449924 -46.800008) (xy 446.449958 -46.800008)
				(xy 446.449958 -36.800028) (xy 431.900076 -36.800028) (xy 431.900076 -46.800008) (xy 414.90011 -46.800008)
				(xy 414.90011 -36.800028) (xy 400.349974 -36.800028) (xy 400.349974 -46.800008) (xy 383.350008 -46.800008)
				(xy 383.350008 -36.800028) (xy 368.800126 -36.800028) (xy 368.800126 -46.800008) (xy 351.799906 -46.800008)
				(xy 351.799906 -36.800028) (xy 337.250024 -36.800028) (xy 337.250024 -46.800008) (xy 320.250058 -46.800008)
				(xy 320.250058 -36.800028) (xy 310.999886 -36.800028)
				(arc
					(start 310.999886 -47.200058)
					(mid 310.706993 -47.907163)
					(end 309.999888 -48.200056)
				)
				(xy 298.200064 -48.200056) (xy 298.200064 -84.000086) (xy 312.699908 -84.000086)
			)
		)
	)
	(zone
		(layer "F.Cu")
		(hatch none 0.5)
		(connect_pads
			(clearance 0)
		)
		(min_thickness 0.25)
		(keepout
			(tracks allowed)
			(vias allowed)
			(pads allowed)
			(copperpour allowed)
			(footprints not_allowed)
		)
		(placement
			(enabled no)
			(sheetname "")
		)
		(fill
			(thermal_gap 0.5)
			(thermal_bridge_width 0.5)
			(island_removal_mode 0)
		)
		(polygon
			(pts
				(arc
					(start 449.674996 -63.799974)
					(mid 456.674982 -56.799988)
					(end 463.674968 -63.799974)
				)
				(arc
					(start 463.674968 -69.799962)
					(mid 456.674982 -76.799948)
					(end 449.674996 -69.799962)
				)
			)
		)
	)
	(zone
		(layer "F.Cu")
		(hatch none 0.5)
		(connect_pads
			(clearance 0)
		)
		(min_thickness 0.25)
		(keepout
			(tracks allowed)
			(vias allowed)
			(pads allowed)
			(copperpour allowed)
			(footprints allowed)
		)
		(placement
			(enabled no)
			(sheetname "")
		)
		(fill
			(thermal_gap 0.5)
			(thermal_bridge_width 0.5)
			(island_removal_mode 0)
		)
		(polygon
			(pts
				(xy 157.7594 -19.5834) (xy 158.8008 -19.5834) (xy 158.9532 -19.431) (xy 158.9532 -18.2118) (xy 158.623 -17.8816)
				(xy 157.5562 -17.8816) (xy 157.3784 -18.0594) (xy 157.3784 -19.2024)
			)
		)
	)
	(zone
		(net "P12V_HDD0")
		(layer "F.Cu")
		(hatch none 0.5)
		(connect_pads
			(clearance 0.5)
		)
		(min_thickness 0.25)
		(fill yes
			(thermal_gap 0.5)
			(thermal_bridge_width 0.5)
			(island_removal_mode 0)
		)
		(polygon
			(pts
				(xy 12.319 -262.255) (xy 12.065 -262.509) (xy 12.065 -264.16) (xy 12.319 -264.414) (xy 14.478 -264.414)
				(xy 14.986 -264.922) (xy 14.986 -267.462) (xy 22.733 -275.209) (xy 31.242 -275.209) (xy 31.369 -275.082)
				(xy 31.369 -273.304) (xy 31.242 -273.177) (xy 25.273 -273.177) (xy 24.638 -272.542) (xy 22.987 -272.542)
				(xy 18.669 -268.224) (xy 18.669 -264.668) (xy 17.526 -263.525) (xy 17.526 -262.509) (xy 17.272 -262.255)
			)
		)
		(polygon
			(pts
				(xy 24.7904 -274.2184) (xy 24.5872 -274.2184) (xy 24.5872 -274.4216) (xy 24.7904 -274.4216)
			)
		)
		(polygon
			(pts
				(xy 23.9268 -274.2184) (xy 23.7236 -274.2184) (xy 23.7236 -274.4216) (xy 23.9268 -274.4216)
			)
		)
	)
	(zone
		(net "GND")
		(layer "F.Cu")
		(hatch none 0.5)
		(connect_pads
			(clearance 0.5)
		)
		(min_thickness 0.25)
		(fill yes
			(thermal_gap 0.5)
			(thermal_bridge_width 0.5)
			(island_removal_mode 0)
		)
		(polygon
			(pts
				(xy 300.121574 -117.574822) (xy 300.992032 -116.704618)
				(arc
					(start 300.992032 -115.92433)
					(mid 300.836954 -114.849068)
					(end 300.970442 -113.770918)
				)
				(arc
					(start 300.970442 -113.770918)
					(mid 301.037178 -112.766744)
					(end 301.347124 -111.809276)
				)
				(xy 301.347124 -111.602774)
				(arc
					(start 300.553882 -110.809532)
					(mid 295.053026 -109.512992)
					(end 290.955984 -105.620058)
				)
				(xy 290.28517 -105.620058) (xy 289.986212 -105.919016)
				(arc
					(start 289.986212 -109.67212)
					(mid 291.204864 -110.393244)
					(end 292.104572 -111.486696)
				)
				(arc
					(start 295.590976 -114.9731)
					(mid 297.298057 -115.708493)
					(end 298.50334 -117.123464)
				)
				(xy 298.954698 -117.574822)
			)
		)
	)
	(zone
		(net "5V_PRE_19")
		(layer "F.Cu")
		(hatch none 0.5)
		(connect_pads
			(clearance 0.5)
		)
		(min_thickness 0.25)
		(fill yes
			(thermal_gap 0.5)
			(thermal_bridge_width 0.5)
			(island_removal_mode 0)
		)
		(polygon
			(pts
				(xy 360.934 -146.05) (xy 360.68 -146.304) (xy 360.68 -148.844) (xy 360.299 -149.225) (xy 357.759 -149.225)
				(xy 357.505 -149.479) (xy 357.505 -149.86) (xy 357.759 -150.114) (xy 361.061 -150.114) (xy 362.331 -148.844)
				(xy 362.331 -146.304) (xy 362.077 -146.05)
			)
		)
	)
	(zone
		(net "P12V_HDD35")
		(layer "F.Cu")
		(hatch none 0.5)
		(connect_pads
			(clearance 0.5)
		)
		(min_thickness 0.25)
		(fill yes
			(thermal_gap 0.5)
			(thermal_bridge_width 0.5)
			(island_removal_mode 0)
		)
		(polygon
			(pts
				(xy 467.106 -25.908) (xy 466.852 -26.162) (xy 466.852 -27.686) (xy 469.265 -30.099) (xy 469.265 -33.655)
				(xy 470.027 -34.417) (xy 470.027 -37.338) (xy 477.774 -45.085) (xy 486.283 -45.085) (xy 486.41 -44.958)
				(xy 486.41 -43.18) (xy 486.283 -43.053) (xy 480.314 -43.053) (xy 479.679 -42.418) (xy 478.028 -42.418)
				(xy 473.71 -38.1) (xy 473.71 -34.544) (xy 472.059 -32.893) (xy 472.059 -26.162) (xy 471.805 -25.908)
			)
		)
		(polygon
			(pts
				(xy 479.8314 -44.0944) (xy 479.6282 -44.0944) (xy 479.6282 -44.2976) (xy 479.8314 -44.2976)
			)
		)
		(polygon
			(pts
				(xy 478.9678 -44.0944) (xy 478.7646 -44.0944) (xy 478.7646 -44.2976) (xy 478.9678 -44.2976)
			)
		)
	)
	(zone
		(net "P5V_HDD5")
		(layer "F.Cu")
		(hatch none 0.5)
		(connect_pads
			(clearance 0.5)
		)
		(min_thickness 0.25)
		(fill yes
			(thermal_gap 0.5)
			(thermal_bridge_width 0.5)
			(island_removal_mode 0)
		)
		(polygon
			(pts
				(xy 177.419 -257.683) (xy 177.165 -257.937) (xy 177.165 -260.223) (xy 177.419 -260.477) (xy 177.419 -262.509)
				(xy 178.181 -263.271) (xy 178.181 -264.033) (xy 178.562 -264.414) (xy 178.943 -264.414) (xy 182.118 -267.589)
				(xy 188.976 -267.589) (xy 189.103 -267.462) (xy 189.103 -265.684) (xy 188.976 -265.557) (xy 183.896 -265.557)
				(xy 181.991 -263.652) (xy 181.102 -263.652) (xy 180.213 -262.763) (xy 180.213 -260.223) (xy 180.848 -259.588)
				(xy 180.848 -257.937) (xy 180.594 -257.683)
			)
		)
		(polygon
			(pts
				(xy 179.2224 -264.1092) (xy 179.0192 -264.1092) (xy 179.0192 -264.3124) (xy 179.2224 -264.3124)
			)
		)
		(polygon
			(pts
				(xy 179.2224 -263.2456) (xy 179.0192 -263.2456) (xy 179.0192 -263.4488) (xy 179.2224 -263.4488)
			)
		)
	)
	(zone
		(net "5V_PRE_8")
		(layer "F.Cu")
		(hatch none 0.5)
		(connect_pads
			(clearance 0.5)
		)
		(min_thickness 0.25)
		(fill yes
			(thermal_gap 0.5)
			(thermal_bridge_width 0.5)
			(island_removal_mode 0)
		)
		(polygon
			(pts
				(xy 392.557 -260.985) (xy 392.303 -261.239) (xy 392.303 -263.779) (xy 391.922 -264.16) (xy 389.382 -264.16)
				(xy 389.128 -264.414) (xy 389.128 -264.795) (xy 389.382 -265.049) (xy 392.684 -265.049) (xy 393.954 -263.779)
				(xy 393.954 -261.239) (xy 393.7 -260.985)
			)
		)
	)
	(zone
		(net "12V_PRE_26")
		(layer "F.Cu")
		(hatch none 0.5)
		(connect_pads
			(clearance 0.5)
		)
		(min_thickness 0.25)
		(fill yes
			(thermal_gap 0.5)
			(thermal_bridge_width 0.5)
			(island_removal_mode 0)
		)
		(polygon
			(pts
				(xy 82.804 -34.798) (xy 82.677 -34.925) (xy 82.677 -36.449) (xy 84.074 -37.846) (xy 85.471 -37.846)
				(xy 90.424 -42.799) (xy 94.361 -42.799) (xy 94.488 -42.672) (xy 94.488 -41.91) (xy 94.361 -41.783)
				(xy 91.059 -41.783) (xy 84.074 -34.798)
			)
		)
	)
	(zone
		(net "P12V_FAN2")
		(layer "F.Cu")
		(hatch none 0.5)
		(connect_pads
			(clearance 0.5)
		)
		(min_thickness 0.25)
		(fill yes
			(thermal_gap 0.5)
			(thermal_bridge_width 0.5)
			(island_removal_mode 0)
		)
		(polygon
			(pts
				(xy 345.458796 -358.267) (xy 345.153996 -358.5718) (xy 345.153996 -359.6894) (xy 343.274396 -361.569)
				(xy 339.217 -361.569) (xy 338.201 -362.585) (xy 338.201 -364.617) (xy 339.09 -365.506) (xy 344.010996 -365.506)
				(xy 344.518996 -366.014) (xy 344.518996 -374.65) (xy 345.280996 -375.412) (xy 346.804996 -375.412)
				(xy 348.455996 -373.761) (xy 348.455996 -365.770414) (xy 348.312486 -365.626904) (xy 348.312486 -358.63149)
				(xy 347.947996 -358.267)
			)
		)
		(polygon
			(pts
				(xy 347.885766 -364.45063) (xy 347.682566 -364.45063) (xy 347.682566 -364.65383) (xy 347.885766 -364.65383)
			)
		)
		(polygon
			(pts
				(xy 347.885766 -363.84103) (xy 347.682566 -363.84103) (xy 347.682566 -364.04423) (xy 347.885766 -364.04423)
			)
		)
		(polygon
			(pts
				(xy 347.541596 -363.5502) (xy 347.338396 -363.5502) (xy 347.338396 -363.7534) (xy 347.541596 -363.7534)
			)
		)
		(polygon
			(pts
				(xy 347.541596 -362.6866) (xy 347.338396 -362.6866) (xy 347.338396 -362.8898) (xy 347.541596 -362.8898)
			)
		)
	)
	(zone
		(layer "F.Cu")
		(hatch none 0.5)
		(connect_pads
			(clearance 0)
		)
		(min_thickness 0.25)
		(keepout
			(tracks not_allowed)
			(vias allowed)
			(pads allowed)
			(copperpour not_allowed)
			(footprints allowed)
		)
		(placement
			(enabled no)
			(sheetname "")
		)
		(fill
			(thermal_gap 0.5)
			(thermal_bridge_width 0.5)
			(island_removal_mode 0)
		)
		(polygon
			(pts
				(arc
					(start 324.07479 -248.115328)
					(mid 323.589777 -247.629934)
					(end 323.10451 -248.115074)
				)
				(arc
					(start 323.10451 -249.385074)
					(mid 323.58965 -249.870214)
					(end 324.07479 -249.385074)
				)
				(xy 324.07479 -248.972324)
				(arc
					(start 323.71665 -248.972324)
					(mid 323.680729 -248.987203)
					(end 323.66585 -249.023124)
				)
				(arc
					(start 323.66585 -249.12955)
					(mid 323.58965 -249.651718)
					(end 323.51345 -249.12955)
				)
				(xy 323.51345 -248.991628)
				(arc
					(start 323.516498 -248.98858)
					(mid 323.573029 -248.879503)
					(end 323.682106 -248.822972)
				)
				(xy 323.685154 -248.819924) (xy 324.07479 -248.819924) (xy 324.07479 -248.680224) (xy 323.685154 -248.680224)
				(arc
					(start 323.682106 -248.677176)
					(mid 323.573029 -248.620645)
					(end 323.516498 -248.511568)
				)
				(xy 323.51345 -248.50852)
				(arc
					(start 323.51345 -248.370598)
					(mid 323.58965 -247.84843)
					(end 323.66585 -248.370598)
				)
				(arc
					(start 323.66585 -248.477024)
					(mid 323.680729 -248.512945)
					(end 323.71665 -248.527824)
				)
				(xy 324.07479 -248.527824)
			)
		)
	)
	(zone
		(net "GND")
		(layer "F.Cu")
		(hatch none 0.5)
		(connect_pads
			(clearance 0.5)
		)
		(min_thickness 0.25)
		(fill yes
			(thermal_gap 0.5)
			(thermal_bridge_width 0.5)
			(island_removal_mode 0)
		)
		(polygon
			(pts
				(arc
					(start 434.493924 -9.84123)
					(mid 434.853747 -10.095791)
					(end 435.182518 -10.389362)
				)
				(xy 438.87771 -14.084554)
				(arc
					(start 438.87771 -47.339758)
					(mid 436.533075 -52.365531)
					(end 431.334672 -50.433224)
				)
				(arc
					(start 430.512474 -50.433224)
					(mid 429.375814 -51.009432)
					(end 428.117 -51.207924)
				)
				(xy 427.515274 -51.207924) (xy 426.620178 -52.10302) (xy 426.620178 -52.597812)
				(arc
					(start 426.932598 -52.910232)
					(mid 433.218488 -55.340599)
					(end 437.640476 -60.426346)
				)
				(arc
					(start 438.938162 -60.426346)
					(mid 440.096448 -59.782532)
					(end 441.402724 -59.559444)
				)
				(arc
					(start 442.865256 -59.559444)
					(mid 443.825683 -59.678437)
					(end 444.728092 -60.028074)
				)
				(xy 445.741806 -60.028074) (xy 446.64376 -59.12612) (xy 446.64376 -47.135288) (xy 440.180476 -40.672004)
				(xy 440.180476 -27.786076) (xy 443.090554 -27.786076) (xy 443.912244 -26.964386) (xy 443.912244 -19.555206)
				(xy 443.565788 -19.20875)
				(arc
					(start 443.565788 -17.856708)
					(mid 443.509369 -17.803548)
					(end 443.454028 -17.749266)
				)
				(arc
					(start 443.223904 -17.519396)
					(mid 440.376331 -13.033491)
					(end 444.3984 -9.561576)
				)
				(xy 445.733424 -9.561576) (xy 446.64376 -8.65124) (xy 446.64376 -2.032) (xy 489.418122 -2.032) (xy 489.418122 -55.891176)
				(xy 478.193862 -55.891176) (xy 478.193862 -51.5366) (xy 476.950786 -50.293524) (xy 475.054676 -50.293524)
				(arc
					(start 475.054676 -48.613822)
					(mid 474.58172 -47.843935)
					(end 474.289374 -46.988984)
				)
				(xy 470.558114 -43.257724) (xy 470.066116 -43.257724)
				(arc
					(start 469.920828 -43.403012)
					(mid 468.43555 -46.285884)
					(end 465.318602 -47.181008)
				)
				(xy 464.123024 -48.376586) (xy 464.123024 -50.433224)
				(arc
					(start 462.008474 -50.433224)
					(mid 460.871814 -51.009432)
					(end 459.613 -51.207924)
				)
				(xy 458.317092 -51.207924) (xy 457.6318 -51.893216) (xy 457.6318 -52.656994)
				(arc
					(start 458.039724 -53.064918)
					(mid 463.725402 -55.590574)
					(end 467.0806 -60.829698)
				)
				(xy 467.599014 -60.829698) (xy 468.107522 -60.32119)
				(arc
					(start 468.968074 -60.32119)
					(mid 470.039879 -59.794467)
					(end 471.220292 -59.613292)
				)
				(arc
					(start 472.973908 -59.613292)
					(mid 474.238978 -59.822138)
					(end 475.36989 -60.426346)
				)
				(xy 477.643698 -60.426346) (xy 477.643698 -84.798916)
				(arc
					(start 470.229946 -92.212668)
					(mid 469.944192 -92.691358)
					(end 469.596724 -93.127322)
				)
				(xy 469.596724 -104.344724)
				(arc
					(start 467.804246 -104.344724)
					(mid 467.416368 -104.60138)
					(end 467.00186 -104.812338)
				)
				(xy 466.326474 -105.487724) (xy 466.326474 -106.59491) (xy 464.533488 -106.59491) (xy 464.013042 -107.115356)
				(xy 464.013042 -109.214158) (xy 464.712304 -109.91342) (xy 469.070436 -109.91342) (xy 472.186 -113.028984)
				(xy 474.204538 -115.047268) (xy 489.418122 -115.047268) (xy 489.418122 -170.8912) (xy 478.193862 -170.8912)
				(arc
					(start 478.193862 -166.11727)
					(mid 477.418643 -165.811782)
					(end 476.721424 -165.355524)
				)
				(xy 475.054676 -165.355524) (xy 475.054676 -162.816286) (xy 474.939614 -162.701224) (xy 474.483176 -162.701224)
				(xy 474.483176 -162.244786) (xy 470.293954 -158.055564) (xy 469.812878 -158.055564) (xy 469.265254 -158.603188)
				(xy 469.265254 -160.455356) (xy 464.225386 -165.495224)
				(arc
					(start 462.008474 -165.495224)
					(mid 461.624474 -165.741248)
					(end 461.215486 -165.943026)
				)
				(xy 461.215486 -166.618158) (xy 468.008716 -173.411388) (xy 468.008716 -174.318422) (xy 468.413846 -174.723552)
				(arc
					(start 469.118188 -174.723552)
					(mid 470.107752 -174.290091)
					(end 471.177874 -174.141892)
				)
				(arc
					(start 472.930982 -174.141892)
					(mid 474.437718 -174.441583)
					(end 475.715076 -175.295052)
				)
				(xy 475.846394 -175.42637) (xy 477.643698 -175.42637) (xy 477.643698 -185.373518) (xy 477.642936 -185.37428)
				(xy 477.642936 -185.404252) (xy 477.338136 -185.709052)
				(arc
					(start 477.338136 -207.373474)
					(mid 477.513499 -208.175076)
					(end 477.527366 -208.995518)
				)
				(xy 477.826324 -209.294476) (xy 477.826324 -210.72729)
				(arc
					(start 478.435162 -211.336128)
					(mid 479.455496 -211.840819)
					(end 480.297236 -212.607144)
				)
				(arc
					(start 480.297236 -212.607144)
					(mid 481.71186 -213.77271)
					(end 482.47554 -215.43899)
				)
				(xy 487.386376 -220.349826) (xy 489.418122 -220.349826)
				(arc
					(start 489.418122 -286.0167)
					(mid 487.255575 -286.5617)
					(end 485.12857 -285.891224)
				)
				(xy 478.193862 -285.891224) (xy 478.193862 -282.262326) (xy 476.34906 -280.417524) (xy 475.054676 -280.417524)
				(xy 475.054676 -277.878286) (xy 474.961458 -277.785068) (xy 474.524578 -277.785068) (xy 474.524578 -277.348188)
				(xy 470.283032 -273.106642) (xy 469.586818 -273.106642) (xy 469.265254 -273.428206) (xy 469.265254 -275.390356)
				(xy 467.496144 -277.159466)
				(arc
					(start 467.496144 -299.794168)
					(mid 456.674982 -310.61533)
					(end 445.85382 -299.794168)
				)
				(arc
					(start 445.85382 -293.799768)
					(mid 446.053139 -291.732355)
					(end 446.64376 -289.741102)
				)
				(xy 446.64376 -275.6789)
				(arc
					(start 447.791586 -275.6789)
					(mid 448.030704 -275.28065)
					(end 448.309746 -274.90928)
				)
				(xy 448.309746 -274.233132) (xy 447.678048 -273.601434)
				(arc
					(start 447.029332 -273.601434)
					(mid 443.060756 -273.203343)
					(end 441.198762 -269.676118)
				)
				(xy 441.198762 -267.41501) (xy 440.078876 -266.295124) (xy 440.078876 -254.479552) (xy 439.41238 -253.813056)
				(xy 438.661302 -253.813056) (xy 438.36336 -254.110998)
				(arc
					(start 438.36336 -257.1115)
					(mid 438.261445 -257.996861)
					(end 437.961024 -258.835906)
				)
				(xy 437.961024 -275.198586) (xy 432.729386 -280.430224)
				(arc
					(start 430.512474 -280.430224)
					(mid 429.375814 -281.006432)
					(end 428.117 -281.204924)
				)
				(xy 426.828966 -281.204924)
				(arc
					(start 425.967144 -282.066746)
					(mid 425.690057 -282.713388)
					(end 425.306236 -283.302964)
				)
				(xy 425.306236 -285.891224) (xy 415.093912 -285.891224) (xy 415.093912 -275.6789)
				(arc
					(start 416.241738 -275.6789)
					(mid 416.401653 -275.402479)
					(end 416.580828 -275.138134)
				)
				(xy 416.580828 -274.456906) (xy 415.757868 -273.633946)
				(arc
					(start 415.398712 -273.633946)
					(mid 411.23806 -273.003338)
					(end 409.694126 -269.088616)
				)
				(xy 409.694126 -267.380974) (xy 408.608276 -266.295124) (xy 408.608276 -258.772152)
				(arc
					(start 408.216862 -258.380738)
					(mid 407.372239 -257.11667)
					(end 407.07564 -255.6256)
				)
				(xy 407.07564 -239.189006)
				(arc
					(start 406.63876 -238.752126)
					(mid 406.323077 -238.586584)
					(end 406.02281 -238.394494)
				)
				(xy 400.901662 -238.394494) (xy 400.553174 -238.742982) (xy 400.553174 -238.990378) (xy 400.626072 -239.063276)
				(xy 402.997924 -239.063276)
				(arc
					(start 402.997924 -240.59642)
					(mid 403.288632 -241.012956)
					(end 403.525482 -241.462306)
				)
				(xy 405.893524 -243.830348)
				(arc
					(start 405.893524 -247.642634)
					(mid 406.854083 -249.411294)
					(end 406.86736 -251.423932)
				)
				(arc
					(start 406.86736 -256.794)
					(mid 406.765445 -257.679361)
					(end 406.465024 -258.518406)
				)
				(xy 406.465024 -270.194024) (xy 406.273254 -270.385794) (xy 406.273254 -275.390356) (xy 404.496016 -277.167594)
				(xy 404.496016 -306.807616) (xy 407.695146 -310.006746) (xy 439.093356 -310.006746) (xy 446.146174 -317.059564)
				(xy 446.146174 -354.49256) (xy 446.672208 -355.018594) (xy 450.028818 -355.018594) (xy 450.722746 -355.712522)
				(xy 451.153022 -355.712522) (xy 451.153022 -356.142798) (xy 452.990458 -357.980234) (xy 452.990458 -361.45724)
				(xy 454.586848 -363.05363) (xy 455.339958 -363.05363) (xy 455.35088 -363.042708) (xy 459.4733 -363.042708)
				(xy 462.074768 -365.644176) (xy 462.074768 -366.968532) (xy 462.858612 -367.752376)
				(arc
					(start 471.387678 -367.752376)
					(mid 474.617434 -366.323621)
					(end 477.969326 -367.435892)
				)
				(arc
					(start 477.969326 -367.435892)
					(mid 478.493376 -367.936687)
					(end 478.937828 -368.509296)
				)
				(arc
					(start 479.975926 -369.547394)
					(mid 485.239853 -372.393077)
					(end 482.60762 -377.767088)
				)
				(arc
					(start 482.60762 -377.767088)
					(mid 480.001794 -377.879796)
					(end 477.806258 -376.471688)
				)
				(xy 476.839534 -376.471688)
				(arc
					(start 476.470218 -376.841004)
					(mid 476.486415 -377.20022)
					(end 476.47352 -377.55957)
				)
				(arc
					(start 476.47352 -377.55957)
					(mid 475.915774 -379.399389)
					(end 474.633544 -380.831852)
				)
				(xy 474.62821 -380.835662)
				(arc
					(start 474.57106 -380.875794)
					(mid 473.709975 -380.423941)
					(end 472.750134 -380.267972)
				)
				(arc
					(start 466.249258 -380.267972)
					(mid 465.864898 -380.292465)
					(end 465.48675 -380.365508)
				)
				(arc
					(start 465.48675 -380.365508)
					(mid 463.851352 -381.445235)
					(end 463.218022 -383.299716)
				)
				(xy 463.218022 -383.96799) (xy 419.731952 -383.96799)
				(arc
					(start 419.731952 -381)
					(mid 418.8439 -378.856054)
					(end 416.699954 -377.968002)
				)
				(xy 416.529266 -377.968002) (xy 416.529266 -377.952) (xy 416.306 -377.952) (xy 415.671 -377.317)
				(arc
					(start 415.671 -372.111016)
					(mid 415.652714 -371.892662)
					(end 415.646616 -371.673628)
				)
				(arc
					(start 415.646616 -368.946684)
					(mid 415.443269 -367.665)
					(end 415.646616 -366.383316)
				)
				(arc
					(start 415.646616 -364.068614)
					(mid 416.322716 -360.489705)
					(end 419.584124 -358.868218)
				)
				(xy 425.38269 -358.868218) (xy 426.24375 -358.007158) (xy 426.24375 -356.485444) (xy 427.89348 -354.835714)
				(xy 427.89348 -353.749356) (xy 425.802298 -351.658174) (xy 425.802298 -336.22742) (xy 419.20287 -329.627992)
				(xy 362.179616 -329.627992) (xy 359.503726 -332.303882) (xy 359.503726 -343.583768) (xy 347.706696 -343.583768)
				(xy 346.202254 -345.08821) (xy 346.202254 -352.74758) (xy 346.820744 -353.36607) (xy 348.435676 -353.36607)
				(xy 350.075754 -355.006148) (xy 353.490022 -355.006148) (xy 354.210112 -355.726238) (xy 354.565458 -355.726238)
				(xy 354.565458 -356.081584) (xy 356.40645 -357.922576) (xy 356.40645 -365.814356)
				(arc
					(start 355.842062 -366.378744)
					(mid 355.860157 -367.680534)
					(end 355.547676 -368.944398)
				)
				(arc
					(start 355.547676 -370.755418)
					(mid 355.892817 -372.522894)
					(end 355.60127 -374.299988)
				)
				(arc
					(start 355.60127 -377.604274)
					(mid 356.017068 -378.849052)
					(end 356.11562 -380.157736)
				)
				(xy 356.11562 -383.96799) (xy 318.18199 -383.96799)
				(arc
					(start 318.18199 -383.299716)
					(mid 317.548577 -381.4453)
					(end 315.913262 -380.365508)
				)
				(arc
					(start 315.913262 -380.365508)
					(mid 315.535111 -380.292488)
					(end 315.150754 -380.267972)
				)
				(arc
					(start 308.649624 -380.267972)
					(mid 308.265136 -380.292449)
					(end 307.886862 -380.365508)
				)
				(arc
					(start 307.886862 -380.365508)
					(mid 307.332672 -380.568994)
					(end 306.828444 -380.876048)
				)
				(arc
					(start 306.828444 -380.876048)
					(mid 305.502773 -379.432791)
					(end 304.926238 -377.559824)
				)
				(arc
					(start 304.926492 -377.55957)
					(mid 305.005098 -376.322111)
					(end 305.4223 -375.154444)
				)
				(arc
					(start 305.4223 -374.350534)
					(mid 305.722059 -372.843632)
					(end 306.575714 -371.566186)
				)
				(arc
					(start 308.689248 -369.452652)
					(mid 308.911062 -369.24725)
					(end 309.147972 -369.05946)
				)
				(xy 309.147972 -367.726976) (xy 309.450232 -367.424716) (xy 314.74918 -367.424716)
				(arc
					(start 315.05779 -367.116106)
					(mid 315.995217 -364.674171)
					(end 318.220598 -363.299502)
				)
				(arc
					(start 319.51295 -362.00715)
					(mid 319.526255 -360.788533)
					(end 319.898014 -359.627932)
				)
				(xy 319.898014 -358.96423) (xy 319.169288 -358.235504) (xy 313.578748 -358.235504) (xy 312.668158 -359.146094)
				(xy 312.668158 -363.806486)
				(arc
					(start 311.333134 -363.806486)
					(mid 311.084241 -364.121016)
					(end 310.806084 -364.40999)
				)
				(xy 310.806084 -365.97844) (xy 301.51451 -365.97844) (xy 300.583346 -365.047276) (xy 285.966408 -365.047276)
				(xy 283.441394 -362.522262) (xy 282.899866 -362.522262) (xy 282.592272 -362.829856) (xy 282.592272 -370.295932)
				(xy 283.240988 -370.944648) (xy 285.205424 -370.944648) (xy 285.205424 -371.025166) (xy 288.461196 -374.280938)
				(xy 288.972498 -374.280938) (xy 289.517328 -374.825768) (xy 290.430966 -374.825768) (xy 290.430966 -375.739406)
				(xy 291.458396 -376.766836) (xy 291.458396 -383.96799) (xy 280.591514 -383.96799) (xy 278.782018 -382.158494)
				(xy 278.782018 -381.889) (xy 277.513034 -381.889)
				(arc
					(start 277.513034 -382.58623)
					(mid 277.531087 -382.676699)
					(end 277.582376 -382.753362)
				)
				(arc
					(start 279.996646 -385.167632)
					(mid 280.07334 -385.218844)
					(end 280.163778 -385.236974)
				)
				(arc
					(start 306.649882 -385.236974)
					(mid 306.817454 -385.167564)
					(end 306.886864 -384.999992)
				)
				(arc
					(start 306.886864 -383.29997)
					(mid 307.157652 -382.361098)
					(end 307.886862 -381.710692)
				)
				(arc
					(start 307.886862 -381.710692)
					(mid 308.258606 -381.580932)
					(end 308.649878 -381.536956)
				)
				(arc
					(start 315.149992 -381.536956)
					(mid 316.396631 -382.053331)
					(end 316.913006 -383.29997)
				)
				(arc
					(start 316.913006 -384.999992)
					(mid 316.982416 -385.167564)
					(end 317.149988 -385.236974)
				)
				(arc
					(start 362.700062 -385.236974)
					(mid 362.867634 -385.167564)
					(end 362.937044 -384.999992)
				)
				(arc
					(start 362.937044 -381)
					(mid 363.453419 -379.753361)
					(end 364.700058 -379.236986)
				)
				(arc
					(start 416.699954 -379.236986)
					(mid 417.946593 -379.753361)
					(end 418.462968 -381)
				)
				(arc
					(start 418.462968 -384.999992)
					(mid 418.532378 -385.167564)
					(end 418.69995 -385.236974)
				)
				(arc
					(start 464.250024 -385.236974)
					(mid 464.417596 -385.167564)
					(end 464.487006 -384.999992)
				)
				(arc
					(start 464.487006 -383.29997)
					(mid 465.003381 -382.053331)
					(end 466.25002 -381.536956)
				)
				(arc
					(start 472.74988 -381.536956)
					(mid 473.996519 -382.053331)
					(end 474.512894 -383.29997)
				)
				(arc
					(start 474.512894 -384.999992)
					(mid 474.582304 -385.167564)
					(end 474.749876 -385.236974)
				)
				(arc
					(start 487.449876 -385.236974)
					(mid 487.617448 -385.167564)
					(end 487.686858 -384.999992)
				)
				(arc
					(start 487.686858 -372.000018)
					(mid 488.203143 -370.753469)
					(end 489.449618 -370.237004)
				)
				(arc
					(start 490.450124 -370.237004)
					(mid 490.617696 -370.167594)
					(end 490.687106 -370.000022)
				)
				(arc
					(start 490.687106 -0.999998)
					(mid 490.617696 -0.832426)
					(end 490.450124 -0.763016)
				)
				(arc
					(start 311.999884 -0.763016)
					(mid 311.832312 -0.832426)
					(end 311.762902 -0.999998)
				)
				(arc
					(start 311.762902 -47.200058)
					(mid 311.246527 -48.446697)
					(end 309.999888 -48.963072)
				)
				(xy 270.764 -48.963072) (xy 270.764 -48.96231)
				(arc
					(start 269.999968 -48.96231)
					(mid 269.831858 -49.031944)
					(end 269.762224 -49.200054)
				)
				(xy 269.762224 -49.784) (xy 269.762986 -49.784) (xy 269.762986 -65.786254) (xy 269.42034 -65.786254)
				(xy 269.42034 -67.998848)
				(arc
					(start 269.42034 -67.999356)
					(mid 269.365281 -68.69588)
					(end 269.201138 -69.37502)
				)
				(arc
					(start 269.201138 -69.37502)
					(mid 269.365259 -70.054164)
					(end 269.42034 -70.750684)
				)
				(xy 269.42034 -70.751446) (xy 269.42034 -73.748646)
				(arc
					(start 269.42034 -73.749408)
					(mid 269.365281 -74.445932)
					(end 269.201138 -75.125072)
				)
				(arc
					(start 269.201138 -75.125072)
					(mid 269.365259 -75.804216)
					(end 269.42034 -76.500736)
				)
				(xy 269.42034 -76.501498) (xy 269.42034 -79.498698)
				(arc
					(start 269.42034 -79.49946)
					(mid 267.497015 -83.147743)
					(end 263.400032 -83.620864)
				)
				(arc
					(start 263.400032 -83.620864)
					(mid 261.580901 -83.915242)
					(end 259.799836 -83.442302)
				)
				(arc
					(start 259.799836 -83.442302)
					(mid 258.658632 -83.836335)
					(end 257.453384 -83.906868)
				)
				(xy 257.0353 -84.324952) (xy 257.0353 -87.466932) (xy 257.616452 -88.048084) (xy 273.32813 -88.048084)
				(xy 277.927054 -92.647008) (xy 277.927054 -95.553276) (xy 278.886412 -96.512634) (xy 288.64306 -96.512634)
				(xy 289.378644 -95.77705)
				(arc
					(start 289.378644 -93.999812)
					(mid 296.956493 -83.676127)
					(end 309.076852 -87.811356)
				)
				(xy 309.94477 -87.811356) (xy 310.406288 -87.349838) (xy 310.406288 -60.426346) (xy 312.744358 -60.426346)
				(arc
					(start 313.013852 -60.156852)
					(mid 314.291219 -59.303406)
					(end 315.797946 -59.003692)
				)
				(xy 317.331344 -59.003692) (xy 320.44386 -55.891176) (xy 320.44386 -45.678852) (xy 321.221608 -44.901104)
				(xy 321.221608 -44.064936) (xy 320.785744 -43.629072)
				(arc
					(start 320.760852 -43.629072)
					(mid 318.74711 -43.896058)
					(end 316.84214 -43.190668)
				)
				(arc
					(start 316.84214 -43.190922)
					(mid 316.23352 -42.686882)
					(end 315.72962 -42.078148)
				)
				(xy 313.031886 -39.380414) (xy 313.031886 -2.032) (xy 362.895388 -2.032)
				(arc
					(start 362.895388 -5.842254)
					(mid 363.054844 -6.648778)
					(end 363.04982 -7.470902)
				)
				(xy 363.605064 -8.026146) (xy 364.428532 -8.026146) (xy 364.630462 -8.228076)
				(arc
					(start 364.744 -8.228076)
					(mid 366.053421 -8.443282)
					(end 367.225072 -9.066276)
				)
				(xy 371.374924 -9.066276) (xy 371.374924 -10.836148) (xy 375.75871 -15.219934)
				(arc
					(start 375.75871 -47.899066)
					(mid 375.462117 -49.390138)
					(end 374.617488 -50.654204)
				)
				(arc
					(start 372.821708 -52.449984)
					(mid 372.003276 -53.614276)
					(end 370.838984 -54.432708)
				)
				(xy 367.327942 -57.94375) (xy 352.619818 -57.94375) (xy 351.588324 -58.975244) (xy 351.588324 -104.141524)
				(xy 349.795846 -104.141524) (xy 349.710248 -104.203754) (xy 348.516702 -105.3973) (xy 348.516702 -108.61802)
				(xy 349.521272 -109.62259) (xy 365.05896 -109.62259)
				(arc
					(start 367.6904 -106.99115)
					(mid 367.773084 -106.825257)
					(end 367.86312 -106.663236)
				)
				(arc
					(start 367.86312 -103.45293)
					(mid 366.467141 -101.993064)
					(end 365.958882 -100.038154)
				)
				(arc
					(start 365.958882 -99.682554)
					(mid 366.071679 -98.737927)
					(end 366.403636 -97.846388)
				)
				(arc
					(start 366.403636 -94.793054)
					(mid 366.703327 -93.286318)
					(end 367.556796 -92.00896)
				)
				(arc
					(start 368.417856 -91.1479)
					(mid 369.18035 -90.09785)
					(end 370.2304 -89.335356)
				)
				(xy 370.761768 -88.804242)
				(arc
					(start 370.761768 -64.907922)
					(mid 371.061459 -63.401186)
					(end 371.914928 -62.123828)
				)
				(xy 373.506238 -60.532518) (xy 373.506238 -60.426346) (xy 373.61241 -60.426346)
				(arc
					(start 373.743728 -60.295028)
					(mid 375.021095 -59.441582)
					(end 376.527822 -59.141868)
				)
				(arc
					(start 378.28093 -59.141868)
					(mid 378.647651 -59.158982)
					(end 379.01118 -59.210194)
				)
				(xy 380.224792 -59.210194) (xy 383.54381 -55.891176)
				(arc
					(start 383.54381 -51.583844)
					(mid 382.791693 -49.544083)
					(end 383.191004 -47.407068)
				)
				(xy 383.191004 -46.835568) (xy 377.918472 -41.563036) (xy 377.918472 -39.647876) (xy 377.086876 -38.81628)
				(xy 377.086876 -27.913076)
				(arc
					(start 380.611888 -27.913076)
					(mid 380.701525 -27.796875)
					(end 380.795276 -27.683968)
				)
				(xy 380.795276 -19.538188) (xy 380.465838 -19.20875)
				(arc
					(start 380.465838 -17.855692)
					(mid 380.402947 -17.796819)
					(end 380.341378 -17.736566)
				)
				(arc
					(start 380.123954 -17.519396)
					(mid 377.276381 -13.033491)
					(end 381.29845 -9.561576)
				)
				(xy 383.115566 -9.561576) (xy 383.54381 -9.133332) (xy 383.54381 -2.032) (xy 402.235924 -2.032)
				(xy 402.235924 -7.407148) (xy 407.95702 -13.128244) (xy 408.578304 -13.128244)
				(arc
					(start 408.858466 -12.848082)
					(mid 410.263923 -10.489052)
					(end 412.848552 -9.561576)
				)
				(xy 413.901382 -9.561576) (xy 415.093912 -8.369046) (xy 415.093912 -2.032) (xy 425.995338 -2.032)
				(arc
					(start 425.995338 -5.842254)
					(mid 426.153205 -6.631873)
					(end 426.153326 -7.43712)
				)
				(xy 426.758608 -8.042402) (xy 427.443138 -8.042402) (xy 427.628812 -8.228076)
				(arc
					(start 427.863 -8.228076)
					(mid 429.172421 -8.443282)
					(end 430.344072 -9.066276)
				)
				(xy 434.493924 -9.066276)
			)
		)
	)
	(zone
		(layer "F.Cu")
		(hatch none 0.5)
		(connect_pads
			(clearance 0)
		)
		(min_thickness 0.25)
		(keepout
			(tracks allowed)
			(vias allowed)
			(pads allowed)
			(copperpour allowed)
			(footprints not_allowed)
		)
		(placement
			(enabled no)
			(sheetname "")
		)
		(fill
			(thermal_gap 0.5)
			(thermal_bridge_width 0.5)
			(island_removal_mode 0)
		)
		(polygon
			(pts
				(xy 289.699954 -345.000072) (xy 289.699954 -371.00002) (xy 276.750018 -371.00002)
				(arc
					(start 276.750018 -361.00004)
					(mid 276.457125 -360.292935)
					(end 275.75002 -360.000042)
				)
				(arc
					(start 273.45005 -360.000042)
					(mid 272.742945 -360.292935)
					(end 272.450052 -361.00004)
				)
				(xy 272.450052 -371.00002) (xy 252.000004 -371.00002) (xy 252.000004 -370.000022) (xy 200.300082 -370.000022)
				(xy 200.300082 -345.000072) (xy 245.000018 -345.000072)
			)
		)
	)
	(zone
		(layer "F.Cu")
		(hatch none 0.5)
		(connect_pads
			(clearance 0)
		)
		(min_thickness 0.25)
		(keepout
			(tracks allowed)
			(vias allowed)
			(pads allowed)
			(copperpour allowed)
			(footprints allowed)
		)
		(placement
			(enabled no)
			(sheetname "")
		)
		(fill
			(thermal_gap 0.5)
			(thermal_bridge_width 0.5)
			(island_removal_mode 0)
		)
		(polygon
			(pts
				(xy 213.3854 -166.2176) (xy 213.3854 -167.2336) (xy 211.6074 -167.2336) (xy 211.6074 -166.2176)
			)
		)
	)
	(zone
		(net "GND")
		(layer "F.Cu")
		(hatch none 0.5)
		(connect_pads
			(clearance 0.5)
		)
		(min_thickness 0.25)
		(fill yes
			(thermal_gap 0.5)
			(thermal_bridge_width 0.5)
			(island_removal_mode 0)
		)
		(polygon
			(pts
				(arc
					(start 273.45005 -357.968042)
					(mid 271.306104 -358.856094)
					(end 270.418052 -361.00004)
				)
				(xy 270.418052 -374.812306) (xy 271.687036 -374.812306)
				(arc
					(start 271.687036 -361.00004)
					(mid 272.203411 -359.753401)
					(end 273.45005 -359.237026)
				)
				(arc
					(start 275.75002 -359.237026)
					(mid 276.996659 -359.753401)
					(end 277.513034 -361.00004)
				)
				(xy 277.513034 -375.250964) (xy 278.782018 -375.250964)
				(arc
					(start 278.782018 -361.00004)
					(mid 277.893966 -358.856094)
					(end 275.75002 -357.968042)
				)
			)
		)
	)
	(zone
		(layer "F.Cu")
		(hatch none 0.5)
		(connect_pads
			(clearance 0)
		)
		(min_thickness 0.25)
		(keepout
			(tracks not_allowed)
			(vias allowed)
			(pads allowed)
			(copperpour not_allowed)
			(footprints allowed)
		)
		(placement
			(enabled no)
			(sheetname "")
		)
		(fill
			(thermal_gap 0.5)
			(thermal_bridge_width 0.5)
			(island_removal_mode 0)
		)
		(polygon
			(pts
				(arc
					(start 446.0875 -244.312694)
					(mid 445.60236 -243.827554)
					(end 445.11722 -244.312694)
				)
				(arc
					(start 445.11722 -245.45544)
					(mid 445.602233 -245.940834)
					(end 446.0875 -245.455694)
				)
				(xy 446.0875 -245.106444)
				(arc
					(start 445.79286 -245.106444)
					(mid 445.719474 -245.133114)
					(end 445.680338 -245.200678)
				)
				(arc
					(start 445.680338 -245.200678)
					(mid 445.601435 -245.722364)
					(end 445.52616 -245.20017)
				)
				(xy 445.52616 -245.189248)
				(arc
					(start 445.528192 -245.186962)
					(mid 445.604193 -245.032077)
					(end 445.759078 -244.956076)
				)
				(xy 445.761364 -244.954044) (xy 446.0875 -244.954044) (xy 446.0875 -244.814344) (xy 445.761364 -244.814344)
				(arc
					(start 445.759078 -244.812312)
					(mid 445.604193 -244.736311)
					(end 445.528192 -244.581426)
				)
				(xy 445.52616 -244.57914)
				(arc
					(start 445.52616 -244.568218)
					(mid 445.601436 -244.046052)
					(end 445.680338 -244.56771)
				)
				(arc
					(start 445.680338 -244.56771)
					(mid 445.719476 -244.635272)
					(end 445.79286 -244.661944)
				)
				(xy 446.0875 -244.661944)
			)
		)
	)
	(zone
		(net "P12V_B_4_VIN_U34")
		(layer "F.Cu")
		(hatch none 0.5)
		(connect_pads
			(clearance 0.5)
		)
		(min_thickness 0.25)
		(fill yes
			(thermal_gap 0.5)
			(thermal_bridge_width 0.5)
			(island_removal_mode 0)
		)
		(polygon
			(pts
				(xy 433.790344 -110.92942) (xy 432.73472 -111.985044) (xy 432.73472 -114.305334) (xy 432.935888 -114.506502)
				(xy 435.614826 -114.506502) (xy 435.723792 -114.397536) (xy 435.723792 -111.03356) (xy 435.619652 -110.92942)
			)
		)
	)
	(zone
		(net "P5V_B_3")
		(layer "F.Cu")
		(hatch none 0.5)
		(connect_pads
			(clearance 0.5)
		)
		(min_thickness 0.25)
		(fill yes
			(thermal_gap 0.5)
			(thermal_bridge_width 0.5)
			(island_removal_mode 0)
		)
		(polygon
			(pts
				(xy 399.923 -136.398) (xy 399.669 -136.652) (xy 399.669 -141.351) (xy 399.923 -141.605) (xy 402.209 -141.605)
				(xy 402.463 -141.351) (xy 402.463 -136.652) (xy 402.209 -136.398)
			)
		)
	)
	(zone
		(layer "F.Cu")
		(hatch none 0.5)
		(connect_pads
			(clearance 0)
		)
		(min_thickness 0.25)
		(keepout
			(tracks allowed)
			(vias allowed)
			(pads allowed)
			(copperpour allowed)
			(footprints allowed)
		)
		(placement
			(enabled no)
			(sheetname "")
		)
		(fill
			(thermal_gap 0.5)
			(thermal_bridge_width 0.5)
			(island_removal_mode 0)
		)
		(polygon
			(pts
				(xy 217.5764 -189.1284) (xy 217.5764 -191.389) (xy 215.7984 -191.389) (xy 215.7984 -189.1284)
			)
		)
	)
	(zone
		(layer "F.Cu")
		(hatch none 0.5)
		(connect_pads
			(clearance 0)
		)
		(min_thickness 0.25)
		(keepout
			(tracks allowed)
			(vias allowed)
			(pads allowed)
			(copperpour allowed)
			(footprints allowed)
		)
		(placement
			(enabled no)
			(sheetname "")
		)
		(fill
			(thermal_gap 0.5)
			(thermal_bridge_width 0.5)
			(island_removal_mode 0)
		)
		(polygon
			(pts
				(xy 32.5628 -19.6088) (xy 31.496 -19.6088) (xy 31.496 -17.9578) (xy 32.5628 -17.9578)
			)
		)
	)
	(zone
		(layer "F.Cu")
		(hatch none 0.5)
		(connect_pads
			(clearance 0)
		)
		(min_thickness 0.25)
		(keepout
			(tracks allowed)
			(vias allowed)
			(pads allowed)
			(copperpour allowed)
			(footprints allowed)
		)
		(placement
			(enabled no)
			(sheetname "")
		)
		(fill
			(thermal_gap 0.5)
			(thermal_bridge_width 0.5)
			(island_removal_mode 0)
		)
		(polygon
			(pts
				(xy 361.42676 -134.139686) (xy 363.01807 -134.139686) (xy 363.01807 -136.047734) (xy 361.42676 -136.047734)
			)
		)
	)
	(zone
		(layer "F.Cu")
		(hatch none 0.5)
		(connect_pads
			(clearance 0)
		)
		(min_thickness 0.25)
		(keepout
			(tracks allowed)
			(vias allowed)
			(pads allowed)
			(copperpour allowed)
			(footprints allowed)
		)
		(placement
			(enabled no)
			(sheetname "")
		)
		(fill
			(thermal_gap 0.5)
			(thermal_bridge_width 0.5)
			(island_removal_mode 0)
		)
		(polygon
			(pts
				(xy 29.863796 -374.7389) (xy 29.863796 -373.7483) (xy 29.863796 -372.8339) (xy 31.082996 -372.8339)
				(xy 31.082996 -374.7389) (xy 30.651196 -374.7389)
			)
		)
	)
	(zone
		(net "P12V_IN")
		(layer "F.Cu")
		(hatch none 0.5)
		(connect_pads
			(clearance 0.5)
		)
		(min_thickness 0.25)
		(fill yes
			(thermal_gap 0.5)
			(thermal_bridge_width 0.5)
			(island_removal_mode 0)
		)
		(polygon
			(pts
				(xy 282.321 -340.614) (xy 282.194 -340.741) (xy 282.194 -342.265) (xy 282.702 -342.773) (xy 282.702 -344.3732)
				(xy 282.9814 -344.6526) (xy 282.9814 -345.3638) (xy 283.083 -345.4654) (xy 284.3022 -345.4654) (xy 284.48 -345.2876)
				(xy 284.48 -340.741) (xy 284.353 -340.614)
			)
		)
		(polygon
			(pts
				(xy 283.6418 -344.678) (xy 283.4386 -344.678) (xy 283.4386 -344.8812) (xy 283.6418 -344.8812)
			)
		)
		(polygon
			(pts
				(xy 283.6926 -344.2462) (xy 283.4894 -344.2462) (xy 283.4894 -344.4494) (xy 283.6926 -344.4494)
			)
		)
		(polygon
			(pts
				(xy 283.6926 -343.3826) (xy 283.4894 -343.3826) (xy 283.4894 -343.5858) (xy 283.6926 -343.5858)
			)
		)
	)
	(zone
		(layer "F.Cu")
		(hatch none 0.5)
		(connect_pads
			(clearance 0)
		)
		(min_thickness 0.25)
		(keepout
			(tracks allowed)
			(vias allowed)
			(pads allowed)
			(copperpour allowed)
			(footprints not_allowed)
		)
		(placement
			(enabled no)
			(sheetname "")
		)
		(fill
			(thermal_gap 0.5)
			(thermal_bridge_width 0.5)
			(island_removal_mode 0)
		)
		(polygon
			(pts
				(xy 298.200064 -211.799932) (xy 491.450122 -211.799932) (xy 491.450122 -161.800032) (xy 478.00006 -161.800032)
				(xy 478.00006 -151.800052) (xy 463.449924 -151.800052) (xy 463.449924 -161.800032) (xy 446.449958 -161.800032)
				(xy 446.449958 -151.800052) (xy 431.900076 -151.800052) (xy 431.900076 -161.800032) (xy 414.90011 -161.800032)
				(xy 414.90011 -151.800052) (xy 400.349974 -151.800052) (xy 400.349974 -161.800032) (xy 383.350008 -161.800032)
				(xy 383.350008 -151.800052) (xy 368.800126 -151.800052) (xy 368.800126 -161.800032) (xy 351.799906 -161.800032)
				(xy 351.799906 -151.800052) (xy 337.250024 -151.800052) (xy 337.250024 -161.800032) (xy 320.250058 -161.800032)
				(xy 320.250058 -151.800052) (xy 305.699922 -151.800052) (xy 305.699922 -161.800032) (xy 298.200064 -161.800032)
			)
		)
	)
	(zone
		(net "MB0_CM_GATE")
		(layer "F.Cu")
		(hatch none 0.5)
		(connect_pads
			(clearance 0.5)
		)
		(min_thickness 0.25)
		(fill yes
			(thermal_gap 0.5)
			(thermal_bridge_width 0.5)
			(island_removal_mode 0)
		)
		(polygon
			(pts
				(xy 214.584026 -355.028754) (xy 214.471504 -355.141276) (xy 214.471504 -357.593138) (xy 214.755222 -357.876856)
				(xy 216.393776 -357.876856) (xy 216.803986 -357.466646) (xy 216.803986 -355.28885) (xy 216.54389 -355.028754)
			)
		)
	)
	(zone
		(layer "F.Cu")
		(hatch none 0.5)
		(connect_pads
			(clearance 0)
		)
		(min_thickness 0.25)
		(keepout
			(tracks allowed)
			(vias allowed)
			(pads allowed)
			(copperpour allowed)
			(footprints allowed)
		)
		(placement
			(enabled no)
			(sheetname "")
		)
		(fill
			(thermal_gap 0.5)
			(thermal_bridge_width 0.5)
			(island_removal_mode 0)
		)
		(polygon
			(pts
				(xy 188.099192 -364.325662) (xy 189.089792 -364.325662) (xy 190.004192 -364.325662) (xy 190.004192 -365.544862)
				(xy 188.099192 -365.544862) (xy 188.099192 -365.113062)
			)
		)
	)
	(zone
		(layer "F.Cu")
		(hatch none 0.5)
		(connect_pads
			(clearance 0)
		)
		(min_thickness 0.25)
		(keepout
			(tracks allowed)
			(vias allowed)
			(pads allowed)
			(copperpour allowed)
			(footprints not_allowed)
		)
		(placement
			(enabled no)
			(sheetname "")
		)
		(fill
			(thermal_gap 0.5)
			(thermal_bridge_width 0.5)
			(island_removal_mode 0)
		)
		(polygon
			(pts
				(arc
					(start 171.600114 -30.999938)
					(mid 170.200066 -32.399986)
					(end 168.800018 -30.999938)
				)
				(arc
					(start 168.800018 -30.999938)
					(mid 170.200066 -29.59989)
					(end 171.600114 -30.999938)
				)
			)
		)
	)
	(zone
		(net "GND")
		(layer "F.Cu")
		(hatch none 0.5)
		(connect_pads
			(clearance 0.5)
		)
		(min_thickness 0.25)
		(fill yes
			(thermal_gap 0.5)
			(thermal_bridge_width 0.5)
			(island_removal_mode 0)
		)
		(polygon
			(pts
				(xy 404.539958 -127.899668) (xy 404.265638 -128.173988) (xy 404.265638 -128.857502) (xy 404.946612 -129.538476)
				(xy 405.893524 -129.538476)
				(arc
					(start 405.893524 -133.01218)
					(mid 406.316512 -133.703161)
					(end 406.59685 -134.463282)
				)
				(arc
					(start 406.59685 -134.463282)
					(mid 406.799108 -135.163678)
					(end 406.86736 -135.889492)
				)
				(arc
					(start 406.86736 -142.1765)
					(mid 406.765445 -143.061861)
					(end 406.465024 -143.900906)
				)
				(xy 406.465024 -160.263586) (xy 403.152356 -163.576254) (xy 401.332192 -163.576254) (xy 401.131024 -163.777422)
				(xy 401.131024 -164.606986) (xy 401.486878 -164.96284) (xy 414.720532 -164.96284) (xy 414.950656 -164.732716)
				(xy 414.950656 -161.859468) (xy 408.633676 -155.542488) (xy 408.633676 -131.502404) (xy 405.03094 -127.899668)
			)
		)
	)
	(zone
		(layer "F.Cu")
		(hatch none 0.5)
		(connect_pads
			(clearance 0)
		)
		(min_thickness 0.25)
		(keepout
			(tracks allowed)
			(vias allowed)
			(pads allowed)
			(copperpour allowed)
			(footprints allowed)
		)
		(placement
			(enabled no)
			(sheetname "")
		)
		(fill
			(thermal_gap 0.5)
			(thermal_bridge_width 0.5)
			(island_removal_mode 0)
		)
		(polygon
			(pts
				(xy 34.671 -10.9982) (xy 33.6042 -10.9982) (xy 33.6042 -9.3472) (xy 34.671 -9.3472)
			)
		)
	)
	(zone
		(net "12V_PRE_35")
		(layer "F.Cu")
		(hatch none 0.5)
		(connect_pads
			(clearance 0.5)
		)
		(min_thickness 0.25)
		(fill yes
			(thermal_gap 0.5)
			(thermal_bridge_width 0.5)
			(island_removal_mode 0)
		)
		(polygon
			(pts
				(xy 474.726 -34.671) (xy 474.599 -34.798) (xy 474.599 -38.5826) (xy 476.297244 -40.280844) (xy 479.954844 -40.280844)
				(xy 482.346 -42.672) (xy 486.283 -42.672) (xy 486.41 -42.545) (xy 486.41 -41.783) (xy 486.283 -41.656)
				(xy 482.981 -41.656) (xy 480.0346 -38.7096) (xy 476.683324 -38.7096) (xy 476.4532 -38.479476) (xy 476.4532 -35.1282)
				(xy 475.996 -34.671)
			)
		)
	)
	(zone
		(layer "F.Cu")
		(hatch none 0.5)
		(connect_pads
			(clearance 0)
		)
		(min_thickness 0.25)
		(keepout
			(tracks allowed)
			(vias allowed)
			(pads allowed)
			(copperpour allowed)
			(footprints not_allowed)
		)
		(placement
			(enabled no)
			(sheetname "")
		)
		(fill
			(thermal_gap 0.5)
			(thermal_bridge_width 0.5)
			(island_removal_mode 0)
		)
		(polygon
			(pts
				(xy 231.199944 -234.00004) (xy 256.199894 -234.00004) (xy 256.199894 -259.999988) (xy 231.199944 -259.999988)
			)
		)
	)
	(zone
		(layer "F.Cu")
		(hatch none 0.5)
		(connect_pads
			(clearance 0)
		)
		(min_thickness 0.25)
		(keepout
			(tracks allowed)
			(vias allowed)
			(pads allowed)
			(copperpour allowed)
			(footprints allowed)
		)
		(placement
			(enabled no)
			(sheetname "")
		)
		(fill
			(thermal_gap 0.5)
			(thermal_bridge_width 0.5)
			(island_removal_mode 0)
		)
		(polygon
			(pts
				(xy 166.873174 -366.110266) (xy 168.346374 -366.110266) (xy 168.346374 -368.531902) (xy 166.873174 -368.531902)
			)
		)
	)
	(zone
		(net "GND")
		(layer "F.Cu")
		(hatch none 0.5)
		(connect_pads
			(clearance 0.5)
		)
		(min_thickness 0.25)
		(fill yes
			(thermal_gap 0.5)
			(thermal_bridge_width 0.5)
			(island_removal_mode 0)
		)
		(polygon
			(pts
				(xy 404.613618 -40.451024) (xy 404.393654 -40.670988) (xy 404.393654 -45.164756) (xy 401.131024 -48.427386)
				(xy 401.131024 -50.433224)
				(arc
					(start 399.015204 -50.433224)
					(mid 398.958268 -50.473591)
					(end 398.90065 -50.51298)
				)
				(xy 397.014446 -52.399184) (xy 397.014446 -53.001672)
				(arc
					(start 397.8148 -53.802026)
					(mid 401.613783 -56.44664)
					(end 403.960076 -60.43676)
				)
				(xy 405.05634 -60.43676) (xy 405.05634 -60.426346) (xy 405.162512 -60.426346)
				(arc
					(start 405.29383 -60.295028)
					(mid 406.571197 -59.441582)
					(end 408.077924 -59.141868)
				)
				(arc
					(start 409.831032 -59.141868)
					(mid 410.454337 -59.191515)
					(end 411.061916 -59.339226)
				)
				(arc
					(start 413.328104 -59.339226)
					(mid 414.150052 -58.170855)
					(end 415.0868 -57.092342)
				)
				(xy 415.0868 -45.6692) (xy 415.627312 -45.6692) (xy 416.494976 -44.801536) (xy 416.494976 -44.37126)
				(xy 416.473386 -44.37126) (xy 416.032188 -43.930062) (xy 414.913064 -43.930062) (xy 414.38576 -44.457366)
				(arc
					(start 414.38576 -50.51933)
					(mid 410.4894 -55.851261)
					(end 406.59304 -50.51933)
				)
				(xy 406.59304 -41.092628) (xy 405.951436 -40.451024)
			)
		)
	)
	(zone
		(net "MB3_CM_GATE_R")
		(layer "F.Cu")
		(hatch none 0.5)
		(connect_pads
			(clearance 0.5)
		)
		(min_thickness 0.25)
		(fill yes
			(thermal_gap 0.5)
			(thermal_bridge_width 0.5)
			(island_removal_mode 0)
		)
		(polygon
			(pts
				(xy 265.885168 -350.642936) (xy 265.723878 -350.804226) (xy 265.723878 -356.021386) (xy 265.884914 -356.182422)
				(xy 268.303756 -356.182422) (xy 268.507972 -355.978206) (xy 268.507972 -351.182432) (xy 267.968476 -350.642936)
			)
		)
	)
	(zone
		(net "P5V_B_4")
		(layer "F.Cu")
		(hatch none 0.5)
		(connect_pads
			(clearance 0.5)
		)
		(min_thickness 0.25)
		(fill yes
			(thermal_gap 0.5)
			(thermal_bridge_width 0.5)
			(island_removal_mode 0)
		)
		(polygon
			(pts
				(xy 368.3 -21.336) (xy 368.046 -21.59) (xy 368.046 -26.289) (xy 368.3 -26.543) (xy 370.586 -26.543)
				(xy 370.84 -26.289) (xy 370.84 -21.59) (xy 370.586 -21.336)
			)
		)
	)
	(zone
		(net "GND")
		(layer "F.Cu")
		(hatch none 0.5)
		(connect_pads
			(clearance 0.5)
		)
		(min_thickness 0.25)
		(fill yes
			(thermal_gap 0.5)
			(thermal_bridge_width 0.5)
			(island_removal_mode 0)
		)
		(polygon
			(pts
				(xy 66.94805 -238.1123) (xy 66.567558 -238.492792) (xy 66.567558 -239.19815)
				(arc
					(start 66.83121 -239.461802)
					(mid 69.043088 -240.905361)
					(end 69.901054 -243.403374)
				)
				(arc
					(start 69.901054 -246.578374)
					(mid 69.429531 -248.478869)
					(end 68.124324 -249.93854)
				)
				(arc
					(start 68.124324 -250.401074)
					(mid 68.098581 -250.85761)
					(end 68.021708 -251.308362)
				)
				(arc
					(start 68.021708 -251.308362)
					(mid 67.849316 -253.499616)
					(end 66.567558 -255.28524)
				)
				(xy 66.567558 -256.742946)
				(arc
					(start 66.97599 -257.151378)
					(mid 68.361198 -257.341894)
					(end 69.601334 -257.9878)
				)
				(xy 70.56755 -257.9878) (xy 71.435976 -257.119374) (xy 71.435976 -253.680976) (xy 72.781414 -253.680976)
				(xy 73.404476 -253.057914)
				(arc
					(start 73.404476 -250.839224)
					(mid 72.774612 -249.490967)
					(end 72.668892 -248.006616)
				)
				(arc
					(start 72.668892 -247.395746)
					(mid 72.870475 -246.131612)
					(end 73.455276 -244.992906)
				)
				(xy 73.455276 -242.543076) (xy 73.887076 -242.111276)
				(arc
					(start 81.209134 -242.111276)
					(mid 82.7024 -241.832659)
					(end 84.195666 -242.111276)
				)
				(xy 85.475826 -242.111276) (xy 86.193884 -241.393218) (xy 86.193884 -238.740188) (xy 85.565996 -238.1123)
			)
		)
	)
	(zone
		(net "GND")
		(layer "F.Cu")
		(hatch none 0.5)
		(connect_pads
			(clearance 0.5)
		)
		(min_thickness 0.25)
		(fill yes
			(thermal_gap 0.5)
			(thermal_bridge_width 0.5)
			(island_removal_mode 0)
		)
		(polygon
			(pts
				(xy 9.390126 -155.1432) (xy 8.73506 -155.798266) (xy 8.73506 -167.963088) (xy 9.02843 -168.256458)
				(xy 9.750298 -168.256458) (xy 13.624306 -164.38245) (xy 19.611848 -164.38245) (xy 20.013676 -163.980622)
				(xy 20.013676 -162.816286) (xy 19.898614 -162.701224) (xy 19.365976 -162.701224) (xy 19.365976 -162.168586)
				(xy 12.34059 -155.1432)
			)
		)
	)
	(zone
		(layer "F.Cu")
		(hatch none 0.5)
		(connect_pads
			(clearance 0)
		)
		(min_thickness 0.25)
		(keepout
			(tracks allowed)
			(vias allowed)
			(pads allowed)
			(copperpour allowed)
			(footprints not_allowed)
		)
		(placement
			(enabled no)
			(sheetname "")
		)
		(fill
			(thermal_gap 0.5)
			(thermal_bridge_width 0.5)
			(island_removal_mode 0)
		)
		(polygon
			(pts
				(arc
					(start 272.450052 -382.585722)
					(mid 272.373932 -382.968405)
					(end 272.15719 -383.292858)
				)
				(arc
					(start 269.74292 -385.707128)
					(mid 269.418483 -385.92391)
					(end 269.035784 -385.99999)
				)
				(arc
					(start 253.000002 -385.99999)
					(mid 252.292897 -385.707097)
					(end 252.000004 -384.999992)
				)
				(arc
					(start 252.000004 -381)
					(mid 251.707111 -380.292895)
					(end 251.000006 -380.000002)
				)
				(xy 252.000004 -380.000002) (xy 252.000004 -371.00002) (xy 272.450052 -371.00002)
			)
		)
	)
	(zone
		(net "12V_PRE_22")
		(layer "F.Cu")
		(hatch none 0.5)
		(connect_pads
			(clearance 0.5)
		)
		(min_thickness 0.25)
		(fill yes
			(thermal_gap 0.5)
			(thermal_bridge_width 0.5)
			(island_removal_mode 0)
		)
		(polygon
			(pts
				(xy 456.7936 -154.686) (xy 454.7616 -156.718) (xy 452.1962 -156.718) (xy 451.9422 -156.972) (xy 451.9422 -157.5054)
				(xy 452.1708 -157.734) (xy 458.1652 -157.734) (xy 459.1812 -156.718) (xy 459.1812 -154.813) (xy 459.0542 -154.686)
			)
		)
	)
	(zone
		(layer "F.Cu")
		(hatch none 0.5)
		(connect_pads
			(clearance 0)
		)
		(min_thickness 0.25)
		(keepout
			(tracks allowed)
			(vias allowed)
			(pads allowed)
			(copperpour allowed)
			(footprints allowed)
		)
		(placement
			(enabled no)
			(sheetname "")
		)
		(fill
			(thermal_gap 0.5)
			(thermal_bridge_width 0.5)
			(island_removal_mode 0)
		)
		(polygon
			(pts
				(xy 255.3208 -367.2332) (xy 256.9464 -367.2332) (xy 256.9464 -368.0206) (xy 255.3208 -368.0206)
			)
		)
	)
	(zone
		(net "GND")
		(layer "F.Cu")
		(hatch none 0.5)
		(connect_pads
			(clearance 0.5)
		)
		(min_thickness 0.25)
		(fill yes
			(thermal_gap 0.5)
			(thermal_bridge_width 0.5)
			(island_removal_mode 0)
		)
		(polygon
			(pts
				(xy 163.279582 -20.203414) (xy 163.053522 -20.429474) (xy 163.0426 -20.429474)
				(arc
					(start 162.762692 -20.709382)
					(mid 162.29441 -22.317397)
					(end 161.21761 -23.600156)
				)
				(arc
					(start 161.21761 -26.634694)
					(mid 161.581724 -26.824316)
					(end 161.925 -27.049476)
				)
				(xy 162.612324 -27.049476)
				(arc
					(start 162.612324 -27.683968)
					(mid 162.696123 -27.784507)
					(end 162.776662 -27.887676)
				)
				(xy 164.579808 -27.887676) (xy 165.669976 -26.797508)
				(arc
					(start 165.669976 -21.27885)
					(mid 164.948451 -20.776747)
					(end 164.28212 -20.203414)
				)
			)
		)
	)
	(zone
		(layer "F.Cu")
		(hatch none 0.5)
		(connect_pads
			(clearance 0)
		)
		(min_thickness 0.25)
		(keepout
			(tracks not_allowed)
			(vias allowed)
			(pads allowed)
			(copperpour not_allowed)
			(footprints allowed)
		)
		(placement
			(enabled no)
			(sheetname "")
		)
		(fill
			(thermal_gap 0.5)
			(thermal_bridge_width 0.5)
			(island_removal_mode 0)
		)
		(polygon
			(pts
				(arc
					(start 160.970722 -14.41958)
					(mid 160.485709 -13.934186)
					(end 160.000442 -14.419326)
				)
				(xy 160.000442 -14.768576)
				(arc
					(start 160.326578 -14.768576)
					(mid 160.385129 -14.744323)
					(end 160.409382 -14.685772)
				)
				(arc
					(start 160.409382 -14.67485)
					(mid 160.485582 -14.152682)
					(end 160.561782 -14.67485)
				)
				(xy 160.561782 -14.717268)
				(arc
					(start 160.559242 -14.719808)
					(mid 160.492847 -14.852041)
					(end 160.360614 -14.918436)
				)
				(xy 160.358074 -14.920976) (xy 160.000442 -14.920976) (xy 160.000442 -15.060676) (xy 160.358074 -15.060676)
				(arc
					(start 160.360614 -15.063216)
					(mid 160.492847 -15.129611)
					(end 160.559242 -15.261844)
				)
				(xy 160.561782 -15.264384)
				(arc
					(start 160.561782 -15.306802)
					(mid 160.485582 -15.82897)
					(end 160.409382 -15.306802)
				)
				(arc
					(start 160.409382 -15.29588)
					(mid 160.385129 -15.237329)
					(end 160.326578 -15.213076)
				)
				(xy 160.000442 -15.213076)
				(arc
					(start 160.000442 -15.562326)
					(mid 160.485582 -16.047466)
					(end 160.970722 -15.562326)
				)
			)
		)
	)
	(zone
		(layer "F.Cu")
		(hatch none 0.5)
		(connect_pads
			(clearance 0)
		)
		(min_thickness 0.25)
		(keepout
			(tracks not_allowed)
			(vias allowed)
			(pads allowed)
			(copperpour not_allowed)
			(footprints allowed)
		)
		(placement
			(enabled no)
			(sheetname "")
		)
		(fill
			(thermal_gap 0.5)
			(thermal_bridge_width 0.5)
			(island_removal_mode 0)
		)
		(polygon
			(pts
				(arc
					(start 382.97739 -244.302534)
					(mid 382.49225 -243.817394)
					(end 382.00711 -244.302534)
				)
				(arc
					(start 382.00711 -245.44528)
					(mid 382.492123 -245.930674)
					(end 382.97739 -245.445534)
				)
				(xy 382.97739 -245.096284)
				(arc
					(start 382.6891 -245.096284)
					(mid 382.613595 -245.122831)
					(end 382.571244 -245.190772)
				)
				(arc
					(start 382.571244 -245.190772)
					(mid 382.4913 -245.712184)
					(end 382.41605 -245.19001)
				)
				(xy 382.41605 -245.185438)
				(arc
					(start 382.418082 -245.183406)
					(mid 382.496 -245.023834)
					(end 382.655572 -244.945916)
				)
				(xy 382.657604 -244.943884) (xy 382.97739 -244.943884) (xy 382.97739 -244.804184) (xy 382.657604 -244.804184)
				(arc
					(start 382.655572 -244.802152)
					(mid 382.496 -244.724234)
					(end 382.418082 -244.564662)
				)
				(xy 382.41605 -244.56263)
				(arc
					(start 382.41605 -244.558058)
					(mid 382.491299 -244.03582)
					(end 382.571244 -244.557296)
				)
				(arc
					(start 382.571244 -244.557296)
					(mid 382.613548 -244.625296)
					(end 382.6891 -244.651784)
				)
				(xy 382.97739 -244.651784)
			)
		)
	)
	(zone
		(net "P12V_HDD26")
		(layer "F.Cu")
		(hatch none 0.5)
		(connect_pads
			(clearance 0.5)
		)
		(min_thickness 0.25)
		(fill yes
			(thermal_gap 0.5)
			(thermal_bridge_width 0.5)
			(island_removal_mode 0)
		)
		(polygon
			(pts
				(xy 75.438 -32.258) (xy 75.184 -32.512) (xy 75.184 -34.163) (xy 75.438 -34.417) (xy 77.597 -34.417)
				(xy 78.105 -34.925) (xy 78.105 -37.465) (xy 85.852 -45.212) (xy 94.361 -45.212) (xy 94.488 -45.085)
				(xy 94.488 -43.307) (xy 94.361 -43.18) (xy 88.392 -43.18) (xy 87.757 -42.545) (xy 86.106 -42.545)
				(xy 81.788 -38.227) (xy 81.788 -34.671) (xy 80.645 -33.528) (xy 80.645 -32.512) (xy 80.391 -32.258)
			)
		)
		(polygon
			(pts
				(xy 87.9094 -44.2214) (xy 87.7062 -44.2214) (xy 87.7062 -44.4246) (xy 87.9094 -44.4246)
			)
		)
		(polygon
			(pts
				(xy 87.0458 -44.2214) (xy 86.8426 -44.2214) (xy 86.8426 -44.4246) (xy 87.0458 -44.4246)
			)
		)
	)
	(zone
		(net "P5V_B_2")
		(layer "F.Cu")
		(hatch none 0.5)
		(connect_pads
			(clearance 0.5)
		)
		(min_thickness 0.25)
		(fill yes
			(thermal_gap 0.5)
			(thermal_bridge_width 0.5)
			(island_removal_mode 0)
		)
		(polygon
			(pts
				(xy 49.911 -21.844) (xy 49.657 -22.098) (xy 49.657 -24.384) (xy 49.911 -24.638) (xy 54.61 -24.638)
				(xy 54.864 -24.384) (xy 54.864 -22.098) (xy 54.61 -21.844)
			)
		)
	)
	(zone
		(layer "F.Cu")
		(hatch none 0.5)
		(connect_pads
			(clearance 0)
		)
		(min_thickness 0.25)
		(keepout
			(tracks allowed)
			(vias allowed)
			(pads allowed)
			(copperpour allowed)
			(footprints allowed)
		)
		(placement
			(enabled no)
			(sheetname "")
		)
		(fill
			(thermal_gap 0.5)
			(thermal_bridge_width 0.5)
			(island_removal_mode 0)
		)
		(polygon
			(pts
				(xy 171.7802 -371.1448) (xy 175.895 -371.1448) (xy 177.038 -371.1448) (xy 177.1904 -371.2972) (xy 177.1904 -372.6688)
				(xy 177.0634 -372.7958) (xy 175.895 -372.7958) (xy 174.8917 -372.7958) (xy 174.1043 -373.5832) (xy 171.8818 -373.5832)
				(xy 171.7802 -373.4816) (xy 171.7802 -372.7958)
			)
		)
	)
	(zone
		(layer "F.Cu")
		(hatch none 0.5)
		(connect_pads
			(clearance 0)
		)
		(min_thickness 0.25)
		(keepout
			(tracks not_allowed)
			(vias allowed)
			(pads allowed)
			(copperpour not_allowed)
			(footprints allowed)
		)
		(placement
			(enabled no)
			(sheetname "")
		)
		(fill
			(thermal_gap 0.5)
			(thermal_bridge_width 0.5)
			(island_removal_mode 0)
		)
		(polygon
			(pts
				(arc
					(start 97.870772 -129.419604)
					(mid 97.385759 -128.93421)
					(end 96.900492 -129.41935)
				)
				(xy 96.900492 -129.7686)
				(arc
					(start 97.226628 -129.7686)
					(mid 97.285179 -129.744347)
					(end 97.309432 -129.685796)
				)
				(arc
					(start 97.309432 -129.674874)
					(mid 97.385632 -129.152706)
					(end 97.461832 -129.674874)
				)
				(xy 97.461832 -129.717292)
				(arc
					(start 97.459292 -129.719832)
					(mid 97.392897 -129.852065)
					(end 97.260664 -129.91846)
				)
				(xy 97.258124 -129.921) (xy 96.900492 -129.921) (xy 96.900492 -130.0607) (xy 97.258124 -130.0607)
				(arc
					(start 97.260664 -130.06324)
					(mid 97.392897 -130.129635)
					(end 97.459292 -130.261868)
				)
				(xy 97.461832 -130.264408)
				(arc
					(start 97.461832 -130.306826)
					(mid 97.385632 -130.828994)
					(end 97.309432 -130.306826)
				)
				(arc
					(start 97.309432 -130.295904)
					(mid 97.285179 -130.237353)
					(end 97.226628 -130.2131)
				)
				(xy 96.900492 -130.2131)
				(arc
					(start 96.900492 -130.56235)
					(mid 97.385632 -131.04749)
					(end 97.870772 -130.56235)
				)
			)
		)
	)
	(zone
		(net "P12V_B")
		(layer "F.Cu")
		(hatch none 0.5)
		(connect_pads
			(clearance 0.5)
		)
		(min_thickness 0.25)
		(fill yes
			(thermal_gap 0.5)
			(thermal_bridge_width 0.5)
			(island_removal_mode 0)
		)
		(polygon
			(pts
				(xy 107.569 -10.033) (xy 107.315 -10.287) (xy 107.315 -12.827) (xy 107.569 -13.081) (xy 110.871 -13.081)
				(xy 111.125 -12.827) (xy 111.125 -10.541) (xy 110.617 -10.033)
			)
		)
	)
	(zone
		(layer "F.Cu")
		(hatch none 0.5)
		(connect_pads
			(clearance 0)
		)
		(min_thickness 0.25)
		(keepout
			(tracks not_allowed)
			(vias allowed)
			(pads allowed)
			(copperpour not_allowed)
			(footprints allowed)
		)
		(placement
			(enabled no)
			(sheetname "")
		)
		(fill
			(thermal_gap 0.5)
			(thermal_bridge_width 0.5)
			(island_removal_mode 0)
		)
		(polygon
			(pts
				(arc
					(start 192.520824 -129.419604)
					(mid 192.035811 -128.93421)
					(end 191.550544 -129.41935)
				)
				(xy 191.550544 -129.7686)
				(arc
					(start 191.87668 -129.7686)
					(mid 191.935231 -129.744347)
					(end 191.959484 -129.685796)
				)
				(arc
					(start 191.959484 -129.674874)
					(mid 192.035684 -129.152706)
					(end 192.111884 -129.674874)
				)
				(xy 192.111884 -129.717292)
				(arc
					(start 192.109344 -129.719832)
					(mid 192.042949 -129.852065)
					(end 191.910716 -129.91846)
				)
				(xy 191.908176 -129.921) (xy 191.550544 -129.921) (xy 191.550544 -130.0607) (xy 191.908176 -130.0607)
				(arc
					(start 191.910716 -130.06324)
					(mid 192.042949 -130.129635)
					(end 192.109344 -130.261868)
				)
				(xy 192.111884 -130.264408)
				(arc
					(start 192.111884 -130.306826)
					(mid 192.035684 -130.828994)
					(end 191.959484 -130.306826)
				)
				(arc
					(start 191.959484 -130.295904)
					(mid 191.935231 -130.237353)
					(end 191.87668 -130.2131)
				)
				(xy 191.550544 -130.2131)
				(arc
					(start 191.550544 -130.56235)
					(mid 192.035684 -131.04749)
					(end 192.520824 -130.56235)
				)
			)
		)
	)
	(zone
		(layer "F.Cu")
		(hatch none 0.5)
		(connect_pads
			(clearance 0)
		)
		(min_thickness 0.25)
		(keepout
			(tracks allowed)
			(vias allowed)
			(pads allowed)
			(copperpour allowed)
			(footprints allowed)
		)
		(placement
			(enabled no)
			(sheetname "")
		)
		(fill
			(thermal_gap 0.5)
			(thermal_bridge_width 0.5)
			(island_removal_mode 0)
		)
		(polygon
			(pts
				(xy 250.2408 -370.3066) (xy 250.0884 -370.1542) (xy 250.0884 -368.5794) (xy 250.5202 -368.1476)
				(xy 251.6632 -368.1476) (xy 251.6632 -367.8936) (xy 254.1778 -367.8936) (xy 254.1778 -370.3066)
			)
		)
	)
	(zone
		(net "MB3_CM_GATE_R")
		(layer "F.Cu")
		(hatch none 0.5)
		(connect_pads
			(clearance 0.5)
		)
		(min_thickness 0.25)
		(fill yes
			(thermal_gap 0.5)
			(thermal_bridge_width 0.5)
			(island_removal_mode 0)
		)
		(polygon
			(pts
				(xy 266.016994 -343.588848) (xy 265.948414 -343.657428) (xy 265.948414 -345.10091) (xy 266.033758 -345.186254)
				(xy 268.046708 -345.186254) (xy 268.24178 -344.991182) (xy 268.24178 -343.763092) (xy 268.067536 -343.588848)
			)
		)
	)
	(zone
		(net "GND")
		(layer "F.Cu")
		(hatch none 0.5)
		(connect_pads
			(clearance 0.5)
		)
		(min_thickness 0.25)
		(fill yes
			(thermal_gap 0.5)
			(thermal_bridge_width 0.5)
			(island_removal_mode 0)
		)
		(polygon
			(pts
				(xy 57.502552 -329.949556) (xy 56.261254 -331.190854) (xy 56.261254 -351.841054) (xy 59.315096 -354.894896)
				(xy 62.25667 -354.894896) (xy 63.088012 -355.726238) (xy 63.354458 -355.726238) (xy 63.354458 -355.992684)
				(xy 65.06845 -357.706676) (xy 65.06845 -365.814356)
				(arc
					(start 64.449452 -366.4331)
					(mid 64.474636 -367.535909)
					(end 64.261746 -368.618262)
				)
				(arc
					(start 64.261746 -371.0813)
					(mid 64.417729 -371.725156)
					(end 64.488822 -372.383812)
				)
				(xy 64.869314 -372.764304) (xy 119.868696 -372.764304) (xy 123.133866 -369.499134) (xy 123.133866 -366.336834)
				(xy 122.176286 -365.379254) (xy 113.719356 -365.379254) (xy 110.798356 -368.300254) (xy 103.38435 -368.300254)
				(xy 102.025196 -369.659408) (xy 92.976192 -369.659408) (xy 90.454988 -367.138204) (xy 90.454988 -355.950012)
				(xy 92.968826 -353.436174) (xy 99.391978 -353.436174) (xy 100.012246 -352.815906) (xy 100.012246 -351.301558)
				(xy 99.484942 -350.774254) (xy 71.700644 -350.774254) (xy 68.960746 -348.034356) (xy 68.960746 -341.551006)
				(xy 68.016882 -340.607142)
				(arc
					(start 64.090804 -340.607142)
					(mid 57.815647 -337.889895)
					(end 59.213242 -331.195934)
				)
				(xy 59.213242 -330.825602) (xy 58.337196 -329.949556)
			)
		)
	)
	(zone
		(net "MB0_CM_GATE")
		(layer "F.Cu")
		(hatch none 0.5)
		(connect_pads
			(clearance 0.5)
		)
		(min_thickness 0.25)
		(fill yes
			(thermal_gap 0.5)
			(thermal_bridge_width 0.5)
			(island_removal_mode 0)
		)
		(polygon
			(pts
				(xy 172.6184 -371.2845) (xy 172.2882 -371.6147) (xy 172.2882 -373.3673) (xy 172.4025 -373.4816)
				(xy 173.4312 -373.4816) (xy 173.6598 -373.253) (xy 173.6598 -371.2845)
			)
		)
	)
	(zone
		(net "5V_PRE_33")
		(layer "F.Cu")
		(hatch none 0.5)
		(connect_pads
			(clearance 0.5)
		)
		(min_thickness 0.25)
		(fill yes
			(thermal_gap 0.5)
			(thermal_bridge_width 0.5)
			(island_removal_mode 0)
		)
		(polygon
			(pts
				(xy 424.053 -30.988) (xy 423.799 -31.242) (xy 423.799 -33.782) (xy 423.418 -34.163) (xy 420.878 -34.163)
				(xy 420.624 -34.417) (xy 420.624 -34.798) (xy 420.878 -35.052) (xy 424.18 -35.052) (xy 425.45 -33.782)
				(xy 425.45 -31.242) (xy 425.196 -30.988)
			)
		)
	)
	(zone
		(layer "F.Cu")
		(hatch none 0.5)
		(connect_pads
			(clearance 0)
		)
		(min_thickness 0.25)
		(keepout
			(tracks not_allowed)
			(vias allowed)
			(pads allowed)
			(copperpour not_allowed)
			(footprints allowed)
		)
		(placement
			(enabled no)
			(sheetname "")
		)
		(fill
			(thermal_gap 0.5)
			(thermal_bridge_width 0.5)
			(island_removal_mode 0)
		)
		(polygon
			(pts
				(arc
					(start 399.64995 -23.999952)
					(mid 404.400004 -19.249898)
					(end 409.150058 -23.999952)
				)
				(arc
					(start 409.150058 -23.999952)
					(mid 404.400004 -28.750006)
					(end 399.64995 -23.999952)
				)
			)
		)
	)
	(zone
		(net "GND")
		(layer "F.Cu")
		(hatch none 0.5)
		(connect_pads
			(clearance 0.5)
		)
		(min_thickness 0.25)
		(fill yes
			(thermal_gap 0.5)
			(thermal_bridge_width 0.5)
			(island_removal_mode 0)
		)
		(polygon
			(pts
				(xy 73.04913 -270.2052) (xy 72.24395 -271.01038) (xy 72.24395 -280.992072) (xy 73.251822 -281.999944)
				(xy 82.662014 -281.999944) (xy 83.132676 -281.529282) (xy 83.132676 -277.878286) (xy 83.017614 -277.763224)
				(xy 82.484976 -277.763224) (xy 82.484976 -277.230586) (xy 75.45959 -270.2052)
			)
		)
	)
	(zone
		(layer "F.Cu")
		(hatch none 0.5)
		(connect_pads
			(clearance 0)
		)
		(min_thickness 0.25)
		(keepout
			(tracks allowed)
			(vias allowed)
			(pads allowed)
			(copperpour allowed)
			(footprints not_allowed)
		)
		(placement
			(enabled no)
			(sheetname "")
		)
		(fill
			(thermal_gap 0.5)
			(thermal_bridge_width 0.5)
			(island_removal_mode 0)
		)
		(polygon
			(pts
				(arc
					(start 141.824964 -181.799992)
					(mid 127.824992 -195.799964)
					(end 113.82502 -181.799992)
				)
				(arc
					(start 113.82502 -181.799992)
					(mid 127.824992 -167.80002)
					(end 141.824964 -181.799992)
				)
			)
		)
	)
	(zone
		(net "GND")
		(layer "F.Cu")
		(hatch none 0.5)
		(connect_pads
			(clearance 0.5)
		)
		(min_thickness 0.25)
		(fill yes
			(thermal_gap 0.5)
			(thermal_bridge_width 0.5)
			(island_removal_mode 0)
		)
		(polygon
			(pts
				(xy 202.5396 -140.716) (xy 202.2856 -140.97) (xy 202.2856 -144.526) (xy 202.6666 -144.907) (xy 209.1436 -144.907)
				(xy 209.3976 -144.653) (xy 209.3976 -140.97) (xy 209.1436 -140.716)
			)
		)
	)
	(zone
		(layer "F.Cu")
		(hatch none 0.5)
		(connect_pads
			(clearance 0)
		)
		(min_thickness 0.25)
		(keepout
			(tracks not_allowed)
			(vias allowed)
			(pads allowed)
			(copperpour not_allowed)
			(footprints allowed)
		)
		(placement
			(enabled no)
			(sheetname "")
		)
		(fill
			(thermal_gap 0.5)
			(thermal_bridge_width 0.5)
			(island_removal_mode 0)
		)
		(polygon
			(pts
				(arc
					(start 102.350062 -23.999952)
					(mid 107.100116 -19.249898)
					(end 111.849916 -23.999952)
				)
				(arc
					(start 111.849916 -23.999952)
					(mid 107.100116 -28.749752)
					(end 102.350062 -23.999952)
				)
			)
		)
	)
	(zone
		(net "MB3_12V_CTRL_GATE1")
		(layer "F.Cu")
		(hatch none 0.5)
		(connect_pads
			(clearance 0.5)
		)
		(min_thickness 0.25)
		(fill yes
			(thermal_gap 0.5)
			(thermal_bridge_width 0.5)
			(island_removal_mode 0)
		)
		(polygon
			(pts
				(xy 263.264396 -350.636332) (xy 263.031986 -350.868742) (xy 260.425184 -350.868742) (xy 260.317996 -350.97593)
				(xy 260.317996 -352.175318) (xy 260.550152 -352.407474) (xy 265.211052 -352.407474) (xy 265.424158 -352.194368)
				(xy 265.424158 -350.7486) (xy 265.31189 -350.636332)
			)
		)
	)
	(zone
		(layer "F.Cu")
		(hatch none 0.5)
		(connect_pads
			(clearance 0)
		)
		(min_thickness 0.25)
		(keepout
			(tracks allowed)
			(vias allowed)
			(pads allowed)
			(copperpour allowed)
			(footprints allowed)
		)
		(placement
			(enabled no)
			(sheetname "")
		)
		(fill
			(thermal_gap 0.5)
			(thermal_bridge_width 0.5)
			(island_removal_mode 0)
		)
		(polygon
			(pts
				(xy 320.668396 -380.1999) (xy 320.668396 -379.2093) (xy 320.668396 -378.2949) (xy 321.887596 -378.2949)
				(xy 321.887596 -380.1999) (xy 321.455796 -380.1999)
			)
		)
	)
	(zone
		(layer "F.Cu")
		(hatch none 0.5)
		(connect_pads
			(clearance 0)
		)
		(min_thickness 0.25)
		(keepout
			(tracks allowed)
			(vias allowed)
			(pads allowed)
			(copperpour allowed)
			(footprints not_allowed)
		)
		(placement
			(enabled no)
			(sheetname "")
		)
		(fill
			(thermal_gap 0.5)
			(thermal_bridge_width 0.5)
			(island_removal_mode 0)
		)
		(polygon
			(pts
				(xy 256.199894 -234.00004) (xy 256.199894 -259.999988) (xy 231.199944 -259.999988) (xy 231.199944 -234.00004)
			)
		)
	)
	(zone
		(layer "F.Cu")
		(hatch none 0.5)
		(connect_pads
			(clearance 0)
		)
		(min_thickness 0.25)
		(keepout
			(tracks allowed)
			(vias allowed)
			(pads allowed)
			(copperpour allowed)
			(footprints allowed)
		)
		(placement
			(enabled no)
			(sheetname "")
		)
		(fill
			(thermal_gap 0.5)
			(thermal_bridge_width 0.5)
			(island_removal_mode 0)
		)
		(polygon
			(pts
				(xy 424.636438 -134.202932) (xy 426.227748 -134.202932) (xy 426.227748 -136.11098) (xy 424.636438 -136.11098)
			)
		)
	)
	(zone
		(net "GND")
		(layer "F.Cu")
		(hatch none 0.5)
		(connect_pads
			(clearance 0.5)
		)
		(min_thickness 0.25)
		(fill yes
			(thermal_gap 0.5)
			(thermal_bridge_width 0.5)
			(island_removal_mode 0)
		)
		(polygon
			(pts
				(arc
					(start 161.70656 -207.481678)
					(mid 162.006251 -205.974942)
					(end 162.85972 -204.697584)
				)
				(xy 166.064692 -201.492866) (xy 166.064692 -195.306696) (xy 165.399212 -194.641216)
				(arc
					(start 163.812728 -194.641216)
					(mid 158.565789 -195.589082)
					(end 153.503122 -193.9163)
				)
				(xy 151.847296 -193.9163) (xy 151.123904 -194.639692) (xy 151.123904 -200.749408) (xy 154.732228 -204.357732)
				(arc
					(start 154.732228 -208.877916)
					(mid 154.931382 -209.973284)
					(end 154.831542 -211.082128)
				)
				(xy 155.32989 -211.580476) (xy 156.161994 -211.580476) (xy 156.161994 -215.339422) (xy 156.731716 -215.909144)
				(xy 160.44418 -215.909144)
				(arc
					(start 161.263838 -215.089486)
					(mid 161.262319 -215.025994)
					(end 161.261806 -214.962486)
				)
				(arc
					(start 161.261806 -214.606378)
					(mid 161.374603 -213.661751)
					(end 161.70656 -212.770212)
				)
				(arc
					(start 161.70656 -210.175348)
					(mid 161.503213 -208.893664)
					(end 161.70656 -207.61198)
				)
			)
		)
	)
	(zone
		(layer "F.Cu")
		(hatch none 0.5)
		(connect_pads
			(clearance 0)
		)
		(min_thickness 0.25)
		(keepout
			(tracks allowed)
			(vias allowed)
			(pads allowed)
			(copperpour allowed)
			(footprints allowed)
		)
		(placement
			(enabled no)
			(sheetname "")
		)
		(fill
			(thermal_gap 0.5)
			(thermal_bridge_width 0.5)
			(island_removal_mode 0)
		)
		(polygon
			(pts
				(xy 191.9732 -379.4125) (xy 191.9732 -378.4219) (xy 191.9732 -377.5075) (xy 193.1924 -377.5075)
				(xy 193.1924 -379.4125) (xy 192.7606 -379.4125)
			)
		)
	)
	(zone
		(net "P12V_HDD20")
		(layer "F.Cu")
		(hatch none 0.5)
		(connect_pads
			(clearance 0.5)
		)
		(min_thickness 0.25)
		(fill yes
			(thermal_gap 0.5)
			(thermal_bridge_width 0.5)
			(island_removal_mode 0)
		)
		(polygon
			(pts
				(xy 397.764 -149.606) (xy 397.51 -149.86) (xy 397.51 -153.924) (xy 396.9893 -154.4447) (xy 396.9893 -156.9593)
				(xy 395.8336 -158.115) (xy 389.382 -158.115) (xy 389.128 -158.369) (xy 389.128 -160.02) (xy 389.382 -160.274)
				(xy 393.319 -160.274) (xy 393.827 -159.766) (xy 401.574 -159.766) (xy 402.463 -158.877) (xy 402.463 -149.86)
				(xy 402.209 -149.606)
			)
		)
		(polygon
			(pts
				(xy 393.4714 -159.1564) (xy 393.2682 -159.1564) (xy 393.2682 -159.3596) (xy 393.4714 -159.3596)
			)
		)
		(polygon
			(pts
				(xy 392.6078 -159.1564) (xy 392.4046 -159.1564) (xy 392.4046 -159.3596) (xy 392.6078 -159.3596)
			)
		)
	)
	(zone
		(net "GND")
		(layer "F.Cu")
		(hatch none 0.5)
		(connect_pads
			(clearance 0.5)
		)
		(min_thickness 0.25)
		(fill yes
			(thermal_gap 0.5)
			(thermal_bridge_width 0.5)
			(island_removal_mode 0)
		)
		(polygon
			(pts
				(xy 455.88809 -220.83395) (xy 455.38009 -221.34195) (xy 455.38009 -226.429062) (xy 456.175872 -227.224844)
				(xy 458.636878 -227.224844) (xy 458.8256 -227.036122) (xy 458.8256 -221.01175) (xy 458.6478 -220.83395)
			)
		)
	)
	(zone
		(net "P5V_HDD28")
		(layer "F.Cu")
		(hatch none 0.5)
		(connect_pads
			(clearance 0.5)
		)
		(min_thickness 0.25)
		(fill yes
			(thermal_gap 0.5)
			(thermal_bridge_width 0.5)
			(island_removal_mode 0)
		)
		(polygon
			(pts
				(xy 145.923 -27.686) (xy 145.669 -27.94) (xy 145.669 -30.226) (xy 145.923 -30.48) (xy 145.923 -32.512)
				(xy 146.685 -33.274) (xy 146.685 -34.036) (xy 147.1168 -34.4678) (xy 147.4978 -34.4678) (xy 150.622 -37.592)
				(xy 157.48 -37.592) (xy 157.607 -37.465) (xy 157.607 -35.687) (xy 157.48 -35.56) (xy 152.4 -35.56)
				(xy 150.495 -33.655) (xy 149.606 -33.655) (xy 148.717 -32.766) (xy 148.717 -30.226) (xy 149.352 -29.591)
				(xy 149.352 -27.94) (xy 149.098 -27.686)
			)
		)
		(polygon
			(pts
				(xy 147.701 -34.1122) (xy 147.4978 -34.1122) (xy 147.4978 -34.3154) (xy 147.701 -34.3154)
			)
		)
		(polygon
			(pts
				(xy 147.701 -33.2486) (xy 147.4978 -33.2486) (xy 147.4978 -33.4518) (xy 147.701 -33.4518)
			)
		)
	)
	(zone
		(net "P5V_HDD15")
		(layer "F.Cu")
		(hatch none 0.5)
		(connect_pads
			(clearance 0.5)
		)
		(min_thickness 0.25)
		(fill yes
			(thermal_gap 0.5)
			(thermal_bridge_width 0.5)
			(island_removal_mode 0)
		)
		(polygon
			(pts
				(xy 114.3 -142.621) (xy 114.046 -142.875) (xy 114.046 -145.161) (xy 114.3 -145.415) (xy 114.3 -147.447)
				(xy 115.062 -148.209) (xy 115.062 -148.971) (xy 115.443 -149.352) (xy 115.824 -149.352) (xy 118.999 -152.527)
				(xy 125.857 -152.527) (xy 125.984 -152.4) (xy 125.984 -150.622) (xy 125.857 -150.495) (xy 120.777 -150.495)
				(xy 118.872 -148.59) (xy 117.983 -148.59) (xy 117.094 -147.701) (xy 117.094 -145.161) (xy 117.729 -144.526)
				(xy 117.729 -142.875) (xy 117.475 -142.621)
			)
		)
		(polygon
			(pts
				(xy 116.1542 -149.0472) (xy 115.951 -149.0472) (xy 115.951 -149.2504) (xy 116.1542 -149.2504)
			)
		)
		(polygon
			(pts
				(xy 116.1542 -148.1836) (xy 115.951 -148.1836) (xy 115.951 -148.3868) (xy 116.1542 -148.3868)
			)
		)
	)
	(zone
		(net "P12V_HDD6")
		(layer "F.Cu")
		(hatch none 0.5)
		(connect_pads
			(clearance 0.5)
		)
		(min_thickness 0.25)
		(fill yes
			(thermal_gap 0.5)
			(thermal_bridge_width 0.5)
			(island_removal_mode 0)
		)
		(polygon
			(pts
				(xy 334.645 -264.541) (xy 334.391 -264.795) (xy 334.391 -268.859) (xy 333.883 -269.367) (xy 333.883 -271.5514)
				(xy 332.3844 -273.05) (xy 326.263 -273.05) (xy 326.009 -273.304) (xy 326.009 -274.955) (xy 326.263 -275.209)
				(xy 330.2 -275.209) (xy 330.708 -274.701) (xy 338.455 -274.701) (xy 339.344 -273.812) (xy 339.344 -264.795)
				(xy 339.09 -264.541)
			)
		)
		(polygon
			(pts
				(xy 330.3524 -274.0914) (xy 330.1492 -274.0914) (xy 330.1492 -274.2946) (xy 330.3524 -274.2946)
			)
		)
		(polygon
			(pts
				(xy 329.4888 -274.0914) (xy 329.2856 -274.0914) (xy 329.2856 -274.2946) (xy 329.4888 -274.2946)
			)
		)
	)
	(zone
		(layer "F.Cu")
		(hatch none 0.5)
		(connect_pads
			(clearance 0)
		)
		(min_thickness 0.25)
		(keepout
			(tracks allowed)
			(vias allowed)
			(pads allowed)
			(copperpour allowed)
			(footprints not_allowed)
		)
		(placement
			(enabled no)
			(sheetname "")
		)
		(fill
			(thermal_gap 0.5)
			(thermal_bridge_width 0.5)
			(island_removal_mode 0)
		)
		(polygon
			(pts
				(xy 288.619946 -303.029874) (xy 280.999946 -303.029874) (xy 280.999946 -312.399934) (xy 288.619946 -312.399934)
			)
		)
	)
	(zone
		(net "GND")
		(layer "F.Cu")
		(hatch none 0.5)
		(connect_pads
			(clearance 0.5)
		)
		(min_thickness 0.25)
		(fill yes
			(thermal_gap 0.5)
			(thermal_bridge_width 0.5)
			(island_removal_mode 0)
		)
		(polygon
			(pts
				(xy 39.067994 -126.864364) (xy 38.35146 -127.580898) (xy 38.35146 -129.201418) (xy 38.351206 -129.201418)
				(arc
					(start 38.351206 -131.57835)
					(mid 37.879683 -133.478845)
					(end 36.574476 -134.938516)
				)
				(arc
					(start 36.574476 -135.40105)
					(mid 36.16463 -137.179956)
					(end 35.01771 -138.60018)
				)
				(xy 35.01771 -141.466062)
				(arc
					(start 35.64001 -142.088362)
					(mid 37.026561 -142.29093)
					(end 38.263322 -142.949676)
				)
				(xy 39.225728 -142.949676) (xy 39.812976 -142.362428) (xy 39.812976 -138.618976) (xy 40.091614 -138.618976)
				(arc
					(start 40.840152 -137.870438)
					(mid 40.770856 -136.498835)
					(end 41.15943 -135.181594)
				)
				(arc
					(start 41.15943 -135.181594)
					(mid 40.788899 -134.066352)
					(end 40.750744 -132.891784)
				)
				(arc
					(start 40.750744 -132.247894)
					(mid 41.024359 -130.78178)
					(end 41.8084 -129.513076)
				)
				(xy 41.8084 -127.311658) (xy 41.361106 -126.864364)
			)
		)
	)
	(zone
		(layer "F.Cu")
		(hatch none 0.5)
		(connect_pads
			(clearance 0)
		)
		(min_thickness 0.25)
		(keepout
			(tracks not_allowed)
			(vias allowed)
			(pads allowed)
			(copperpour not_allowed)
			(footprints allowed)
		)
		(placement
			(enabled no)
			(sheetname "")
		)
		(fill
			(thermal_gap 0.5)
			(thermal_bridge_width 0.5)
			(island_removal_mode 0)
		)
		(polygon
			(pts
				(arc
					(start 322.6816 -16.95196)
					(mid 322.19646 -17.4371)
					(end 322.6816 -17.92224)
				)
				(xy 323.09435 -17.92224)
				(arc
					(start 323.09435 -17.60855)
					(mid 323.066452 -17.541198)
					(end 322.9991 -17.5133)
				)
				(arc
					(start 322.937124 -17.5133)
					(mid 322.414956 -17.4371)
					(end 322.937124 -17.3609)
				)
				(xy 323.030596 -17.3609)
				(arc
					(start 323.032882 -17.363186)
					(mid 323.174235 -17.433415)
					(end 323.244464 -17.574768)
				)
				(xy 323.24675 -17.577054) (xy 323.24675 -17.92224) (xy 323.38645 -17.92224) (xy 323.38645 -17.577054)
				(arc
					(start 323.388736 -17.574768)
					(mid 323.458965 -17.433415)
					(end 323.600318 -17.363186)
				)
				(xy 323.602604 -17.3609)
				(arc
					(start 323.696076 -17.3609)
					(mid 324.218244 -17.4371)
					(end 323.696076 -17.5133)
				)
				(arc
					(start 323.6341 -17.5133)
					(mid 323.566748 -17.541198)
					(end 323.53885 -17.60855)
				)
				(xy 323.53885 -17.92224)
				(arc
					(start 323.951346 -17.92224)
					(mid 324.43674 -17.437227)
					(end 323.9516 -16.95196)
				)
			)
		)
	)
	(zone
		(net "P5V_B_2")
		(layer "F.Cu")
		(hatch none 0.5)
		(connect_pads
			(clearance 0.5)
		)
		(min_thickness 0.25)
		(fill yes
			(thermal_gap 0.5)
			(thermal_bridge_width 0.5)
			(island_removal_mode 0)
		)
		(polygon
			(pts
				(xy 113.03 -136.779) (xy 112.776 -137.033) (xy 112.776 -139.319) (xy 113.03 -139.573) (xy 117.729 -139.573)
				(xy 117.983 -139.319) (xy 117.983 -137.033) (xy 117.729 -136.779)
			)
		)
	)
	(zone
		(net "P12V_HDD17")
		(layer "F.Cu")
		(hatch none 0.5)
		(connect_pads
			(clearance 0.5)
		)
		(min_thickness 0.25)
		(fill yes
			(thermal_gap 0.5)
			(thermal_bridge_width 0.5)
			(island_removal_mode 0)
		)
		(polygon
			(pts
				(xy 170.053 -147.193) (xy 169.799 -147.447) (xy 169.799 -149.098) (xy 170.053 -149.352) (xy 172.212 -149.352)
				(xy 172.72 -149.86) (xy 172.72 -152.4) (xy 180.467 -160.147) (xy 188.976 -160.147) (xy 189.103 -160.02)
				(xy 189.103 -158.242) (xy 188.976 -158.115) (xy 183.007 -158.115) (xy 182.372 -157.48) (xy 180.721 -157.48)
				(xy 176.403 -153.162) (xy 176.403 -149.606) (xy 175.26 -148.463) (xy 175.26 -147.447) (xy 175.006 -147.193)
			)
		)
		(polygon
			(pts
				(xy 182.5244 -159.1564) (xy 182.3212 -159.1564) (xy 182.3212 -159.3596) (xy 182.5244 -159.3596)
			)
		)
		(polygon
			(pts
				(xy 181.6608 -159.1564) (xy 181.4576 -159.1564) (xy 181.4576 -159.3596) (xy 181.6608 -159.3596)
			)
		)
	)
	(zone
		(net "12V_PRE_9")
		(layer "F.Cu")
		(hatch none 0.5)
		(connect_pads
			(clearance 0.5)
		)
		(min_thickness 0.25)
		(fill yes
			(thermal_gap 0.5)
			(thermal_bridge_width 0.5)
			(island_removal_mode 0)
		)
		(polygon
			(pts
				(xy 425.6786 -269.686024) (xy 423.7482 -271.616424) (xy 420.751 -271.616424) (xy 420.497 -271.870424)
				(xy 420.497 -272.581624) (xy 420.6367 -272.721324) (xy 422.9227 -272.721324) (xy 422.9354 -272.734024)
				(xy 426.6184 -272.734024) (xy 427.6344 -271.718024) (xy 427.6344 -269.813024) (xy 427.5074 -269.686024)
			)
		)
	)
	(zone
		(net "P5V_HDD0")
		(layer "F.Cu")
		(hatch none 0.5)
		(connect_pads
			(clearance 0.5)
		)
		(min_thickness 0.25)
		(fill yes
			(thermal_gap 0.5)
			(thermal_bridge_width 0.5)
			(island_removal_mode 0)
		)
		(polygon
			(pts
				(xy 19.685 -257.683) (xy 19.431 -257.937) (xy 19.431 -260.223) (xy 19.685 -260.477) (xy 19.685 -262.509)
				(xy 20.447 -263.271) (xy 20.447 -264.033) (xy 20.828 -264.414) (xy 21.209 -264.414) (xy 24.384 -267.589)
				(xy 31.242 -267.589) (xy 31.369 -267.462) (xy 31.369 -265.684) (xy 31.242 -265.557) (xy 26.162 -265.557)
				(xy 24.257 -263.652) (xy 23.368 -263.652) (xy 22.479 -262.763) (xy 22.479 -260.223) (xy 23.114 -259.588)
				(xy 23.114 -257.937) (xy 22.86 -257.683)
			)
		)
		(polygon
			(pts
				(xy 21.3868 -264.0838) (xy 21.1836 -264.0838) (xy 21.1836 -264.287) (xy 21.3868 -264.287)
			)
		)
		(polygon
			(pts
				(xy 21.3868 -263.2202) (xy 21.1836 -263.2202) (xy 21.1836 -263.4234) (xy 21.3868 -263.4234)
			)
		)
	)
	(zone
		(layer "F.Cu")
		(hatch none 0.5)
		(connect_pads
			(clearance 0)
		)
		(min_thickness 0.25)
		(keepout
			(tracks allowed)
			(vias allowed)
			(pads allowed)
			(copperpour allowed)
			(footprints allowed)
		)
		(placement
			(enabled no)
			(sheetname "")
		)
		(fill
			(thermal_gap 0.5)
			(thermal_bridge_width 0.5)
			(island_removal_mode 0)
		)
		(polygon
			(pts
				(xy 18.841974 -224.926906) (xy 18.841974 -220.828616) (xy 20.092924 -220.828616) (xy 20.092924 -224.926906)
			)
		)
	)
	(zone
		(layer "F.Cu")
		(hatch none 0.5)
		(connect_pads
			(clearance 0)
		)
		(min_thickness 0.25)
		(keepout
			(tracks allowed)
			(vias allowed)
			(pads allowed)
			(copperpour allowed)
			(footprints allowed)
		)
		(placement
			(enabled no)
			(sheetname "")
		)
		(fill
			(thermal_gap 0.5)
			(thermal_bridge_width 0.5)
			(island_removal_mode 0)
		)
		(polygon
			(pts
				(xy 454.490074 -225.105468) (xy 454.490074 -221.007178) (xy 455.741024 -221.007178) (xy 455.741024 -225.105468)
			)
		)
	)
	(zone
		(net "P3V3_STBY_B")
		(layer "F.Cu")
		(hatch none 0.5)
		(connect_pads
			(clearance 0.5)
		)
		(min_thickness 0.25)
		(fill yes
			(thermal_gap 0.5)
			(thermal_bridge_width 0.5)
			(island_removal_mode 0)
		)
		(polygon
			(pts
				(xy 223.774 -246.888) (xy 222.758 -247.904) (xy 222.758 -270.256) (xy 234.078272 -281.576272) (xy 234.078272 -289.64509)
				(xy 237.148116 -292.714934) (xy 244.17147 -292.714934) (xy 248.611136 -297.1546) (xy 253.342394 -297.1546)
				(xy 256.9464 -300.758606) (xy 272.87474 -300.758606) (xy 274.630642 -302.514508) (xy 293.984426 -302.514508)
				(xy 294.372284 -302.12665) (xy 294.372284 -299.268388) (xy 294.147748 -299.043852) (xy 276.038818 -299.043852)
				(xy 274.76323 -297.768264) (xy 260.1722 -297.768264) (xy 255.113536 -292.7096) (xy 250.40209 -292.7096)
				(xy 247.702832 -290.010342) (xy 247.702832 -279.833832) (xy 229.743 -261.874) (xy 229.743 -248.158)
				(xy 228.473 -246.888)
			)
		)
	)
	(zone
		(net "12V_PRE_6")
		(layer "F.Cu")
		(hatch none 0.5)
		(connect_pads
			(clearance 0.5)
		)
		(min_thickness 0.25)
		(fill yes
			(thermal_gap 0.5)
			(thermal_bridge_width 0.5)
			(island_removal_mode 0)
		)
		(polygon
			(pts
				(xy 331.028548 -269.686024) (xy 329.098148 -271.616424) (xy 326.100948 -271.616424) (xy 325.846948 -271.870424)
				(xy 325.846948 -272.581624) (xy 325.986648 -272.721324) (xy 328.272648 -272.721324) (xy 328.285348 -272.734024)
				(xy 331.968348 -272.734024) (xy 332.984348 -271.718024) (xy 332.984348 -269.813024) (xy 332.857348 -269.686024)
			)
		)
	)
	(zone
		(net "P3V3_STBY_B")
		(layer "F.Cu")
		(hatch none 0.5)
		(connect_pads
			(clearance 0.5)
		)
		(min_thickness 0.25)
		(fill yes
			(thermal_gap 0.5)
			(thermal_bridge_width 0.5)
			(island_removal_mode 0)
		)
		(polygon
			(pts
				(xy 217.8431 -224.53092) (xy 217.724228 -224.649792) (xy 217.724228 -227.233988) (xy 217.7288 -227.23856)
				(xy 217.7288 -227.510848) (xy 218.059254 -227.841302) (xy 220.006672 -227.841302) (xy 220.55582 -227.292154)
				(xy 220.55582 -226.10826) (xy 220.68536 -225.97872) (xy 220.68536 -225.13544) (xy 220.61932 -225.0694)
				(xy 219.8116 -225.0694) (xy 219.27312 -224.53092)
			)
		)
		(polygon
			(pts
				(xy 219.8116 -226.8982) (xy 219.6084 -226.8982) (xy 219.6084 -227.1014) (xy 219.8116 -227.1014)
			)
		)
		(polygon
			(pts
				(xy 219.8116 -226.0346) (xy 219.6084 -226.0346) (xy 219.6084 -226.2378) (xy 219.8116 -226.2378)
			)
		)
		(polygon
			(pts
				(xy 220.1926 -225.6282) (xy 219.9894 -225.6282) (xy 219.9894 -225.8314) (xy 220.1926 -225.8314)
			)
		)
	)
	(zone
		(net "GND")
		(layer "F.Cu")
		(hatch none 0.5)
		(connect_pads
			(clearance 0.5)
		)
		(min_thickness 0.25)
		(fill yes
			(thermal_gap 0.5)
			(thermal_bridge_width 0.5)
			(island_removal_mode 0)
		)
		(polygon
			(pts
				(xy 41.340278 -270.3322) (xy 40.34536 -271.327118) (xy 40.34536 -280.768044) (xy 42.126916 -282.5496)
				(xy 50.750978 -282.5496) (xy 51.636676 -281.663902) (xy 51.636676 -277.878286) (xy 51.521614 -277.763224)
				(xy 50.988976 -277.763224) (xy 50.988976 -277.230586) (xy 44.09059 -270.3322)
			)
		)
	)
	(zone
		(layer "F.Cu")
		(hatch none 0.5)
		(connect_pads
			(clearance 0)
		)
		(min_thickness 0.25)
		(keepout
			(tracks allowed)
			(vias allowed)
			(pads allowed)
			(copperpour allowed)
			(footprints allowed)
		)
		(placement
			(enabled no)
			(sheetname "")
		)
		(fill
			(thermal_gap 0.5)
			(thermal_bridge_width 0.5)
			(island_removal_mode 0)
		)
		(polygon
			(pts
				(xy 329.84821 -134.234682) (xy 331.43952 -134.234682) (xy 331.43952 -136.14273) (xy 329.84821 -136.14273)
			)
		)
	)
	(zone
		(net "P12V_HDD33")
		(layer "F.Cu")
		(hatch none 0.5)
		(connect_pads
			(clearance 0.5)
		)
		(min_thickness 0.25)
		(fill yes
			(thermal_gap 0.5)
			(thermal_bridge_width 0.5)
			(island_removal_mode 0)
		)
		(polygon
			(pts
				(xy 429.26 -34.544) (xy 429.006 -34.798) (xy 429.006 -38.862) (xy 428.4726 -39.3954) (xy 428.4726 -41.656)
				(xy 427.0756 -43.053) (xy 420.878 -43.053) (xy 420.624 -43.307) (xy 420.624 -44.958) (xy 420.878 -45.212)
				(xy 424.815 -45.212) (xy 425.323 -44.704) (xy 433.07 -44.704) (xy 433.959 -43.815) (xy 433.959 -34.798)
				(xy 433.705 -34.544)
			)
		)
		(polygon
			(pts
				(xy 424.9674 -44.0944) (xy 424.7642 -44.0944) (xy 424.7642 -44.2976) (xy 424.9674 -44.2976)
			)
		)
		(polygon
			(pts
				(xy 424.1038 -44.0944) (xy 423.9006 -44.0944) (xy 423.9006 -44.2976) (xy 424.1038 -44.2976)
			)
		)
	)
	(zone
		(layer "F.Cu")
		(hatch none 0.5)
		(connect_pads
			(clearance 0)
		)
		(min_thickness 0.25)
		(keepout
			(tracks allowed)
			(vias allowed)
			(pads allowed)
			(copperpour allowed)
			(footprints allowed)
		)
		(placement
			(enabled no)
			(sheetname "")
		)
		(fill
			(thermal_gap 0.5)
			(thermal_bridge_width 0.5)
			(island_removal_mode 0)
		)
		(polygon
			(pts
				(xy 249.2248 -132.08) (xy 249.2248 -133.1468) (xy 247.5738 -133.1468) (xy 247.5738 -132.08)
			)
		)
	)
	(zone
		(net "P5V_HDD29")
		(layer "F.Cu")
		(hatch none 0.5)
		(connect_pads
			(clearance 0.5)
		)
		(min_thickness 0.25)
		(fill yes
			(thermal_gap 0.5)
			(thermal_bridge_width 0.5)
			(island_removal_mode 0)
		)
		(polygon
			(pts
				(xy 177.419 -27.686) (xy 177.165 -27.94) (xy 177.165 -30.226) (xy 177.419 -30.48) (xy 177.419 -32.512)
				(xy 178.181 -33.274) (xy 178.181 -34.199576) (xy 178.398424 -34.417) (xy 178.943 -34.417) (xy 182.118 -37.592)
				(xy 188.976 -37.592) (xy 189.103 -37.465) (xy 189.103 -35.687) (xy 188.976 -35.56) (xy 183.896 -35.56)
				(xy 181.991 -33.655) (xy 181.102 -33.655) (xy 180.213 -32.766) (xy 180.213 -30.226) (xy 180.848 -29.591)
				(xy 180.848 -27.94) (xy 180.594 -27.686)
			)
		)
		(polygon
			(pts
				(xy 179.2478 -34.1122) (xy 179.0446 -34.1122) (xy 179.0446 -34.3154) (xy 179.2478 -34.3154)
			)
		)
		(polygon
			(pts
				(xy 179.2478 -33.2486) (xy 179.0446 -33.2486) (xy 179.0446 -33.4518) (xy 179.2478 -33.4518)
			)
		)
	)
	(zone
		(net "GND")
		(layer "F.Cu")
		(hatch none 0.5)
		(connect_pads
			(clearance 0.5)
		)
		(min_thickness 0.25)
		(fill yes
			(thermal_gap 0.5)
			(thermal_bridge_width 0.5)
			(island_removal_mode 0)
		)
		(polygon
			(pts
				(xy 446.02654 -358.828848) (xy 445.903604 -358.951784) (xy 445.903604 -362.331) (xy 445.348868 -362.885736)
				(xy 445.348868 -364.519464) (xy 445.446404 -364.617) (xy 448.799204 -364.617) (xy 449.180204 -364.236)
				(xy 449.180204 -359.55859) (xy 448.450462 -358.828848)
			)
		)
		(polygon
			(pts
				(xy 445.966596 -363.857286) (xy 445.763396 -363.857286) (xy 445.763396 -364.060486) (xy 445.966596 -364.060486)
			)
		)
		(polygon
			(pts
				(xy 446.411604 -363.5502) (xy 446.208404 -363.5502) (xy 446.208404 -363.7534) (xy 446.411604 -363.7534)
			)
		)
		(polygon
			(pts
				(xy 446.411604 -362.6866) (xy 446.208404 -362.6866) (xy 446.208404 -362.8898) (xy 446.411604 -362.8898)
			)
		)
	)
	(zone
		(net "P12V_FAN1")
		(layer "F.Cu")
		(hatch none 0.5)
		(connect_pads
			(clearance 0.5)
		)
		(min_thickness 0.25)
		(fill yes
			(thermal_gap 0.5)
			(thermal_bridge_width 0.5)
			(island_removal_mode 0)
		)
		(polygon
			(pts
				(xy 127.191516 -358.76611) (xy 126.738634 -359.218992) (xy 126.738634 -361.726988) (xy 128.314196 -363.30255)
				(xy 133.527038 -363.30255) (xy 133.703568 -363.12602) (xy 134.669022 -363.12602) (xy 135.275828 -362.519214)
				(xy 138.365484 -362.519214) (xy 141.14907 -365.3028) (xy 148.8948 -365.3028) (xy 149.352 -365.76)
				(xy 149.352 -374.396) (xy 150.241 -375.285) (xy 153.67 -375.285) (xy 154.432 -374.523) (xy 154.432 -359.885234)
				(xy 153.312876 -358.76611)
			)
		)
		(polygon
			(pts
				(xy 133.555994 -362.593636) (xy 133.352794 -362.593636) (xy 133.352794 -362.796836) (xy 133.555994 -362.796836)
			)
		)
		(polygon
			(pts
				(xy 132.946394 -362.593636) (xy 132.743194 -362.593636) (xy 132.743194 -362.796836) (xy 132.946394 -362.796836)
			)
		)
		(polygon
			(pts
				(xy 134.730236 -362.160566) (xy 134.527036 -362.160566) (xy 134.527036 -362.363766) (xy 134.730236 -362.363766)
			)
		)
		(polygon
			(pts
				(xy 133.866636 -362.160566) (xy 133.663436 -362.160566) (xy 133.663436 -362.363766) (xy 133.866636 -362.363766)
			)
		)
	)
	(zone
		(net "P12V_HDD30")
		(layer "F.Cu")
		(hatch none 0.5)
		(connect_pads
			(clearance 0.5)
		)
		(min_thickness 0.25)
		(fill yes
			(thermal_gap 0.5)
			(thermal_bridge_width 0.5)
			(island_removal_mode 0)
		)
		(polygon
			(pts
				(xy 334.645 -34.417) (xy 334.391 -34.671) (xy 334.391 -38.862) (xy 333.8703 -39.3827) (xy 333.8703 -41.6941)
				(xy 332.5114 -43.053) (xy 326.263 -43.053) (xy 326.009 -43.307) (xy 326.009 -44.958) (xy 326.263 -45.212)
				(xy 330.2 -45.212) (xy 330.708 -44.704) (xy 336.296 -44.704) (xy 339.344 -41.656) (xy 339.344 -34.671)
				(xy 339.09 -34.417)
			)
		)
		(polygon
			(pts
				(xy 330.3524 -44.0944) (xy 330.1492 -44.0944) (xy 330.1492 -44.2976) (xy 330.3524 -44.2976)
			)
		)
		(polygon
			(pts
				(xy 329.4888 -44.0944) (xy 329.2856 -44.0944) (xy 329.2856 -44.2976) (xy 329.4888 -44.2976)
			)
		)
	)
	(zone
		(net "P12V_B")
		(layer "F.Cu")
		(hatch none 0.5)
		(connect_pads
			(clearance 0.5)
		)
		(min_thickness 0.25)
		(fill yes
			(thermal_gap 0.5)
			(thermal_bridge_width 0.5)
			(island_removal_mode 0)
		)
		(polygon
			(pts
				(xy 14.224 -255.143) (xy 13.208 -256.159) (xy 12.573 -256.159) (xy 12.192 -256.54) (xy 12.192 -259.08)
				(xy 12.446 -259.334) (xy 15.748 -259.334) (xy 16.002 -259.08) (xy 16.002 -256.794) (xy 15.367 -256.159)
				(xy 14.986 -256.159) (xy 14.732 -255.905) (xy 14.732 -255.27) (xy 14.605 -255.143)
			)
		)
		(polygon
			(pts
				(xy 14.1986 -255.7272) (xy 13.9954 -255.7272) (xy 13.9954 -255.9304) (xy 14.1986 -255.9304)
			)
		)
	)
	(zone
		(layer "F.Cu")
		(hatch none 0.5)
		(connect_pads
			(clearance 0)
		)
		(min_thickness 0.25)
		(keepout
			(tracks allowed)
			(vias allowed)
			(pads allowed)
			(copperpour allowed)
			(footprints allowed)
		)
		(placement
			(enabled no)
			(sheetname "")
		)
		(fill
			(thermal_gap 0.5)
			(thermal_bridge_width 0.5)
			(island_removal_mode 0)
		)
		(polygon
			(pts
				(xy 213.6902 -206.8068) (xy 213.6902 -207.8736) (xy 212.0392 -207.8736) (xy 212.0392 -206.8068)
			)
		)
	)
	(zone
		(layers "F.Cu" "B.Cu")
		(hatch none 0.5)
		(connect_pads
			(clearance 0)
		)
		(min_thickness 0.25)
		(keepout
			(tracks not_allowed)
			(vias allowed)
			(pads allowed)
			(copperpour not_allowed)
			(footprints allowed)
		)
		(placement
			(enabled no)
			(sheetname "")
		)
		(fill yes
			(thermal_gap 0.5)
			(thermal_bridge_width 0.5)
			(island_removal_mode 0)
		)
		(polygon
			(pts
				(arc
					(start 319.214754 -13.14196)
					(mid 318.72936 -13.626973)
					(end 319.2145 -14.11224)
				)
				(xy 319.56375 -14.11224)
				(arc
					(start 319.56375 -13.79855)
					(mid 319.536389 -13.731739)
					(end 319.470024 -13.7033)
				)
				(arc
					(start 319.470024 -13.7033)
					(mid 318.947856 -13.6271)
					(end 319.470024 -13.5509)
				)
				(xy 319.499996 -13.5509)
				(arc
					(start 319.502282 -13.553186)
					(mid 319.643635 -13.623415)
					(end 319.713864 -13.764768)
				)
				(xy 319.71615 -13.767054) (xy 319.71615 -14.11224) (xy 319.85585 -14.11224) (xy 319.85585 -13.767054)
				(arc
					(start 319.858136 -13.764768)
					(mid 319.928365 -13.623415)
					(end 320.069718 -13.553186)
				)
				(xy 320.072004 -13.5509)
				(arc
					(start 320.101976 -13.5509)
					(mid 320.624144 -13.6271)
					(end 320.101976 -13.7033)
				)
				(arc
					(start 320.101976 -13.7033)
					(mid 320.035603 -13.73173)
					(end 320.00825 -13.79855)
				)
				(xy 320.00825 -14.11224)
				(arc
					(start 320.3575 -14.11224)
					(mid 320.84264 -13.6271)
					(end 320.3575 -13.14196)
				)
			)
		)
	)
	(zone
		(layers "F.Cu" "B.Cu")
		(hatch none 0.5)
		(connect_pads
			(clearance 0)
		)
		(min_thickness 0.25)
		(keepout
			(tracks allowed)
			(vias allowed)
			(pads allowed)
			(copperpour allowed)
			(footprints not_allowed)
		)
		(placement
			(enabled no)
			(sheetname "")
		)
		(fill yes
			(thermal_gap 0.5)
			(thermal_bridge_width 0.5)
			(island_removal_mode 0)
		)
		(polygon
			(pts
				(arc
					(start 449.674996 -178.799998)
					(mid 456.674982 -171.800012)
					(end 463.674968 -178.799998)
				)
				(arc
					(start 463.674968 -184.799986)
					(mid 456.674982 -191.799972)
					(end 449.674996 -184.799986)
				)
			)
		)
	)
	(zone
		(layers "F.Cu" "B.Cu")
		(hatch none 0.5)
		(connect_pads
			(clearance 0)
		)
		(min_thickness 0.25)
		(keepout
			(tracks allowed)
			(vias allowed)
			(pads allowed)
			(copperpour allowed)
			(footprints not_allowed)
		)
		(placement
			(enabled no)
			(sheetname "")
		)
		(fill yes
			(thermal_gap 0.5)
			(thermal_bridge_width 0.5)
			(island_removal_mode 0)
		)
		(polygon
			(pts
				(arc
					(start 182.79999 -204.0001)
					(mid 189.799976 -197.000114)
					(end 196.799962 -204.0001)
				)
				(arc
					(start 196.799962 -210.000088)
					(mid 189.799976 -217.000074)
					(end 182.79999 -210.000088)
				)
			)
		)
	)
	(zone
		(layers "F.Cu" "B.Cu")
		(hatch none 0.5)
		(connect_pads
			(clearance 0)
		)
		(min_thickness 0.25)
		(keepout
			(tracks allowed)
			(vias allowed)
			(pads allowed)
			(copperpour allowed)
			(footprints not_allowed)
		)
		(placement
			(enabled no)
			(sheetname "")
		)
		(fill yes
			(thermal_gap 0.5)
			(thermal_bridge_width 0.5)
			(island_removal_mode 0)
		)
		(polygon
			(pts
				(arc
					(start 166.325042 -63.799974)
					(mid 159.325056 -56.799988)
					(end 152.32507 -63.799974)
				)
				(arc
					(start 152.32507 -69.799962)
					(mid 159.325056 -76.799948)
					(end 166.325042 -69.799962)
				)
			)
		)
	)
	(zone
		(layers "F.Cu" "B.Cu")
		(hatch none 0.5)
		(connect_pads
			(clearance 0)
		)
		(min_thickness 0.25)
		(keepout
			(tracks not_allowed)
			(vias allowed)
			(pads allowed)
			(copperpour not_allowed)
			(footprints allowed)
		)
		(placement
			(enabled no)
			(sheetname "")
		)
		(fill yes
			(thermal_gap 0.5)
			(thermal_bridge_width 0.5)
			(island_removal_mode 0)
		)
		(polygon
			(pts
				(arc
					(start 382.314704 -128.141984)
					(mid 381.82931 -128.626997)
					(end 382.31445 -129.112264)
				)
				(xy 382.6637 -129.112264)
				(arc
					(start 382.6637 -128.7907)
					(mid 382.638108 -128.728916)
					(end 382.576324 -128.703324)
				)
				(arc
					(start 382.569974 -128.703324)
					(mid 382.047806 -128.627124)
					(end 382.569974 -128.550924)
				)
				(xy 382.60782 -128.550924)
				(arc
					(start 382.61036 -128.553464)
					(mid 382.745793 -128.621231)
					(end 382.81356 -128.756664)
				)
				(xy 382.8161 -128.759204) (xy 382.8161 -129.112264) (xy 382.9558 -129.112264) (xy 382.9558 -128.759204)
				(arc
					(start 382.95834 -128.756664)
					(mid 383.026107 -128.621231)
					(end 383.16154 -128.553464)
				)
				(xy 383.16408 -128.550924)
				(arc
					(start 383.201926 -128.550924)
					(mid 383.724094 -128.627124)
					(end 383.201926 -128.703324)
				)
				(arc
					(start 383.195576 -128.703324)
					(mid 383.133792 -128.728916)
					(end 383.1082 -128.7907)
				)
				(xy 383.1082 -129.112264)
				(arc
					(start 383.45745 -129.112264)
					(mid 383.94259 -128.627124)
					(end 383.45745 -128.141984)
				)
			)
		)
	)
	(zone
		(layers "F.Cu" "B.Cu")
		(hatch none 0.5)
		(connect_pads
			(clearance 0)
		)
		(min_thickness 0.25)
		(keepout
			(tracks allowed)
			(vias allowed)
			(pads allowed)
			(copperpour allowed)
			(footprints not_allowed)
		)
		(placement
			(enabled no)
			(sheetname "")
		)
		(fill yes
			(thermal_gap 0.5)
			(thermal_bridge_width 0.5)
			(island_removal_mode 0)
		)
		(polygon
			(pts
				(arc
					(start 237.199932 -244.00002)
					(mid 244.199918 -237.000034)
					(end 251.199904 -244.00002)
				)
				(arc
					(start 251.199904 -250.000008)
					(mid 244.199918 -256.999994)
					(end 237.199932 -250.000008)
				)
			)
		)
	)
	(zone
		(layers "F.Cu" "B.Cu")
		(hatch none 0.5)
		(connect_pads
			(clearance 0)
		)
		(min_thickness 0.25)
		(keepout
			(tracks allowed)
			(vias allowed)
			(pads allowed)
			(copperpour allowed)
			(footprints not_allowed)
		)
		(placement
			(enabled no)
			(sheetname "")
		)
		(fill yes
			(thermal_gap 0.5)
			(thermal_bridge_width 0.5)
			(island_removal_mode 0)
		)
		(polygon
			(pts
				(arc
					(start 103.324914 -178.799998)
					(mid 96.324928 -171.800012)
					(end 89.324942 -178.799998)
				)
				(arc
					(start 89.324942 -184.799986)
					(mid 96.324928 -191.799972)
					(end 103.324914 -184.799986)
				)
			)
		)
	)
	(zone
		(layers "F.Cu" "B.Cu")
		(hatch none 0.5)
		(connect_pads
			(clearance 0)
		)
		(min_thickness 0.25)
		(keepout
			(tracks allowed)
			(vias allowed)
			(pads allowed)
			(copperpour allowed)
			(footprints not_allowed)
		)
		(placement
			(enabled no)
			(sheetname "")
		)
		(fill yes
			(thermal_gap 0.5)
			(thermal_bridge_width 0.5)
			(island_removal_mode 0)
		)
		(polygon
			(pts
				(arc
					(start 337.674966 -178.799998)
					(mid 330.67498 -171.800012)
					(end 323.674994 -178.799998)
				)
				(arc
					(start 323.674994 -184.799986)
					(mid 330.67498 -191.799972)
					(end 337.674966 -184.799986)
				)
			)
		)
	)
	(zone
		(layers "F.Cu" "B.Cu")
		(hatch none 0.5)
		(connect_pads
			(clearance 0)
		)
		(min_thickness 0.25)
		(keepout
			(tracks allowed)
			(vias allowed)
			(pads allowed)
			(copperpour allowed)
			(footprints not_allowed)
		)
		(placement
			(enabled no)
			(sheetname "")
		)
		(fill yes
			(thermal_gap 0.5)
			(thermal_bridge_width 0.5)
			(island_removal_mode 0)
		)
		(polygon
			(pts
				(arc
					(start 463.674968 -293.800022)
					(mid 456.674982 -286.800036)
					(end 449.674996 -293.800022)
				)
				(arc
					(start 449.674996 -299.80001)
					(mid 456.674982 -306.799996)
					(end 463.674968 -299.80001)
				)
			)
		)
	)
	(zone
		(layers "F.Cu" "B.Cu")
		(hatch none 0.5)
		(connect_pads
			(clearance 0)
		)
		(min_thickness 0.25)
		(keepout
			(tracks allowed)
			(vias allowed)
			(pads allowed)
			(copperpour allowed)
			(footprints not_allowed)
		)
		(placement
			(enabled no)
			(sheetname "")
		)
		(fill yes
			(thermal_gap 0.5)
			(thermal_bridge_width 0.5)
			(island_removal_mode 0)
		)
		(polygon
			(pts
				(arc
					(start 337.674966 -293.800022)
					(mid 330.67498 -286.800036)
					(end 323.674994 -293.800022)
				)
				(arc
					(start 323.674994 -299.80001)
					(mid 330.67498 -306.799996)
					(end 337.674966 -299.80001)
				)
			)
		)
	)
	(zone
		(layers "F.Cu" "B.Cu")
		(hatch none 0.5)
		(connect_pads
			(clearance 0)
		)
		(min_thickness 0.25)
		(keepout
			(tracks allowed)
			(vias allowed)
			(pads allowed)
			(copperpour allowed)
			(footprints not_allowed)
		)
		(placement
			(enabled no)
			(sheetname "")
		)
		(fill yes
			(thermal_gap 0.5)
			(thermal_bridge_width 0.5)
			(island_removal_mode 0)
		)
		(polygon
			(pts
				(arc
					(start 26.325068 -63.799974)
					(mid 33.325054 -56.799988)
					(end 40.32504 -63.799974)
				)
				(arc
					(start 40.32504 -69.799962)
					(mid 33.325054 -76.799948)
					(end 26.325068 -69.799962)
				)
			)
		)
	)
	(zone
		(layers "F.Cu" "B.Cu")
		(hatch none 0.5)
		(connect_pads
			(clearance 0)
		)
		(min_thickness 0.25)
		(keepout
			(tracks allowed)
			(vias allowed)
			(pads allowed)
			(copperpour allowed)
			(footprints not_allowed)
		)
		(placement
			(enabled no)
			(sheetname "")
		)
		(fill yes
			(thermal_gap 0.5)
			(thermal_bridge_width 0.5)
			(island_removal_mode 0)
		)
		(polygon
			(pts
				(arc
					(start 40.32504 -178.799998)
					(mid 33.325054 -171.800012)
					(end 26.325068 -178.799998)
				)
				(arc
					(start 26.325068 -184.799986)
					(mid 33.325054 -191.799972)
					(end 40.32504 -184.799986)
				)
			)
		)
	)
	(zone
		(net "MB0_CM_GATE_R")
		(layers "F.Cu" "B.Cu")
		(hatch none 0.5)
		(connect_pads
			(clearance 0.5)
		)
		(min_thickness 0.25)
		(fill yes
			(thermal_gap 0.5)
			(thermal_bridge_width 0.5)
			(island_removal_mode 0)
		)
		(polygon
			(pts
				(xy 207.264 -337.693) (xy 207.01 -337.947) (xy 207.01 -339.217) (xy 207.264 -339.471) (xy 209.042 -339.471)
				(xy 209.296 -339.217) (xy 209.296 -337.947) (xy 209.042 -337.693)
			)
		)
	)
	(zone
		(layers "F.Cu" "B.Cu")
		(hatch none 0.5)
		(connect_pads
			(clearance 0)
		)
		(min_thickness 0.25)
		(keepout
			(tracks allowed)
			(vias allowed)
			(pads allowed)
			(copperpour allowed)
			(footprints not_allowed)
		)
		(placement
			(enabled no)
			(sheetname "")
		)
		(fill yes
			(thermal_gap 0.5)
			(thermal_bridge_width 0.5)
			(island_removal_mode 0)
		)
		(polygon
			(pts
				(arc
					(start 293.200074 -244.00002)
					(mid 300.20006 -237.000034)
					(end 307.200046 -244.00002)
				)
				(arc
					(start 307.200046 -250.000008)
					(mid 300.20006 -256.999994)
					(end 293.200074 -250.000008)
				)
			)
		)
	)
	(zone
		(layers "F.Cu" "B.Cu")
		(hatch none 0.5)
		(connect_pads
			(clearance 0)
		)
		(min_thickness 0.25)
		(keepout
			(tracks allowed)
			(vias allowed)
			(pads allowed)
			(copperpour allowed)
			(footprints not_allowed)
		)
		(placement
			(enabled no)
			(sheetname "")
		)
		(fill yes
			(thermal_gap 0.5)
			(thermal_bridge_width 0.5)
			(island_removal_mode 0)
		)
		(polygon
			(pts
				(arc
					(start 337.674966 -63.799974)
					(mid 330.67498 -56.799988)
					(end 323.674994 -63.799974)
				)
				(arc
					(start 323.674994 -69.799962)
					(mid 330.67498 -76.799948)
					(end 337.674966 -69.799962)
				)
			)
		)
	)
	(zone
		(layers "F.Cu" "B.Cu")
		(hatch none 0.5)
		(connect_pads
			(clearance 0)
		)
		(min_thickness 0.25)
		(keepout
			(tracks allowed)
			(vias allowed)
			(pads allowed)
			(copperpour allowed)
			(footprints not_allowed)
		)
		(placement
			(enabled no)
			(sheetname "")
		)
		(fill yes
			(thermal_gap 0.5)
			(thermal_bridge_width 0.5)
			(island_removal_mode 0)
		)
		(polygon
			(pts
				(arc
					(start 89.324942 -63.799974)
					(mid 96.324928 -56.799988)
					(end 103.324914 -63.799974)
				)
				(arc
					(start 103.324914 -69.799962)
					(mid 96.324928 -76.799948)
					(end 89.324942 -69.799962)
				)
			)
		)
	)
	(zone
		(layers "F.Cu" "B.Cu")
		(hatch none 0.5)
		(connect_pads
			(clearance 0)
		)
		(min_thickness 0.25)
		(keepout
			(tracks allowed)
			(vias allowed)
			(pads allowed)
			(copperpour allowed)
			(footprints not_allowed)
		)
		(placement
			(enabled no)
			(sheetname "")
		)
		(fill yes
			(thermal_gap 0.5)
			(thermal_bridge_width 0.5)
			(island_removal_mode 0)
		)
		(polygon
			(pts
				(arc
					(start 152.32507 -63.799974)
					(mid 159.325056 -56.799988)
					(end 166.325042 -63.799974)
				)
				(arc
					(start 166.325042 -69.799962)
					(mid 159.325056 -76.799948)
					(end 152.32507 -69.799962)
				)
			)
		)
	)
	(zone
		(layers "F.Cu" "B.Cu")
		(hatch none 0.5)
		(connect_pads
			(clearance 0)
		)
		(min_thickness 0.25)
		(keepout
			(tracks allowed)
			(vias allowed)
			(pads allowed)
			(copperpour allowed)
			(footprints not_allowed)
		)
		(placement
			(enabled no)
			(sheetname "")
		)
		(fill yes
			(thermal_gap 0.5)
			(thermal_bridge_width 0.5)
			(island_removal_mode 0)
		)
		(polygon
			(pts
				(arc
					(start 166.325042 -293.800022)
					(mid 159.325056 -286.800036)
					(end 152.32507 -293.800022)
				)
				(arc
					(start 152.32507 -299.80001)
					(mid 159.325056 -306.799996)
					(end 166.325042 -299.80001)
				)
			)
		)
	)
	(zone
		(layers "F.Cu" "B.Cu")
		(hatch none 0.5)
		(connect_pads
			(clearance 0)
		)
		(min_thickness 0.25)
		(keepout
			(tracks allowed)
			(vias allowed)
			(pads allowed)
			(copperpour allowed)
			(footprints not_allowed)
		)
		(placement
			(enabled no)
			(sheetname "")
		)
		(fill yes
			(thermal_gap 0.5)
			(thermal_bridge_width 0.5)
			(island_removal_mode 0)
		)
		(polygon
			(pts
				(arc
					(start 166.325042 -178.799998)
					(mid 159.325056 -171.800012)
					(end 152.32507 -178.799998)
				)
				(arc
					(start 152.32507 -184.799986)
					(mid 159.325056 -191.799972)
					(end 166.325042 -184.799986)
				)
			)
		)
	)
	(zone
		(layers "F.Cu" "B.Cu")
		(hatch none 0.5)
		(connect_pads
			(clearance 0)
		)
		(min_thickness 0.25)
		(keepout
			(tracks allowed)
			(vias allowed)
			(pads allowed)
			(copperpour allowed)
			(footprints not_allowed)
		)
		(placement
			(enabled no)
			(sheetname "")
		)
		(fill yes
			(thermal_gap 0.5)
			(thermal_bridge_width 0.5)
			(island_removal_mode 0)
		)
		(polygon
			(pts
				(arc
					(start 103.324914 -293.800022)
					(mid 96.324928 -286.800036)
					(end 89.324942 -293.800022)
				)
				(arc
					(start 89.324942 -299.80001)
					(mid 96.324928 -306.799996)
					(end 103.324914 -299.80001)
				)
			)
		)
	)
	(zone
		(layers "F.Cu" "B.Cu")
		(hatch none 0.5)
		(connect_pads
			(clearance 0)
		)
		(min_thickness 0.25)
		(keepout
			(tracks not_allowed)
			(vias allowed)
			(pads allowed)
			(copperpour not_allowed)
			(footprints allowed)
		)
		(placement
			(enabled no)
			(sheetname "")
		)
		(fill yes
			(thermal_gap 0.5)
			(thermal_bridge_width 0.5)
			(island_removal_mode 0)
		)
		(polygon
			(pts
				(arc
					(start 445.414654 -128.141984)
					(mid 444.92926 -128.626997)
					(end 445.4144 -129.112264)
				)
				(xy 445.76365 -129.112264)
				(arc
					(start 445.76365 -128.79705)
					(mid 445.736198 -128.730776)
					(end 445.669924 -128.703324)
				)
				(arc
					(start 445.669924 -128.703324)
					(mid 445.147756 -128.627124)
					(end 445.669924 -128.550924)
				)
				(xy 445.70142 -128.550924)
				(arc
					(start 445.70396 -128.55321)
					(mid 445.844016 -128.622958)
					(end 445.913764 -128.763014)
				)
				(xy 445.91605 -128.765554) (xy 445.91605 -129.112264) (xy 446.05575 -129.112264) (xy 446.05575 -128.765554)
				(arc
					(start 446.058036 -128.763014)
					(mid 446.127784 -128.622958)
					(end 446.26784 -128.55321)
				)
				(xy 446.27038 -128.550924)
				(arc
					(start 446.301876 -128.550924)
					(mid 446.824044 -128.627124)
					(end 446.301876 -128.703324)
				)
				(arc
					(start 446.301876 -128.703324)
					(mid 446.235602 -128.730776)
					(end 446.20815 -128.79705)
				)
				(xy 446.20815 -129.112264)
				(arc
					(start 446.5574 -129.112264)
					(mid 447.04254 -128.627124)
					(end 446.5574 -128.141984)
				)
			)
		)
	)
	(zone
		(layers "F.Cu" "B.Cu")
		(hatch none 0.5)
		(connect_pads
			(clearance 0)
		)
		(min_thickness 0.25)
		(keepout
			(tracks allowed)
			(vias allowed)
			(pads allowed)
			(copperpour allowed)
			(footprints not_allowed)
		)
		(placement
			(enabled no)
			(sheetname "")
		)
		(fill yes
			(thermal_gap 0.5)
			(thermal_bridge_width 0.5)
			(island_removal_mode 0)
		)
		(polygon
			(pts
				(arc
					(start 103.324914 -63.799974)
					(mid 96.324928 -56.799988)
					(end 89.324942 -63.799974)
				)
				(arc
					(start 89.324942 -69.799962)
					(mid 96.324928 -76.799948)
					(end 103.324914 -69.799962)
				)
			)
		)
	)
	(zone
		(layers "F.Cu" "B.Cu")
		(hatch none 0.5)
		(connect_pads
			(clearance 0)
		)
		(min_thickness 0.25)
		(keepout
			(tracks allowed)
			(vias allowed)
			(pads allowed)
			(copperpour allowed)
			(footprints not_allowed)
		)
		(placement
			(enabled no)
			(sheetname "")
		)
		(fill yes
			(thermal_gap 0.5)
			(thermal_bridge_width 0.5)
			(island_removal_mode 0)
		)
		(polygon
			(pts
				(arc
					(start 26.325068 -293.800022)
					(mid 33.325054 -286.800036)
					(end 40.32504 -293.800022)
				)
				(arc
					(start 40.32504 -299.80001)
					(mid 33.325054 -306.799996)
					(end 26.325068 -299.80001)
				)
			)
		)
	)
	(zone
		(layers "F.Cu" "B.Cu")
		(hatch none 0.5)
		(connect_pads
			(clearance 0)
		)
		(min_thickness 0.25)
		(keepout
			(tracks not_allowed)
			(vias allowed)
			(pads allowed)
			(copperpour not_allowed)
			(footprints allowed)
		)
		(placement
			(enabled no)
			(sheetname "")
		)
		(fill yes
			(thermal_gap 0.5)
			(thermal_bridge_width 0.5)
			(island_removal_mode 0)
		)
		(polygon
			(pts
				(arc
					(start 382.314704 -13.14196)
					(mid 381.82931 -13.626973)
					(end 382.31445 -14.11224)
				)
				(xy 382.6637 -14.11224)
				(arc
					(start 382.6637 -13.7795)
					(mid 382.641382 -13.725618)
					(end 382.5875 -13.7033)
				)
				(arc
					(start 382.569974 -13.7033)
					(mid 382.047806 -13.6271)
					(end 382.569974 -13.5509)
				)
				(xy 382.618996 -13.5509)
				(arc
					(start 382.621536 -13.55344)
					(mid 382.74915 -13.61785)
					(end 382.81356 -13.745464)
				)
				(xy 382.8161 -13.748004) (xy 382.8161 -14.11224) (xy 382.9558 -14.11224) (xy 382.9558 -13.748004)
				(arc
					(start 382.95834 -13.745464)
					(mid 383.02275 -13.61785)
					(end 383.150364 -13.55344)
				)
				(xy 383.152904 -13.5509)
				(arc
					(start 383.201926 -13.5509)
					(mid 383.724094 -13.6271)
					(end 383.201926 -13.7033)
				)
				(arc
					(start 383.1844 -13.7033)
					(mid 383.130518 -13.725618)
					(end 383.1082 -13.7795)
				)
				(xy 383.1082 -14.11224)
				(arc
					(start 383.45745 -14.11224)
					(mid 383.94259 -13.6271)
					(end 383.45745 -13.14196)
				)
			)
		)
	)
	(zone
		(layers "F.Cu" "B.Cu")
		(hatch none 0.5)
		(connect_pads
			(clearance 0)
		)
		(min_thickness 0.25)
		(keepout
			(tracks allowed)
			(vias allowed)
			(pads allowed)
			(copperpour allowed)
			(footprints not_allowed)
		)
		(placement
			(enabled no)
			(sheetname "")
		)
		(fill yes
			(thermal_gap 0.5)
			(thermal_bridge_width 0.5)
			(island_removal_mode 0)
		)
		(polygon
			(pts
				(arc
					(start 152.32507 -293.800022)
					(mid 159.325056 -286.800036)
					(end 166.325042 -293.800022)
				)
				(arc
					(start 166.325042 -299.80001)
					(mid 159.325056 -306.799996)
					(end 152.32507 -299.80001)
				)
			)
		)
	)
	(zone
		(layers "F.Cu" "B.Cu")
		(hatch none 0.5)
		(connect_pads
			(clearance 0)
		)
		(min_thickness 0.25)
		(keepout
			(tracks allowed)
			(vias allowed)
			(pads allowed)
			(copperpour allowed)
			(footprints not_allowed)
		)
		(placement
			(enabled no)
			(sheetname "")
		)
		(fill yes
			(thermal_gap 0.5)
			(thermal_bridge_width 0.5)
			(island_removal_mode 0)
		)
		(polygon
			(pts
				(arc
					(start 400.675094 -293.800022)
					(mid 393.675108 -286.800036)
					(end 386.675122 -293.800022)
				)
				(arc
					(start 386.675122 -299.80001)
					(mid 393.675108 -306.799996)
					(end 400.675094 -299.80001)
				)
			)
		)
	)
	(zone
		(layers "F.Cu" "B.Cu")
		(hatch none 0.5)
		(connect_pads
			(clearance 0)
		)
		(min_thickness 0.25)
		(keepout
			(tracks not_allowed)
			(vias allowed)
			(pads allowed)
			(copperpour not_allowed)
			(footprints allowed)
		)
		(placement
			(enabled no)
			(sheetname "")
		)
		(fill yes
			(thermal_gap 0.5)
			(thermal_bridge_width 0.5)
			(island_removal_mode 0)
		)
		(polygon
			(pts
				(arc
					(start 413.864806 -13.14196)
					(mid 413.379412 -13.626973)
					(end 413.864552 -14.11224)
				)
				(xy 414.213802 -14.11224)
				(arc
					(start 414.213802 -13.782802)
					(mid 414.190516 -13.726586)
					(end 414.1343 -13.7033)
				)
				(arc
					(start 414.120076 -13.7033)
					(mid 413.597908 -13.6271)
					(end 414.120076 -13.5509)
				)
				(xy 414.165796 -13.5509)
				(arc
					(start 414.168336 -13.55344)
					(mid 414.298259 -13.618843)
					(end 414.363662 -13.748766)
				)
				(xy 414.366202 -13.751306) (xy 414.366202 -14.11224) (xy 414.505902 -14.11224) (xy 414.505902 -13.751306)
				(arc
					(start 414.508442 -13.748766)
					(mid 414.573845 -13.618843)
					(end 414.703768 -13.55344)
				)
				(xy 414.706308 -13.5509)
				(arc
					(start 414.752028 -13.5509)
					(mid 415.274196 -13.6271)
					(end 414.752028 -13.7033)
				)
				(arc
					(start 414.737804 -13.7033)
					(mid 414.681588 -13.726586)
					(end 414.658302 -13.782802)
				)
				(xy 414.658302 -14.11224)
				(arc
					(start 415.007552 -14.11224)
					(mid 415.492692 -13.6271)
					(end 415.007552 -13.14196)
				)
			)
		)
	)
	(zone
		(layers "F.Cu" "B.Cu")
		(hatch none 0.5)
		(connect_pads
			(clearance 0)
		)
		(min_thickness 0.25)
		(keepout
			(tracks not_allowed)
			(vias allowed)
			(pads allowed)
			(copperpour not_allowed)
			(footprints allowed)
		)
		(placement
			(enabled no)
			(sheetname "")
		)
		(fill yes
			(thermal_gap 0.5)
			(thermal_bridge_width 0.5)
			(island_removal_mode 0)
		)
		(polygon
			(pts
				(xy 244.779546 -65.055242) (xy 244.779546 -63.73622) (xy 267.393928 -63.73622) (xy 267.393928 -65.055242)
			)
		)
	)
	(zone
		(layers "F.Cu" "B.Cu")
		(hatch none 0.5)
		(connect_pads
			(clearance 0)
		)
		(min_thickness 0.25)
		(keepout
			(tracks allowed)
			(vias allowed)
			(pads allowed)
			(copperpour allowed)
			(footprints not_allowed)
		)
		(placement
			(enabled no)
			(sheetname "")
		)
		(fill yes
			(thermal_gap 0.5)
			(thermal_bridge_width 0.5)
			(island_removal_mode 0)
		)
		(polygon
			(pts
				(arc
					(start 26.325068 -178.799998)
					(mid 33.325054 -171.800012)
					(end 40.32504 -178.799998)
				)
				(arc
					(start 40.32504 -184.799986)
					(mid 33.325054 -191.799972)
					(end 26.325068 -184.799986)
				)
			)
		)
	)
	(zone
		(layers "F.Cu" "B.Cu")
		(hatch none 0.5)
		(connect_pads
			(clearance 0)
		)
		(min_thickness 0.25)
		(keepout
			(tracks allowed)
			(vias allowed)
			(pads allowed)
			(copperpour allowed)
			(footprints not_allowed)
		)
		(placement
			(enabled no)
			(sheetname "")
		)
		(fill yes
			(thermal_gap 0.5)
			(thermal_bridge_width 0.5)
			(island_removal_mode 0)
		)
		(polygon
			(pts
				(arc
					(start 89.324942 -293.800022)
					(mid 96.324928 -286.800036)
					(end 103.324914 -293.800022)
				)
				(arc
					(start 103.324914 -299.80001)
					(mid 96.324928 -306.799996)
					(end 89.324942 -299.80001)
				)
			)
		)
	)
	(zone
		(layers "F.Cu" "B.Cu")
		(hatch none 0.5)
		(connect_pads
			(clearance 0)
		)
		(min_thickness 0.25)
		(keepout
			(tracks allowed)
			(vias allowed)
			(pads allowed)
			(copperpour allowed)
			(footprints not_allowed)
		)
		(placement
			(enabled no)
			(sheetname "")
		)
		(fill yes
			(thermal_gap 0.5)
			(thermal_bridge_width 0.5)
			(island_removal_mode 0)
		)
		(polygon
			(pts
				(arc
					(start 237.199932 -175.800004)
					(mid 244.199918 -168.800018)
					(end 251.199904 -175.800004)
				)
				(arc
					(start 251.199904 -181.799992)
					(mid 244.199918 -188.799978)
					(end 237.199932 -181.799992)
				)
			)
		)
	)
	(zone
		(layers "F.Cu" "B.Cu")
		(hatch none 0.5)
		(connect_pads
			(clearance 0)
		)
		(min_thickness 0.25)
		(keepout
			(tracks allowed)
			(vias allowed)
			(pads allowed)
			(copperpour allowed)
			(footprints not_allowed)
		)
		(placement
			(enabled no)
			(sheetname "")
		)
		(fill yes
			(thermal_gap 0.5)
			(thermal_bridge_width 0.5)
			(island_removal_mode 0)
		)
		(polygon
			(pts
				(arc
					(start 323.674994 -178.799998)
					(mid 330.67498 -171.800012)
					(end 337.674966 -178.799998)
				)
				(arc
					(start 337.674966 -184.799986)
					(mid 330.67498 -191.799972)
					(end 323.674994 -184.799986)
				)
			)
		)
	)
	(zone
		(layers "F.Cu" "B.Cu")
		(hatch none 0.5)
		(connect_pads
			(clearance 0)
		)
		(min_thickness 0.25)
		(keepout
			(tracks allowed)
			(vias allowed)
			(pads allowed)
			(copperpour allowed)
			(footprints not_allowed)
		)
		(placement
			(enabled no)
			(sheetname "")
		)
		(fill yes
			(thermal_gap 0.5)
			(thermal_bridge_width 0.5)
			(island_removal_mode 0)
		)
		(polygon
			(pts
				(arc
					(start 400.675094 -63.799974)
					(mid 393.675108 -56.799988)
					(end 386.675122 -63.799974)
				)
				(arc
					(start 386.675122 -69.799962)
					(mid 393.675108 -76.799948)
					(end 400.675094 -69.799962)
				)
			)
		)
	)
	(zone
		(layers "F.Cu" "B.Cu")
		(hatch none 0.5)
		(connect_pads
			(clearance 0)
		)
		(min_thickness 0.25)
		(keepout
			(tracks not_allowed)
			(vias allowed)
			(pads allowed)
			(copperpour not_allowed)
			(footprints allowed)
		)
		(placement
			(enabled no)
			(sheetname "")
		)
		(fill yes
			(thermal_gap 0.5)
			(thermal_bridge_width 0.5)
			(island_removal_mode 0)
		)
		(polygon
			(pts
				(arc
					(start 319.214754 -128.141984)
					(mid 318.72936 -128.626997)
					(end 319.2145 -129.112264)
				)
				(xy 319.56375 -129.112264)
				(arc
					(start 319.56375 -128.78435)
					(mid 319.540018 -128.727056)
					(end 319.482724 -128.703324)
				)
				(arc
					(start 319.470024 -128.703324)
					(mid 318.947856 -128.627124)
					(end 319.470024 -128.550924)
				)
				(xy 319.51422 -128.550924)
				(arc
					(start 319.51676 -128.553464)
					(mid 319.647749 -128.619325)
					(end 319.71361 -128.750314)
				)
				(xy 319.71615 -128.752854) (xy 319.71615 -129.112264) (xy 319.85585 -129.112264) (xy 319.85585 -128.752854)
				(arc
					(start 319.85839 -128.750314)
					(mid 319.924251 -128.619325)
					(end 320.05524 -128.553464)
				)
				(xy 320.05778 -128.550924)
				(arc
					(start 320.101976 -128.550924)
					(mid 320.624144 -128.627124)
					(end 320.101976 -128.703324)
				)
				(arc
					(start 320.089276 -128.703324)
					(mid 320.031982 -128.727056)
					(end 320.00825 -128.78435)
				)
				(xy 320.00825 -129.112264)
				(arc
					(start 320.3575 -129.112264)
					(mid 320.84264 -128.627124)
					(end 320.3575 -128.141984)
				)
			)
		)
	)
	(zone
		(layers "F.Cu" "B.Cu")
		(hatch none 0.5)
		(connect_pads
			(clearance 0)
		)
		(min_thickness 0.25)
		(keepout
			(tracks allowed)
			(vias allowed)
			(pads allowed)
			(copperpour allowed)
			(footprints not_allowed)
		)
		(placement
			(enabled no)
			(sheetname "")
		)
		(fill yes
			(thermal_gap 0.5)
			(thermal_bridge_width 0.5)
			(island_removal_mode 0)
		)
		(polygon
			(pts
				(arc
					(start 463.674968 -63.799974)
					(mid 456.674982 -56.799988)
					(end 449.674996 -63.799974)
				)
				(arc
					(start 449.674996 -69.799962)
					(mid 456.674982 -76.799948)
					(end 463.674968 -69.799962)
				)
			)
		)
	)
	(zone
		(layers "F.Cu" "B.Cu")
		(hatch none 0.5)
		(connect_pads
			(clearance 0)
		)
		(min_thickness 0.25)
		(keepout
			(tracks not_allowed)
			(vias allowed)
			(pads allowed)
			(copperpour not_allowed)
			(footprints allowed)
		)
		(placement
			(enabled no)
			(sheetname "")
		)
		(fill yes
			(thermal_gap 0.5)
			(thermal_bridge_width 0.5)
			(island_removal_mode 0)
		)
		(polygon
			(pts
				(arc
					(start 445.414654 -13.14196)
					(mid 444.92926 -13.626973)
					(end 445.4144 -14.11224)
				)
				(xy 445.76365 -14.11224)
				(arc
					(start 445.76365 -13.78585)
					(mid 445.739472 -13.727478)
					(end 445.6811 -13.7033)
				)
				(arc
					(start 445.669924 -13.7033)
					(mid 445.147756 -13.6271)
					(end 445.669924 -13.5509)
				)
				(xy 445.712596 -13.5509)
				(arc
					(start 445.715136 -13.55344)
					(mid 445.847192 -13.619758)
					(end 445.91351 -13.751814)
				)
				(xy 445.91605 -13.754354) (xy 445.91605 -14.11224) (xy 446.05575 -14.11224) (xy 446.05575 -13.754354)
				(arc
					(start 446.05829 -13.751814)
					(mid 446.124608 -13.619758)
					(end 446.256664 -13.55344)
				)
				(xy 446.259204 -13.5509)
				(arc
					(start 446.301876 -13.5509)
					(mid 446.824044 -13.6271)
					(end 446.301876 -13.7033)
				)
				(arc
					(start 446.2907 -13.7033)
					(mid 446.232328 -13.727478)
					(end 446.20815 -13.78585)
				)
				(xy 446.20815 -14.11224)
				(arc
					(start 446.5574 -14.11224)
					(mid 447.04254 -13.6271)
					(end 446.5574 -13.14196)
				)
			)
		)
	)
	(zone
		(layers "F.Cu" "B.Cu")
		(hatch none 0.5)
		(connect_pads
			(clearance 0)
		)
		(min_thickness 0.25)
		(keepout
			(tracks allowed)
			(vias allowed)
			(pads allowed)
			(copperpour allowed)
			(footprints not_allowed)
		)
		(placement
			(enabled no)
			(sheetname "")
		)
		(fill yes
			(thermal_gap 0.5)
			(thermal_bridge_width 0.5)
			(island_removal_mode 0)
		)
		(polygon
			(pts
				(arc
					(start 40.32504 -293.800022)
					(mid 33.325054 -286.800036)
					(end 26.325068 -293.800022)
				)
				(arc
					(start 26.325068 -299.80001)
					(mid 33.325054 -306.799996)
					(end 40.32504 -299.80001)
				)
			)
		)
	)
	(zone
		(layers "F.Cu" "B.Cu")
		(hatch none 0.5)
		(connect_pads
			(clearance 0)
		)
		(min_thickness 0.25)
		(keepout
			(tracks allowed)
			(vias allowed)
			(pads allowed)
			(copperpour allowed)
			(footprints not_allowed)
		)
		(placement
			(enabled no)
			(sheetname "")
		)
		(fill yes
			(thermal_gap 0.5)
			(thermal_bridge_width 0.5)
			(island_removal_mode 0)
		)
		(polygon
			(pts
				(arc
					(start 386.675122 -178.799998)
					(mid 393.675108 -171.800012)
					(end 400.675094 -178.799998)
				)
				(arc
					(start 400.675094 -184.799986)
					(mid 393.675108 -191.799972)
					(end 386.675122 -184.799986)
				)
			)
		)
	)
	(zone
		(layers "F.Cu" "B.Cu")
		(hatch none 0.5)
		(connect_pads
			(clearance 0)
		)
		(min_thickness 0.25)
		(keepout
			(tracks not_allowed)
			(vias allowed)
			(pads allowed)
			(copperpour not_allowed)
			(footprints allowed)
		)
		(placement
			(enabled no)
			(sheetname "")
		)
		(fill yes
			(thermal_gap 0.5)
			(thermal_bridge_width 0.5)
			(island_removal_mode 0)
		)
		(polygon
			(pts
				(arc
					(start 413.864806 -128.141984)
					(mid 413.379412 -128.626997)
					(end 413.864552 -129.112264)
				)
				(xy 414.213802 -129.112264)
				(arc
					(start 414.213802 -128.768602)
					(mid 414.194683 -128.722443)
					(end 414.148524 -128.703324)
				)
				(arc
					(start 414.120076 -128.703324)
					(mid 413.597908 -128.627124)
					(end 414.120076 -128.550924)
				)
				(xy 414.18002 -128.550924)
				(arc
					(start 414.182814 -128.553718)
					(mid 414.302392 -128.614734)
					(end 414.363408 -128.734312)
				)
				(xy 414.366202 -128.737106) (xy 414.366202 -129.112264) (xy 414.505902 -129.112264) (xy 414.505902 -128.737106)
				(arc
					(start 414.508696 -128.734312)
					(mid 414.569712 -128.614734)
					(end 414.68929 -128.553718)
				)
				(xy 414.692084 -128.550924)
				(arc
					(start 414.752028 -128.550924)
					(mid 415.274196 -128.627124)
					(end 414.752028 -128.703324)
				)
				(arc
					(start 414.72358 -128.703324)
					(mid 414.677421 -128.722443)
					(end 414.658302 -128.768602)
				)
				(xy 414.658302 -129.112264)
				(arc
					(start 415.007552 -129.112264)
					(mid 415.492692 -128.627124)
					(end 415.007552 -128.141984)
				)
			)
		)
	)
	(zone
		(layers "F.Cu" "B.Cu")
		(hatch none 0.5)
		(connect_pads
			(clearance 0)
		)
		(min_thickness 0.25)
		(keepout
			(tracks allowed)
			(vias allowed)
			(pads allowed)
			(copperpour allowed)
			(footprints not_allowed)
		)
		(placement
			(enabled no)
			(sheetname "")
		)
		(fill yes
			(thermal_gap 0.5)
			(thermal_bridge_width 0.5)
			(island_removal_mode 0)
		)
		(polygon
			(pts
				(arc
					(start 323.674994 -63.799974)
					(mid 330.67498 -56.799988)
					(end 337.674966 -63.799974)
				)
				(arc
					(start 337.674966 -69.799962)
					(mid 330.67498 -76.799948)
					(end 323.674994 -69.799962)
				)
			)
		)
	)
	(zone
		(layers "F.Cu" "B.Cu")
		(hatch none 0.5)
		(connect_pads
			(clearance 0)
		)
		(min_thickness 0.25)
		(keepout
			(tracks not_allowed)
			(vias allowed)
			(pads allowed)
			(copperpour not_allowed)
			(footprints allowed)
		)
		(placement
			(enabled no)
			(sheetname "")
		)
		(fill yes
			(thermal_gap 0.5)
			(thermal_bridge_width 0.5)
			(island_removal_mode 0)
		)
		(polygon
			(pts
				(arc
					(start 350.764856 -128.141984)
					(mid 350.279462 -128.626997)
					(end 350.764602 -129.112264)
				)
				(xy 351.113852 -129.112264)
				(arc
					(start 351.113852 -128.787652)
					(mid 351.089153 -128.728023)
					(end 351.029524 -128.703324)
				)
				(arc
					(start 351.020126 -128.703324)
					(mid 350.497958 -128.627124)
					(end 351.020126 -128.550924)
				)
				(xy 351.06102 -128.550924)
				(arc
					(start 351.06356 -128.553464)
					(mid 351.19686 -128.620316)
					(end 351.263712 -128.753616)
				)
				(xy 351.266252 -128.756156) (xy 351.266252 -129.112264) (xy 351.405952 -129.112264) (xy 351.405952 -128.756156)
				(arc
					(start 351.408492 -128.753616)
					(mid 351.475344 -128.620316)
					(end 351.608644 -128.553464)
				)
				(xy 351.611184 -128.550924)
				(arc
					(start 351.652078 -128.550924)
					(mid 352.174246 -128.627124)
					(end 351.652078 -128.703324)
				)
				(arc
					(start 351.64268 -128.703324)
					(mid 351.583051 -128.728023)
					(end 351.558352 -128.787652)
				)
				(xy 351.558352 -129.112264)
				(arc
					(start 351.907602 -129.112264)
					(mid 352.392742 -128.627124)
					(end 351.907602 -128.141984)
				)
			)
		)
	)
	(zone
		(layers "F.Cu" "B.Cu")
		(hatch none 0.5)
		(connect_pads
			(clearance 0)
		)
		(min_thickness 0.25)
		(keepout
			(tracks allowed)
			(vias allowed)
			(pads allowed)
			(copperpour allowed)
			(footprints not_allowed)
		)
		(placement
			(enabled no)
			(sheetname "")
		)
		(fill yes
			(thermal_gap 0.5)
			(thermal_bridge_width 0.5)
			(island_removal_mode 0)
		)
		(polygon
			(pts
				(arc
					(start 463.674968 -178.799998)
					(mid 456.674982 -171.800012)
					(end 449.674996 -178.799998)
				)
				(arc
					(start 449.674996 -184.799986)
					(mid 456.674982 -191.799972)
					(end 463.674968 -184.799986)
				)
			)
		)
	)
	(zone
		(layers "F.Cu" "B.Cu")
		(hatch none 0.5)
		(connect_pads
			(clearance 0)
		)
		(min_thickness 0.25)
		(keepout
			(tracks allowed)
			(vias allowed)
			(pads allowed)
			(copperpour allowed)
			(footprints not_allowed)
		)
		(placement
			(enabled no)
			(sheetname "")
		)
		(fill yes
			(thermal_gap 0.5)
			(thermal_bridge_width 0.5)
			(island_removal_mode 0)
		)
		(polygon
			(pts
				(arc
					(start 40.32504 -63.799974)
					(mid 33.325054 -56.799988)
					(end 26.325068 -63.799974)
				)
				(arc
					(start 26.325068 -69.799962)
					(mid 33.325054 -76.799948)
					(end 40.32504 -69.799962)
				)
			)
		)
	)
	(zone
		(layers "F.Cu" "B.Cu")
		(hatch none 0.5)
		(connect_pads
			(clearance 0)
		)
		(min_thickness 0.25)
		(keepout
			(tracks allowed)
			(vias allowed)
			(pads allowed)
			(copperpour allowed)
			(footprints not_allowed)
		)
		(placement
			(enabled no)
			(sheetname "")
		)
		(fill yes
			(thermal_gap 0.5)
			(thermal_bridge_width 0.5)
			(island_removal_mode 0)
		)
		(polygon
			(pts
				(arc
					(start 293.200074 -94.000066)
					(mid 300.20006 -87.00008)
					(end 307.200046 -94.000066)
				)
				(arc
					(start 307.200046 -100.000054)
					(mid 300.20006 -107.00004)
					(end 293.200074 -100.000054)
				)
			)
		)
	)
	(zone
		(layers "F.Cu" "B.Cu")
		(hatch none 0.5)
		(connect_pads
			(clearance 0)
		)
		(min_thickness 0.25)
		(keepout
			(tracks allowed)
			(vias allowed)
			(pads allowed)
			(copperpour allowed)
			(footprints not_allowed)
		)
		(placement
			(enabled no)
			(sheetname "")
		)
		(fill yes
			(thermal_gap 0.5)
			(thermal_bridge_width 0.5)
			(island_removal_mode 0)
		)
		(polygon
			(pts
				(arc
					(start 400.675094 -178.799998)
					(mid 393.675108 -171.800012)
					(end 386.675122 -178.799998)
				)
				(arc
					(start 386.675122 -184.799986)
					(mid 393.675108 -191.799972)
					(end 400.675094 -184.799986)
				)
			)
		)
	)
	(zone
		(layers "F.Cu" "B.Cu")
		(hatch none 0.5)
		(connect_pads
			(clearance 0)
		)
		(min_thickness 0.25)
		(keepout
			(tracks allowed)
			(vias allowed)
			(pads allowed)
			(copperpour allowed)
			(footprints not_allowed)
		)
		(placement
			(enabled no)
			(sheetname "")
		)
		(fill yes
			(thermal_gap 0.5)
			(thermal_bridge_width 0.5)
			(island_removal_mode 0)
		)
		(polygon
			(pts
				(arc
					(start 182.79999 -94.000066)
					(mid 189.799976 -87.00008)
					(end 196.799962 -94.000066)
				)
				(arc
					(start 196.799962 -100.000054)
					(mid 189.799976 -107.00004)
					(end 182.79999 -100.000054)
				)
			)
		)
	)
	(zone
		(net "MB0_CM_GATE_R")
		(layers "F.Cu" "B.Cu")
		(hatch none 0.5)
		(connect_pads
			(clearance 0.5)
		)
		(min_thickness 0.25)
		(fill yes
			(thermal_gap 0.5)
			(thermal_bridge_width 0.5)
			(island_removal_mode 0)
		)
		(polygon
			(pts
				(xy 207.264 -347.472) (xy 207.01 -347.726) (xy 207.01 -348.996) (xy 207.264 -349.25) (xy 209.042 -349.25)
				(xy 209.296 -348.996) (xy 209.296 -347.726) (xy 209.042 -347.472)
			)
		)
	)
	(zone
		(layers "F.Cu" "B.Cu" "In1.Cu" "In2.Cu" "In3.Cu" "In4.Cu" "In5.Cu" "In6.Cu")
		(hatch none 0.5)
		(connect_pads
			(clearance 0)
		)
		(min_thickness 0.25)
		(keepout
			(tracks not_allowed)
			(vias allowed)
			(pads allowed)
			(copperpour not_allowed)
			(footprints allowed)
		)
		(placement
			(enabled no)
			(sheetname "")
		)
		(fill yes
			(thermal_gap 0.5)
			(thermal_bridge_width 0.5)
			(island_removal_mode 0)
		)
		(polygon
			(pts
				(arc
					(start 89.324942 -178.799998)
					(mid 96.324928 -171.800012)
					(end 103.324914 -178.799998)
				)
				(arc
					(start 103.324914 -184.799986)
					(mid 96.324928 -191.799972)
					(end 89.324942 -184.799986)
				)
			)
		)
	)
	(zone
		(layers "F.Cu" "B.Cu" "In1.Cu" "In2.Cu" "In3.Cu" "In4.Cu" "In5.Cu" "In6.Cu")
		(hatch none 0.5)
		(connect_pads
			(clearance 0)
		)
		(min_thickness 0.25)
		(keepout
			(tracks not_allowed)
			(vias allowed)
			(pads allowed)
			(copperpour not_allowed)
			(footprints allowed)
		)
		(placement
			(enabled no)
			(sheetname "")
		)
		(fill yes
			(thermal_gap 0.5)
			(thermal_bridge_width 0.5)
			(island_removal_mode 0)
		)
		(polygon
			(pts
				(arc
					(start 26.325068 -178.799998)
					(mid 33.325054 -171.800012)
					(end 40.32504 -178.799998)
				)
				(arc
					(start 40.32504 -184.799986)
					(mid 33.325054 -191.799972)
					(end 26.325068 -184.799986)
				)
			)
		)
	)
	(zone
		(layers "F.Cu" "B.Cu" "In1.Cu" "In2.Cu" "In3.Cu" "In4.Cu" "In5.Cu" "In6.Cu")
		(hatch none 0.5)
		(connect_pads
			(clearance 0)
		)
		(min_thickness 0.25)
		(keepout
			(tracks not_allowed)
			(vias allowed)
			(pads allowed)
			(copperpour not_allowed)
			(footprints allowed)
		)
		(placement
			(enabled no)
			(sheetname "")
		)
		(fill
			(thermal_gap 0.5)
			(thermal_bridge_width 0.5)
			(island_removal_mode 0)
		)
		(polygon
			(pts
				(arc
					(start 48.749966 -13.999972)
					(mid 39.249858 -13.999972)
					(end 48.749966 -13.999972)
				)
			)
		)
	)
	(zone
		(layers "F.Cu" "B.Cu" "In1.Cu" "In2.Cu" "In3.Cu" "In4.Cu" "In5.Cu" "In6.Cu")
		(hatch none 0.5)
		(connect_pads
			(clearance 0)
		)
		(min_thickness 0.25)
		(keepout
			(tracks not_allowed)
			(vias allowed)
			(pads allowed)
			(copperpour not_allowed)
			(footprints allowed)
		)
		(placement
			(enabled no)
			(sheetname "")
		)
		(fill
			(thermal_gap 0.5)
			(thermal_bridge_width 0.5)
			(island_removal_mode 0)
		)
		(polygon
			(pts
				(arc
					(start 432.286918 -66.799968)
					(mid 418.062918 -66.799968)
					(end 432.286918 -66.799968)
				)
			)
		)
	)
	(zone
		(layers "F.Cu" "B.Cu" "In1.Cu" "In2.Cu" "In3.Cu" "In4.Cu" "In5.Cu" "In6.Cu")
		(hatch none 0.5)
		(connect_pads
			(clearance 0)
		)
		(min_thickness 0.25)
		(keepout
			(tracks not_allowed)
			(vias allowed)
			(pads allowed)
			(copperpour not_allowed)
			(footprints allowed)
		)
		(placement
			(enabled no)
			(sheetname "")
		)
		(fill yes
			(thermal_gap 0.5)
			(thermal_bridge_width 0.5)
			(island_removal_mode 0)
		)
		(polygon
			(pts
				(arc
					(start 323.674994 -63.799974)
					(mid 330.67498 -56.799988)
					(end 337.674966 -63.799974)
				)
				(arc
					(start 337.674966 -69.799962)
					(mid 330.67498 -76.799948)
					(end 323.674994 -69.799962)
				)
			)
		)
	)
	(zone
		(layers "F.Cu" "B.Cu" "In1.Cu" "In2.Cu" "In3.Cu" "In4.Cu" "In5.Cu" "In6.Cu")
		(hatch none 0.5)
		(connect_pads
			(clearance 0)
		)
		(min_thickness 0.25)
		(keepout
			(tracks not_allowed)
			(vias allowed)
			(pads allowed)
			(copperpour not_allowed)
			(footprints allowed)
		)
		(placement
			(enabled no)
			(sheetname "")
		)
		(fill yes
			(thermal_gap 0.5)
			(thermal_bridge_width 0.5)
			(island_removal_mode 0)
		)
		(polygon
			(pts
				(arc
					(start 386.675122 -293.800022)
					(mid 393.675108 -286.800036)
					(end 400.675094 -293.800022)
				)
				(arc
					(start 400.675094 -299.80001)
					(mid 393.675108 -306.799996)
					(end 386.675122 -299.80001)
				)
			)
		)
	)
	(zone
		(layers "F.Cu" "B.Cu" "In1.Cu" "In2.Cu" "In3.Cu" "In4.Cu" "In5.Cu" "In6.Cu")
		(hatch none 0.5)
		(connect_pads
			(clearance 0)
		)
		(min_thickness 0.25)
		(keepout
			(tracks not_allowed)
			(vias allowed)
			(pads allowed)
			(copperpour not_allowed)
			(footprints allowed)
		)
		(placement
			(enabled no)
			(sheetname "")
		)
		(fill
			(thermal_gap 0.5)
			(thermal_bridge_width 0.5)
			(island_removal_mode 0)
		)
		(polygon
			(pts
				(arc
					(start 129.919984 -331.399896)
					(mid 125.919992 -335.399888)
					(end 129.919984 -339.39988)
				)
				(arc
					(start 134.999984 -339.39988)
					(mid 138.999976 -335.399888)
					(end 134.999984 -331.399896)
				)
			)
		)
	)
	(zone
		(layers "F.Cu" "B.Cu" "In1.Cu" "In2.Cu" "In3.Cu" "In4.Cu" "In5.Cu" "In6.Cu")
		(hatch none 0.5)
		(connect_pads
			(clearance 0)
		)
		(min_thickness 0.25)
		(keepout
			(tracks not_allowed)
			(vias allowed)
			(pads allowed)
			(copperpour not_allowed)
			(footprints allowed)
		)
		(placement
			(enabled no)
			(sheetname "")
		)
		(fill
			(thermal_gap 0.5)
			(thermal_bridge_width 0.5)
			(island_removal_mode 0)
		)
		(polygon
			(pts
				(arc
					(start 409.149804 -24.025606)
					(mid 399.649696 -24.025606)
					(end 409.149804 -24.025606)
				)
			)
		)
	)
	(zone
		(layers "F.Cu" "B.Cu" "In1.Cu" "In2.Cu" "In3.Cu" "In4.Cu" "In5.Cu" "In6.Cu")
		(hatch none 0.5)
		(connect_pads
			(clearance 0)
		)
		(min_thickness 0.25)
		(keepout
			(tracks not_allowed)
			(vias allowed)
			(pads allowed)
			(copperpour not_allowed)
			(footprints allowed)
		)
		(placement
			(enabled no)
			(sheetname "")
		)
		(fill
			(thermal_gap 0.5)
			(thermal_bridge_width 0.5)
			(island_removal_mode 0)
		)
		(polygon
			(pts
				(arc
					(start 284.299914 -295.213532)
					(mid 276.799802 -295.213532)
					(end 284.299914 -295.213532)
				)
			)
		)
	)
	(zone
		(layers "F.Cu" "B.Cu" "In1.Cu" "In2.Cu" "In3.Cu" "In4.Cu" "In5.Cu" "In6.Cu")
		(hatch none 0.5)
		(connect_pads
			(clearance 0)
		)
		(min_thickness 0.25)
		(keepout
			(tracks not_allowed)
			(vias allowed)
			(pads allowed)
			(copperpour not_allowed)
			(footprints allowed)
		)
		(placement
			(enabled no)
			(sheetname "")
		)
		(fill
			(thermal_gap 0.5)
			(thermal_bridge_width 0.5)
			(island_removal_mode 0)
		)
		(polygon
			(pts
				(arc
					(start 111.849916 -23.999952)
					(mid 102.349808 -23.999952)
					(end 111.849916 -23.999952)
				)
			)
		)
	)
	(zone
		(layers "F.Cu" "B.Cu" "In1.Cu" "In2.Cu" "In3.Cu" "In4.Cu" "In5.Cu" "In6.Cu")
		(hatch none 0.5)
		(connect_pads
			(clearance 0)
		)
		(min_thickness 0.25)
		(keepout
			(tracks not_allowed)
			(vias allowed)
			(pads allowed)
			(copperpour not_allowed)
			(footprints allowed)
		)
		(placement
			(enabled no)
			(sheetname "")
		)
		(fill
			(thermal_gap 0.5)
			(thermal_bridge_width 0.5)
			(island_removal_mode 0)
		)
		(polygon
			(pts
				(arc
					(start 439.17489 -66.799714)
					(mid 411.174946 -66.799714)
					(end 439.17489 -66.799714)
				)
			)
		)
	)
	(zone
		(layers "F.Cu" "B.Cu" "In1.Cu" "In2.Cu" "In3.Cu" "In4.Cu" "In5.Cu" "In6.Cu")
		(hatch none 0.5)
		(connect_pads
			(clearance 0)
		)
		(min_thickness 0.25)
		(keepout
			(tracks not_allowed)
			(vias allowed)
			(pads allowed)
			(copperpour not_allowed)
			(footprints allowed)
		)
		(placement
			(enabled no)
			(sheetname "")
		)
		(fill
			(thermal_gap 0.5)
			(thermal_bridge_width 0.5)
			(island_removal_mode 0)
		)
		(polygon
			(pts
				(arc
					(start 174.95012 -13.999972)
					(mid 165.450012 -13.999972)
					(end 174.95012 -13.999972)
				)
			)
		)
	)
	(zone
		(layers "F.Cu" "B.Cu" "In1.Cu" "In2.Cu" "In3.Cu" "In4.Cu" "In5.Cu" "In6.Cu")
		(hatch none 0.5)
		(connect_pads
			(clearance 0)
		)
		(min_thickness 0.25)
		(keepout
			(tracks not_allowed)
			(vias allowed)
			(pads allowed)
			(copperpour not_allowed)
			(footprints allowed)
		)
		(placement
			(enabled no)
			(sheetname "")
		)
		(fill yes
			(thermal_gap 0.5)
			(thermal_bridge_width 0.5)
			(island_removal_mode 0)
		)
		(polygon
			(pts
				(arc
					(start 89.324942 -63.799974)
					(mid 96.324928 -56.799988)
					(end 103.324914 -63.799974)
				)
				(arc
					(start 103.324914 -69.799962)
					(mid 96.324928 -76.799948)
					(end 89.324942 -69.799962)
				)
			)
		)
	)
	(zone
		(layers "F.Cu" "B.Cu" "In1.Cu" "In2.Cu" "In3.Cu" "In4.Cu" "In5.Cu" "In6.Cu")
		(hatch none 0.5)
		(connect_pads
			(clearance 0)
		)
		(min_thickness 0.25)
		(keepout
			(tracks not_allowed)
			(vias allowed)
			(pads allowed)
			(copperpour not_allowed)
			(footprints allowed)
		)
		(placement
			(enabled no)
			(sheetname "")
		)
		(fill yes
			(thermal_gap 0.5)
			(thermal_bridge_width 0.5)
			(island_removal_mode 0)
		)
		(polygon
			(pts
				(arc
					(start 449.674996 -293.800022)
					(mid 456.674982 -286.800036)
					(end 463.674968 -293.800022)
				)
				(arc
					(start 463.674968 -299.80001)
					(mid 456.674982 -306.799996)
					(end 449.674996 -299.80001)
				)
			)
		)
	)
	(zone
		(layers "F.Cu" "B.Cu" "In1.Cu" "In2.Cu" "In3.Cu" "In4.Cu" "In5.Cu" "In6.Cu")
		(hatch none 0.5)
		(connect_pads
			(clearance 0)
		)
		(min_thickness 0.25)
		(keepout
			(tracks not_allowed)
			(vias allowed)
			(pads allowed)
			(copperpour not_allowed)
			(footprints allowed)
		)
		(placement
			(enabled no)
			(sheetname "")
		)
		(fill yes
			(thermal_gap 0.5)
			(thermal_bridge_width 0.5)
			(island_removal_mode 0)
		)
		(polygon
			(pts
				(arc
					(start 26.325068 -63.799974)
					(mid 33.325054 -56.799988)
					(end 40.32504 -63.799974)
				)
				(arc
					(start 40.32504 -69.799962)
					(mid 33.325054 -76.799948)
					(end 26.325068 -69.799962)
				)
			)
		)
	)
	(zone
		(layers "F.Cu" "B.Cu" "In1.Cu" "In2.Cu" "In3.Cu" "In4.Cu" "In5.Cu" "In6.Cu")
		(hatch none 0.5)
		(connect_pads
			(clearance 0)
		)
		(min_thickness 0.25)
		(keepout
			(tracks not_allowed)
			(vias allowed)
			(pads allowed)
			(copperpour not_allowed)
			(footprints allowed)
		)
		(placement
			(enabled no)
			(sheetname "")
		)
		(fill yes
			(thermal_gap 0.5)
			(thermal_bridge_width 0.5)
			(island_removal_mode 0)
		)
		(polygon
			(pts
				(arc
					(start 323.674994 -178.799998)
					(mid 330.67498 -171.800012)
					(end 337.674966 -178.799998)
				)
				(arc
					(start 337.674966 -184.799986)
					(mid 330.67498 -191.799972)
					(end 323.674994 -184.799986)
				)
			)
		)
	)
	(zone
		(layers "F.Cu" "B.Cu" "In1.Cu" "In2.Cu" "In3.Cu" "In4.Cu" "In5.Cu" "In6.Cu")
		(hatch none 0.5)
		(connect_pads
			(clearance 0)
		)
		(min_thickness 0.25)
		(keepout
			(tracks not_allowed)
			(vias allowed)
			(pads allowed)
			(copperpour not_allowed)
			(footprints allowed)
		)
		(placement
			(enabled no)
			(sheetname "")
		)
		(fill
			(thermal_gap 0.5)
			(thermal_bridge_width 0.5)
			(island_removal_mode 0)
		)
		(polygon
			(pts
				(arc
					(start 62.61989 -331.399896)
					(mid 58.619898 -335.399888)
					(end 62.61989 -339.39988)
				)
				(arc
					(start 67.69989 -339.39988)
					(mid 71.699882 -335.399888)
					(end 67.69989 -331.399896)
				)
			)
		)
	)
	(zone
		(layers "F.Cu" "B.Cu" "In1.Cu" "In2.Cu" "In3.Cu" "In4.Cu" "In5.Cu" "In6.Cu")
		(name "Package Keepin")
		(hatch none 0.5)
		(connect_pads
			(clearance 0)
		)
		(min_thickness 0.25)
		(keepout
			(tracks allowed)
			(vias allowed)
			(pads allowed)
			(copperpour allowed)
			(footprints allowed)
		)
		(placement
			(enabled no)
			(sheetname "")
		)
		(fill
			(thermal_gap 0.5)
			(thermal_bridge_width 0.5)
			(island_removal_mode 0)
		)
		(polygon
			(pts
				(arc
					(start 275.75002 -354.996242)
					(mid 279.995346 -356.754714)
					(end 281.753818 -361.00004)
				)
				(xy 281.753818 -380.927356) (xy 281.822652 -380.99619)
				(arc
					(start 303.105566 -380.99619)
					(mid 305.317076 -378.306051)
					(end 308.649878 -377.296172)
				)
				(arc
					(start 315.149992 -377.296172)
					(mid 318.482738 -378.306134)
					(end 320.694304 -380.99619)
				)
				(arc
					(start 358.69626 -380.99619)
					(mid 360.456078 -376.753326)
					(end 364.700058 -374.996202)
				)
				(arc
					(start 416.699954 -374.996202)
					(mid 420.943933 -376.753327)
					(end 422.703752 -380.99619)
				)
				(arc
					(start 460.705708 -380.99619)
					(mid 462.917218 -378.306051)
					(end 466.25002 -377.296172)
				)
				(arc
					(start 472.74988 -377.296172)
					(mid 476.082626 -378.306134)
					(end 478.294192 -380.99619)
				)
				(xy 483.446074 -380.99619)
				(arc
					(start 483.446074 -372.000018)
					(mid 484.250034 -368.99906)
					(end 486.446322 -366.801654)
				)
				(xy 486.446322 -5.0038) (xy 316.003686 -5.0038)
				(arc
					(start 316.003686 -47.200058)
					(mid 314.245214 -51.445384)
					(end 309.999888 -53.203856)
				)
				(xy 274.00377 -53.203856)
				(arc
					(start 274.00377 -62.00013)
					(mid 272.245298 -66.245202)
					(end 268.000226 -68.003674)
				)
				(arc
					(start 207.999838 -68.003674)
					(mid 203.754766 -66.245202)
					(end 201.996294 -62.00013)
				)
				(xy 201.996294 -53.203856)
				(arc
					(start 200.000108 -53.203856)
					(mid 195.754782 -51.445384)
					(end 193.99631 -47.200058)
				)
				(xy 193.99631 -5.0038) (xy 5.0038 -5.0038)
				(arc
					(start 5.0038 -366.801654)
					(mid 7.200002 -368.999057)
					(end 8.003794 -372.000018)
				)
				(xy 8.003794 -380.99619)
				(arc
					(start 11.70559 -380.99619)
					(mid 13.9171 -378.306051)
					(end 17.249902 -377.296172)
				)
				(arc
					(start 23.750016 -377.296172)
					(mid 27.082762 -378.306134)
					(end 29.294328 -380.99619)
				)
				(arc
					(start 67.296284 -380.99619)
					(mid 69.056102 -376.753326)
					(end 73.300082 -374.996202)
				)
				(arc
					(start 125.299978 -374.996202)
					(mid 129.543957 -376.753327)
					(end 131.303776 -380.99619)
				)
				(arc
					(start 169.305732 -380.99619)
					(mid 171.517242 -378.306051)
					(end 174.850044 -377.296172)
				)
				(arc
					(start 181.349904 -377.296172)
					(mid 184.68265 -378.306134)
					(end 186.894216 -380.99619)
				)
				(arc
					(start 192.996312 -380.99619)
					(mid 194.75613 -376.753326)
					(end 199.00011 -374.996202)
				)
				(arc
					(start 251.000006 -374.996202)
					(mid 255.243985 -376.753327)
					(end 257.003804 -380.99619)
				)
				(xy 267.377418 -380.99619) (xy 267.446252 -380.927356)
				(arc
					(start 267.446252 -361.00004)
					(mid 269.204724 -356.754714)
					(end 273.45005 -354.996242)
				)
			)
		)
	)
	(zone
		(layers "F.Cu" "B.Cu" "In1.Cu" "In2.Cu" "In3.Cu" "In4.Cu" "In5.Cu" "In6.Cu")
		(hatch none 0.5)
		(connect_pads
			(clearance 0)
		)
		(min_thickness 0.25)
		(keepout
			(tracks not_allowed)
			(vias allowed)
			(pads allowed)
			(copperpour not_allowed)
			(footprints allowed)
		)
		(placement
			(enabled no)
			(sheetname "")
		)
		(fill yes
			(thermal_gap 0.5)
			(thermal_bridge_width 0.5)
			(island_removal_mode 0)
		)
		(polygon
			(pts
				(arc
					(start 152.32507 -63.799974)
					(mid 159.325056 -56.799988)
					(end 166.325042 -63.799974)
				)
				(arc
					(start 166.325042 -69.799962)
					(mid 159.325056 -76.799948)
					(end 152.32507 -69.799962)
				)
			)
		)
	)
	(zone
		(layers "F.Cu" "B.Cu" "In1.Cu" "In2.Cu" "In3.Cu" "In4.Cu" "In5.Cu" "In6.Cu")
		(name "Route Keepin")
		(hatch none 0.5)
		(connect_pads
			(clearance 0)
		)
		(min_thickness 0.25)
		(keepout
			(tracks allowed)
			(vias allowed)
			(pads allowed)
			(copperpour allowed)
			(footprints allowed)
		)
		(placement
			(enabled no)
			(sheetname "")
		)
		(fill
			(thermal_gap 0.5)
			(thermal_bridge_width 0.5)
			(island_removal_mode 0)
		)
		(polygon
			(pts
				(arc
					(start 275.75002 -359.238042)
					(mid 276.995941 -359.754119)
					(end 277.512018 -361.00004)
				)
				(arc
					(start 277.512018 -382.585722)
					(mid 277.530052 -382.676854)
					(end 277.581614 -382.754124)
				)
				(arc
					(start 279.995884 -385.168394)
					(mid 280.073163 -385.219937)
					(end 280.164286 -385.23799)
				)
				(arc
					(start 306.649882 -385.23799)
					(mid 306.818172 -385.168282)
					(end 306.88788 -384.999992)
				)
				(arc
					(start 306.88788 -383.29997)
					(mid 307.403957 -382.054049)
					(end 308.649878 -381.537972)
				)
				(arc
					(start 315.149992 -381.537972)
					(mid 316.395913 -382.054049)
					(end 316.91199 -383.29997)
				)
				(arc
					(start 316.91199 -384.999992)
					(mid 316.981698 -385.168282)
					(end 317.149988 -385.23799)
				)
				(arc
					(start 362.700062 -385.23799)
					(mid 362.868352 -385.168282)
					(end 362.93806 -384.999992)
				)
				(arc
					(start 362.93806 -381)
					(mid 363.454137 -379.754079)
					(end 364.700058 -379.238002)
				)
				(arc
					(start 416.699954 -379.238002)
					(mid 417.945875 -379.754079)
					(end 418.461952 -381)
				)
				(arc
					(start 418.461952 -384.999992)
					(mid 418.53166 -385.168282)
					(end 418.69995 -385.23799)
				)
				(arc
					(start 464.250024 -385.23799)
					(mid 464.418314 -385.168282)
					(end 464.488022 -384.999992)
				)
				(arc
					(start 464.488022 -383.29997)
					(mid 465.004099 -382.054049)
					(end 466.25002 -381.537972)
				)
				(arc
					(start 472.74988 -381.537972)
					(mid 473.995801 -382.054049)
					(end 474.511878 -383.29997)
				)
				(arc
					(start 474.511878 -384.999992)
					(mid 474.581586 -385.168282)
					(end 474.749876 -385.23799)
				)
				(arc
					(start 487.449876 -385.23799)
					(mid 487.618166 -385.168282)
					(end 487.687874 -384.999992)
				)
				(arc
					(start 487.687874 -372.000018)
					(mid 488.203861 -370.754187)
					(end 489.449618 -370.23802)
				)
				(arc
					(start 490.450124 -370.23802)
					(mid 490.618414 -370.168312)
					(end 490.688122 -370.000022)
				)
				(arc
					(start 490.688122 -0.999998)
					(mid 490.618414 -0.831708)
					(end 490.450124 -0.762)
				)
				(arc
					(start 311.999884 -0.762)
					(mid 311.831594 -0.831708)
					(end 311.761886 -0.999998)
				)
				(arc
					(start 311.761886 -47.200058)
					(mid 311.245809 -48.445979)
					(end 309.999888 -48.962056)
				)
				(arc
					(start 269.999968 -48.962056)
					(mid 269.831678 -49.031764)
					(end 269.76197 -49.200054)
				)
				(arc
					(start 269.76197 -61.999876)
					(mid 269.245893 -63.245797)
					(end 267.999972 -63.761874)
				)
				(arc
					(start 207.999838 -63.761874)
					(mid 206.754171 -63.245797)
					(end 206.238094 -62.00013)
				)
				(arc
					(start 206.238094 -49.200054)
					(mid 206.168386 -49.031764)
					(end 206.000096 -48.962056)
				)
				(arc
					(start 200.000108 -48.962056)
					(mid 198.754187 -48.445979)
					(end 198.23811 -47.200058)
				)
				(arc
					(start 198.23811 -0.999998)
					(mid 198.168402 -0.831708)
					(end 198.000112 -0.762)
				)
				(arc
					(start 0.999998 -0.762)
					(mid 0.831708 -0.831708)
					(end 0.762 -0.999998)
				)
				(arc
					(start 0.762 -370.000022)
					(mid 0.831708 -370.168312)
					(end 0.999998 -370.23802)
				)
				(arc
					(start 1.999996 -370.23802)
					(mid 3.245917 -370.754097)
					(end 3.761994 -372.000018)
				)
				(arc
					(start 3.761994 -384.999992)
					(mid 3.831702 -385.168282)
					(end 3.999992 -385.23799)
				)
				(arc
					(start 15.249906 -385.23799)
					(mid 15.418196 -385.168282)
					(end 15.487904 -384.999992)
				)
				(arc
					(start 15.487904 -383.29997)
					(mid 16.003981 -382.054049)
					(end 17.249902 -381.537972)
				)
				(arc
					(start 23.750016 -381.537972)
					(mid 24.995937 -382.054049)
					(end 25.512014 -383.29997)
				)
				(arc
					(start 25.512014 -384.999992)
					(mid 25.581722 -385.168282)
					(end 25.750012 -385.23799)
				)
				(arc
					(start 71.300086 -385.23799)
					(mid 71.468376 -385.168282)
					(end 71.538084 -384.999992)
				)
				(arc
					(start 71.538084 -381)
					(mid 72.054161 -379.754079)
					(end 73.300082 -379.238002)
				)
				(arc
					(start 125.299978 -379.238002)
					(mid 126.545899 -379.754079)
					(end 127.061976 -381)
				)
				(arc
					(start 127.061976 -384.999992)
					(mid 127.131684 -385.168282)
					(end 127.299974 -385.23799)
				)
				(arc
					(start 172.850048 -385.23799)
					(mid 173.018338 -385.168282)
					(end 173.088046 -384.999992)
				)
				(arc
					(start 173.088046 -383.29997)
					(mid 173.604123 -382.054049)
					(end 174.850044 -381.537972)
				)
				(arc
					(start 181.349904 -381.537972)
					(mid 182.595825 -382.054049)
					(end 183.111902 -383.29997)
				)
				(arc
					(start 183.111902 -384.999992)
					(mid 183.18161 -385.168282)
					(end 183.3499 -385.23799)
				)
				(arc
					(start 197.000114 -385.23799)
					(mid 197.168404 -385.168282)
					(end 197.238112 -384.999992)
				)
				(arc
					(start 197.238112 -381)
					(mid 197.754189 -379.754079)
					(end 199.00011 -379.238002)
				)
				(arc
					(start 251.000006 -379.238002)
					(mid 252.245927 -379.754079)
					(end 252.762004 -381)
				)
				(arc
					(start 252.762004 -384.999992)
					(mid 252.831712 -385.168282)
					(end 253.000002 -385.23799)
				)
				(arc
					(start 269.035784 -385.23799)
					(mid 269.126916 -385.219956)
					(end 269.204186 -385.168394)
				)
				(arc
					(start 271.618456 -382.754124)
					(mid 271.669999 -382.676845)
					(end 271.688052 -382.585722)
				)
				(arc
					(start 271.688052 -361.00004)
					(mid 272.204129 -359.754119)
					(end 273.45005 -359.238042)
				)
			)
		)
	)
	(zone
		(layers "F.Cu" "B.Cu" "In1.Cu" "In2.Cu" "In3.Cu" "In4.Cu" "In5.Cu" "In6.Cu")
		(hatch none 0.5)
		(connect_pads
			(clearance 0)
		)
		(min_thickness 0.25)
		(keepout
			(tracks not_allowed)
			(vias allowed)
			(pads allowed)
			(copperpour not_allowed)
			(footprints allowed)
		)
		(placement
			(enabled no)
			(sheetname "")
		)
		(fill yes
			(thermal_gap 0.5)
			(thermal_bridge_width 0.5)
			(island_removal_mode 0)
		)
		(polygon
			(pts
				(arc
					(start 26.325068 -293.800022)
					(mid 33.325054 -286.800036)
					(end 40.32504 -293.800022)
				)
				(arc
					(start 40.32504 -299.80001)
					(mid 33.325054 -306.799996)
					(end 26.325068 -299.80001)
				)
			)
		)
	)
	(zone
		(layers "F.Cu" "B.Cu" "In1.Cu" "In2.Cu" "In3.Cu" "In4.Cu" "In5.Cu" "In6.Cu")
		(hatch none 0.5)
		(connect_pads
			(clearance 0)
		)
		(min_thickness 0.25)
		(keepout
			(tracks not_allowed)
			(vias allowed)
			(pads allowed)
			(copperpour not_allowed)
			(footprints allowed)
		)
		(placement
			(enabled no)
			(sheetname "")
		)
		(fill yes
			(thermal_gap 0.5)
			(thermal_bridge_width 0.5)
			(island_removal_mode 0)
		)
		(polygon
			(pts
				(arc
					(start 386.675122 -178.799998)
					(mid 393.675108 -171.800012)
					(end 400.675094 -178.799998)
				)
				(arc
					(start 400.675094 -184.799986)
					(mid 393.675108 -191.799972)
					(end 386.675122 -184.799986)
				)
			)
		)
	)
	(zone
		(layers "F.Cu" "B.Cu" "In1.Cu" "In2.Cu" "In3.Cu" "In4.Cu" "In5.Cu" "In6.Cu")
		(hatch none 0.5)
		(connect_pads
			(clearance 0)
		)
		(min_thickness 0.25)
		(keepout
			(tracks not_allowed)
			(vias allowed)
			(pads allowed)
			(copperpour not_allowed)
			(footprints allowed)
		)
		(placement
			(enabled no)
			(sheetname "")
		)
		(fill yes
			(thermal_gap 0.5)
			(thermal_bridge_width 0.5)
			(island_removal_mode 0)
		)
		(polygon
			(pts
				(arc
					(start 449.674996 -178.799998)
					(mid 456.674982 -171.800012)
					(end 463.674968 -178.799998)
				)
				(arc
					(start 463.674968 -184.799986)
					(mid 456.674982 -191.799972)
					(end 449.674996 -184.799986)
				)
			)
		)
	)
	(zone
		(layers "F.Cu" "B.Cu" "In1.Cu" "In2.Cu" "In3.Cu" "In4.Cu" "In5.Cu" "In6.Cu")
		(hatch none 0.5)
		(connect_pads
			(clearance 0)
		)
		(min_thickness 0.25)
		(keepout
			(tracks not_allowed)
			(vias allowed)
			(pads allowed)
			(copperpour not_allowed)
			(footprints allowed)
		)
		(placement
			(enabled no)
			(sheetname "")
		)
		(fill
			(thermal_gap 0.5)
			(thermal_bridge_width 0.5)
			(island_removal_mode 0)
		)
		(polygon
			(pts
				(arc
					(start 346.050108 -13.999972)
					(mid 336.55 -13.999972)
					(end 346.050108 -13.999972)
				)
			)
		)
	)
	(zone
		(layers "F.Cu" "B.Cu" "In1.Cu" "In2.Cu" "In3.Cu" "In4.Cu" "In5.Cu" "In6.Cu")
		(hatch none 0.5)
		(connect_pads
			(clearance 0)
		)
		(min_thickness 0.25)
		(keepout
			(tracks not_allowed)
			(vias allowed)
			(pads allowed)
			(copperpour not_allowed)
			(footprints allowed)
		)
		(placement
			(enabled no)
			(sheetname "")
		)
		(fill yes
			(thermal_gap 0.5)
			(thermal_bridge_width 0.5)
			(island_removal_mode 0)
		)
		(polygon
			(pts
				(arc
					(start 152.32507 -293.800022)
					(mid 159.325056 -286.800036)
					(end 166.325042 -293.800022)
				)
				(arc
					(start 166.325042 -299.80001)
					(mid 159.325056 -306.799996)
					(end 152.32507 -299.80001)
				)
			)
		)
	)
	(zone
		(layers "F.Cu" "B.Cu" "In1.Cu" "In2.Cu" "In3.Cu" "In4.Cu" "In5.Cu" "In6.Cu")
		(hatch none 0.5)
		(connect_pads
			(clearance 0)
		)
		(min_thickness 0.25)
		(keepout
			(tracks not_allowed)
			(vias allowed)
			(pads allowed)
			(copperpour not_allowed)
			(footprints allowed)
		)
		(placement
			(enabled no)
			(sheetname "")
		)
		(fill yes
			(thermal_gap 0.5)
			(thermal_bridge_width 0.5)
			(island_removal_mode 0)
		)
		(polygon
			(pts
				(arc
					(start 386.675122 -63.799974)
					(mid 393.675108 -56.799988)
					(end 400.675094 -63.799974)
				)
				(arc
					(start 400.675094 -69.799962)
					(mid 393.675108 -76.799948)
					(end 386.675122 -69.799962)
				)
			)
		)
	)
	(zone
		(layers "F.Cu" "B.Cu" "In1.Cu" "In2.Cu" "In3.Cu" "In4.Cu" "In5.Cu" "In6.Cu")
		(hatch none 0.5)
		(connect_pads
			(clearance 0)
		)
		(min_thickness 0.25)
		(keepout
			(tracks not_allowed)
			(vias allowed)
			(pads allowed)
			(copperpour not_allowed)
			(footprints allowed)
		)
		(placement
			(enabled no)
			(sheetname "")
		)
		(fill
			(thermal_gap 0.5)
			(thermal_bridge_width 0.5)
			(island_removal_mode 0)
		)
		(polygon
			(pts
				(arc
					(start 472.250008 -13.999972)
					(mid 462.7499 -13.999972)
					(end 472.250008 -13.999972)
				)
			)
		)
	)
	(zone
		(layers "F.Cu" "B.Cu" "In1.Cu" "In2.Cu" "In3.Cu" "In4.Cu" "In5.Cu" "In6.Cu")
		(hatch none 0.5)
		(connect_pads
			(clearance 0)
		)
		(min_thickness 0.25)
		(keepout
			(tracks not_allowed)
			(vias allowed)
			(pads allowed)
			(copperpour not_allowed)
			(footprints allowed)
		)
		(placement
			(enabled no)
			(sheetname "")
		)
		(fill yes
			(thermal_gap 0.5)
			(thermal_bridge_width 0.5)
			(island_removal_mode 0)
		)
		(polygon
			(pts
				(arc
					(start 323.674994 -293.800022)
					(mid 330.67498 -286.800036)
					(end 337.674966 -293.800022)
				)
				(arc
					(start 337.674966 -299.80001)
					(mid 330.67498 -306.799996)
					(end 323.674994 -299.80001)
				)
			)
		)
	)
	(zone
		(layers "F.Cu" "B.Cu" "In1.Cu" "In2.Cu" "In3.Cu" "In4.Cu" "In5.Cu" "In6.Cu")
		(hatch none 0.5)
		(connect_pads
			(clearance 0)
		)
		(min_thickness 0.25)
		(keepout
			(tracks not_allowed)
			(vias allowed)
			(pads allowed)
			(copperpour not_allowed)
			(footprints allowed)
		)
		(placement
			(enabled no)
			(sheetname "")
		)
		(fill yes
			(thermal_gap 0.5)
			(thermal_bridge_width 0.5)
			(island_removal_mode 0)
		)
		(polygon
			(pts
				(arc
					(start 152.32507 -178.799998)
					(mid 159.325056 -171.800012)
					(end 166.325042 -178.799998)
				)
				(arc
					(start 166.325042 -184.799986)
					(mid 159.325056 -191.799972)
					(end 152.32507 -184.799986)
				)
			)
		)
	)
	(zone
		(layers "F.Cu" "B.Cu" "In1.Cu" "In2.Cu" "In3.Cu" "In4.Cu" "In5.Cu" "In6.Cu")
		(hatch none 0.5)
		(connect_pads
			(clearance 0)
		)
		(min_thickness 0.25)
		(keepout
			(tracks not_allowed)
			(vias allowed)
			(pads allowed)
			(copperpour not_allowed)
			(footprints allowed)
		)
		(placement
			(enabled no)
			(sheetname "")
		)
		(fill yes
			(thermal_gap 0.5)
			(thermal_bridge_width 0.5)
			(island_removal_mode 0)
		)
		(polygon
			(pts
				(arc
					(start 449.674996 -63.799974)
					(mid 456.674982 -56.799988)
					(end 463.674968 -63.799974)
				)
				(arc
					(start 463.674968 -69.799962)
					(mid 456.674982 -76.799948)
					(end 449.674996 -69.799962)
				)
			)
		)
	)
	(zone
		(layers "F.Cu" "B.Cu" "In1.Cu" "In2.Cu" "In3.Cu" "In4.Cu" "In5.Cu" "In6.Cu")
		(hatch none 0.5)
		(connect_pads
			(clearance 0)
		)
		(min_thickness 0.25)
		(keepout
			(tracks not_allowed)
			(vias allowed)
			(pads allowed)
			(copperpour not_allowed)
			(footprints allowed)
		)
		(placement
			(enabled no)
			(sheetname "")
		)
		(fill
			(thermal_gap 0.5)
			(thermal_bridge_width 0.5)
			(island_removal_mode 0)
		)
		(polygon
			(pts
				(arc
					(start 141.824964 -181.799738)
					(mid 113.824512 -181.799738)
					(end 141.824964 -181.799738)
				)
			)
		)
	)
	(zone
		(layers "F.Cu" "B.Cu" "In1.Cu" "In2.Cu" "In3.Cu" "In4.Cu" "In5.Cu" "In6.Cu")
		(hatch none 0.5)
		(connect_pads
			(clearance 0)
		)
		(min_thickness 0.25)
		(keepout
			(tracks not_allowed)
			(vias allowed)
			(pads allowed)
			(copperpour not_allowed)
			(footprints allowed)
		)
		(placement
			(enabled no)
			(sheetname "")
		)
		(fill yes
			(thermal_gap 0.5)
			(thermal_bridge_width 0.5)
			(island_removal_mode 0)
		)
		(polygon
			(pts
				(arc
					(start 89.324942 -293.800022)
					(mid 96.324928 -286.800036)
					(end 103.324914 -293.800022)
				)
				(arc
					(start 103.324914 -299.80001)
					(mid 96.324928 -306.799996)
					(end 89.324942 -299.80001)
				)
			)
		)
	)
	(zone
		(layers "F.Cu" "B.Cu" "In1.Cu" "In2.Cu" "In3.Cu" "In4.Cu" "In5.Cu" "In6.Cu")
		(hatch none 0.5)
		(connect_pads
			(clearance 0)
		)
		(min_thickness 0.25)
		(keepout
			(tracks not_allowed)
			(vias allowed)
			(pads allowed)
			(copperpour not_allowed)
			(footprints allowed)
		)
		(placement
			(enabled no)
			(sheetname "")
		)
		(fill
			(thermal_gap 0.5)
			(thermal_bridge_width 0.5)
			(island_removal_mode 0)
		)
		(polygon
			(pts
				(arc
					(start 134.936992 -181.799738)
					(mid 120.712992 -181.799738)
					(end 134.936992 -181.799738)
				)
			)
		)
	)
	(zone
		(net "MB0_P12V_IN_R")
		(layers "F.Cu" "B.Cu" "In1.Cu" "In2.Cu" "In4.Cu" "In5.Cu" "In6.Cu")
		(hatch none 0.5)
		(connect_pads
			(clearance 0.5)
		)
		(min_thickness 0.25)
		(fill yes
			(thermal_gap 0.5)
			(thermal_bridge_width 0.5)
			(island_removal_mode 0)
		)
		(polygon
			(pts
				(xy 166.3954 -329.1205) (xy 166.3954 -358.2035) (xy 204.111606 -358.2035) (xy 204.4446 -357.870506)
				(xy 204.4446 -329.415394) (xy 204.149706 -329.1205)
			)
		)
	)
	(zone
		(layers "F.Cu" "B.Cu" "In2.Cu")
		(hatch none 0.5)
		(connect_pads
			(clearance 0)
		)
		(min_thickness 0.25)
		(keepout
			(tracks not_allowed)
			(vias allowed)
			(pads allowed)
			(copperpour not_allowed)
			(footprints allowed)
		)
		(placement
			(enabled no)
			(sheetname "")
		)
		(fill yes
			(thermal_gap 0.5)
			(thermal_bridge_width 0.5)
			(island_removal_mode 0)
		)
		(polygon
			(pts
				(arc
					(start 285.436564 -175.145954)
					(mid 284.887924 -175.694594)
					(end 285.436564 -176.243234)
				)
				(arc
					(start 286.836612 -176.243234)
					(mid 287.22366 -176.083438)
					(end 287.385252 -175.697134)
				)
				(arc
					(start 287.230312 -175.697134)
					(mid 286.836612 -176.088302)
					(end 286.442912 -175.697134)
				)
				(arc
					(start 285.830264 -175.697134)
					(mid 285.436564 -176.088302)
					(end 285.042864 -175.697134)
				)
				(arc
					(start 285.042864 -175.694594)
					(mid 285.436564 -175.300894)
					(end 285.830264 -175.694594)
				)
				(arc
					(start 286.442912 -175.694594)
					(mid 286.836612 -175.300894)
					(end 287.230312 -175.694594)
				)
				(arc
					(start 287.385252 -175.694594)
					(mid 287.224559 -175.306647)
					(end 286.836612 -175.145954)
				)
			)
		)
	)
	(zone
		(layers "F.Cu" "B.Cu" "In2.Cu")
		(hatch none 0.5)
		(connect_pads
			(clearance 0)
		)
		(min_thickness 0.25)
		(keepout
			(tracks not_allowed)
			(vias allowed)
			(pads allowed)
			(copperpour not_allowed)
			(footprints allowed)
		)
		(placement
			(enabled no)
			(sheetname "")
		)
		(fill yes
			(thermal_gap 0.5)
			(thermal_bridge_width 0.5)
			(island_removal_mode 0)
		)
		(polygon
			(pts
				(arc
					(start 285.436564 -200.345802)
					(mid 284.887924 -200.894442)
					(end 285.436564 -201.443082)
				)
				(arc
					(start 286.836612 -201.443082)
					(mid 287.22366 -201.283286)
					(end 287.385252 -200.896982)
				)
				(arc
					(start 287.230312 -200.896982)
					(mid 286.836612 -201.28815)
					(end 286.442912 -200.896982)
				)
				(arc
					(start 285.830264 -200.896982)
					(mid 285.436564 -201.28815)
					(end 285.042864 -200.896982)
				)
				(arc
					(start 285.042864 -200.894442)
					(mid 285.436564 -200.500742)
					(end 285.830264 -200.894442)
				)
				(arc
					(start 286.442912 -200.894442)
					(mid 286.836612 -200.500742)
					(end 287.230312 -200.894442)
				)
				(arc
					(start 287.385252 -200.894442)
					(mid 287.224559 -200.506495)
					(end 286.836612 -200.345802)
				)
			)
		)
	)
	(zone
		(layers "F.Cu" "B.Cu" "In2.Cu")
		(hatch none 0.5)
		(connect_pads
			(clearance 0)
		)
		(min_thickness 0.25)
		(keepout
			(tracks not_allowed)
			(vias allowed)
			(pads allowed)
			(copperpour not_allowed)
			(footprints allowed)
		)
		(placement
			(enabled no)
			(sheetname "")
		)
		(fill yes
			(thermal_gap 0.5)
			(thermal_bridge_width 0.5)
			(island_removal_mode 0)
		)
		(polygon
			(pts
				(arc
					(start 286.436562 -212.945726)
					(mid 285.887922 -213.494366)
					(end 286.436562 -214.043006)
				)
				(arc
					(start 287.83661 -214.043006)
					(mid 288.223658 -213.88321)
					(end 288.38525 -213.496906)
				)
				(arc
					(start 288.23031 -213.496906)
					(mid 287.83661 -213.888074)
					(end 287.44291 -213.496906)
				)
				(arc
					(start 286.830262 -213.496906)
					(mid 286.436562 -213.888074)
					(end 286.042862 -213.496906)
				)
				(arc
					(start 286.042862 -213.494366)
					(mid 286.436562 -213.100666)
					(end 286.830262 -213.494366)
				)
				(arc
					(start 287.44291 -213.494366)
					(mid 287.83661 -213.100666)
					(end 288.23031 -213.494366)
				)
				(arc
					(start 288.38525 -213.494366)
					(mid 288.224557 -213.106419)
					(end 287.83661 -212.945726)
				)
			)
		)
	)
	(zone
		(layers "F.Cu" "B.Cu" "In2.Cu")
		(hatch none 0.5)
		(connect_pads
			(clearance 0)
		)
		(min_thickness 0.25)
		(keepout
			(tracks not_allowed)
			(vias allowed)
			(pads allowed)
			(copperpour not_allowed)
			(footprints allowed)
		)
		(placement
			(enabled no)
			(sheetname "")
		)
		(fill yes
			(thermal_gap 0.5)
			(thermal_bridge_width 0.5)
			(island_removal_mode 0)
		)
		(polygon
			(pts
				(arc
					(start 285.436564 -207.54594)
					(mid 284.887924 -208.09458)
					(end 285.436564 -208.64322)
				)
				(arc
					(start 286.836612 -208.64322)
					(mid 287.22366 -208.483424)
					(end 287.385252 -208.09712)
				)
				(arc
					(start 287.230312 -208.09712)
					(mid 286.836612 -208.488288)
					(end 286.442912 -208.09712)
				)
				(arc
					(start 285.830264 -208.09712)
					(mid 285.436564 -208.488288)
					(end 285.042864 -208.09712)
				)
				(arc
					(start 285.042864 -208.09458)
					(mid 285.436564 -207.70088)
					(end 285.830264 -208.09458)
				)
				(arc
					(start 286.442912 -208.09458)
					(mid 286.836612 -207.70088)
					(end 287.230312 -208.09458)
				)
				(arc
					(start 287.385252 -208.09458)
					(mid 287.224559 -207.706633)
					(end 286.836612 -207.54594)
				)
			)
		)
	)
	(zone
		(layers "F.Cu" "B.Cu" "In2.Cu")
		(hatch none 0.5)
		(connect_pads
			(clearance 0)
		)
		(min_thickness 0.25)
		(keepout
			(tracks not_allowed)
			(vias allowed)
			(pads allowed)
			(copperpour not_allowed)
			(footprints allowed)
		)
		(placement
			(enabled no)
			(sheetname "")
		)
		(fill yes
			(thermal_gap 0.5)
			(thermal_bridge_width 0.5)
			(island_removal_mode 0)
		)
		(polygon
			(pts
				(arc
					(start 286.436562 -198.545704)
					(mid 285.887922 -199.094344)
					(end 286.436562 -199.642984)
				)
				(arc
					(start 287.83661 -199.642984)
					(mid 288.223658 -199.483188)
					(end 288.38525 -199.096884)
				)
				(arc
					(start 288.23031 -199.096884)
					(mid 287.83661 -199.488052)
					(end 287.44291 -199.096884)
				)
				(arc
					(start 286.830262 -199.096884)
					(mid 286.436562 -199.488052)
					(end 286.042862 -199.096884)
				)
				(arc
					(start 286.042862 -199.094344)
					(mid 286.436562 -198.700644)
					(end 286.830262 -199.094344)
				)
				(arc
					(start 287.44291 -199.094344)
					(mid 287.83661 -198.700644)
					(end 288.23031 -199.094344)
				)
				(arc
					(start 288.38525 -199.094344)
					(mid 288.224557 -198.706397)
					(end 287.83661 -198.545704)
				)
			)
		)
	)
	(zone
		(layers "F.Cu" "B.Cu" "In2.Cu")
		(hatch none 0.5)
		(connect_pads
			(clearance 0)
		)
		(min_thickness 0.25)
		(keepout
			(tracks not_allowed)
			(vias allowed)
			(pads allowed)
			(copperpour not_allowed)
			(footprints allowed)
		)
		(placement
			(enabled no)
			(sheetname "")
		)
		(fill yes
			(thermal_gap 0.5)
			(thermal_bridge_width 0.5)
			(island_removal_mode 0)
		)
		(polygon
			(pts
				(arc
					(start 285.436564 -214.745824)
					(mid 284.887924 -215.294464)
					(end 285.436564 -215.843104)
				)
				(arc
					(start 286.836612 -215.843104)
					(mid 287.22366 -215.683308)
					(end 287.385252 -215.297004)
				)
				(arc
					(start 287.230312 -215.297004)
					(mid 286.836612 -215.688172)
					(end 286.442912 -215.297004)
				)
				(arc
					(start 285.830264 -215.297004)
					(mid 285.436564 -215.688172)
					(end 285.042864 -215.297004)
				)
				(arc
					(start 285.042864 -215.294464)
					(mid 285.436564 -214.900764)
					(end 285.830264 -215.294464)
				)
				(arc
					(start 286.442912 -215.294464)
					(mid 286.836612 -214.900764)
					(end 287.230312 -215.294464)
				)
				(arc
					(start 287.385252 -215.294464)
					(mid 287.224559 -214.906517)
					(end 286.836612 -214.745824)
				)
			)
		)
	)
	(zone
		(layers "F.Cu" "B.Cu" "In2.Cu")
		(hatch none 0.5)
		(connect_pads
			(clearance 0)
		)
		(min_thickness 0.25)
		(keepout
			(tracks not_allowed)
			(vias allowed)
			(pads allowed)
			(copperpour not_allowed)
			(footprints allowed)
		)
		(placement
			(enabled no)
			(sheetname "")
		)
		(fill yes
			(thermal_gap 0.5)
			(thermal_bridge_width 0.5)
			(island_removal_mode 0)
		)
		(polygon
			(pts
				(arc
					(start 285.436564 -178.745896)
					(mid 284.887924 -179.294536)
					(end 285.436564 -179.843176)
				)
				(arc
					(start 286.836612 -179.843176)
					(mid 287.22366 -179.68338)
					(end 287.385252 -179.297076)
				)
				(arc
					(start 287.230312 -179.297076)
					(mid 286.836612 -179.688244)
					(end 286.442912 -179.297076)
				)
				(arc
					(start 285.830264 -179.297076)
					(mid 285.436564 -179.688244)
					(end 285.042864 -179.297076)
				)
				(arc
					(start 285.042864 -179.294536)
					(mid 285.436564 -178.900836)
					(end 285.830264 -179.294536)
				)
				(arc
					(start 286.442912 -179.294536)
					(mid 286.836612 -178.900836)
					(end 287.230312 -179.294536)
				)
				(arc
					(start 287.385252 -179.294536)
					(mid 287.224559 -178.906589)
					(end 286.836612 -178.745896)
				)
			)
		)
	)
	(zone
		(layers "F.Cu" "B.Cu" "In2.Cu")
		(hatch none 0.5)
		(connect_pads
			(clearance 0)
		)
		(min_thickness 0.25)
		(keepout
			(tracks not_allowed)
			(vias allowed)
			(pads allowed)
			(copperpour not_allowed)
			(footprints allowed)
		)
		(placement
			(enabled no)
			(sheetname "")
		)
		(fill yes
			(thermal_gap 0.5)
			(thermal_bridge_width 0.5)
			(island_removal_mode 0)
		)
		(polygon
			(pts
				(arc
					(start 286.436562 -180.54574)
					(mid 285.887922 -181.09438)
					(end 286.436562 -181.64302)
				)
				(arc
					(start 287.83661 -181.64302)
					(mid 288.223658 -181.483224)
					(end 288.38525 -181.09692)
				)
				(arc
					(start 288.23031 -181.09692)
					(mid 287.83661 -181.488088)
					(end 287.44291 -181.09692)
				)
				(arc
					(start 286.830262 -181.09692)
					(mid 286.436562 -181.488088)
					(end 286.042862 -181.09692)
				)
				(arc
					(start 286.042862 -181.09438)
					(mid 286.436562 -180.70068)
					(end 286.830262 -181.09438)
				)
				(arc
					(start 287.44291 -181.09438)
					(mid 287.83661 -180.70068)
					(end 288.23031 -181.09438)
				)
				(arc
					(start 288.38525 -181.09438)
					(mid 288.224557 -180.706433)
					(end 287.83661 -180.54574)
				)
			)
		)
	)
	(zone
		(layers "F.Cu" "B.Cu" "In2.Cu")
		(hatch none 0.5)
		(connect_pads
			(clearance 0)
		)
		(min_thickness 0.25)
		(keepout
			(tracks not_allowed)
			(vias allowed)
			(pads allowed)
			(copperpour not_allowed)
			(footprints allowed)
		)
		(placement
			(enabled no)
			(sheetname "")
		)
		(fill yes
			(thermal_gap 0.5)
			(thermal_bridge_width 0.5)
			(island_removal_mode 0)
		)
		(polygon
			(pts
				(arc
					(start 285.436564 -203.945744)
					(mid 284.887924 -204.494384)
					(end 285.436564 -205.043024)
				)
				(arc
					(start 286.836612 -205.043024)
					(mid 287.22366 -204.883228)
					(end 287.385252 -204.496924)
				)
				(arc
					(start 287.230312 -204.496924)
					(mid 286.836612 -204.888092)
					(end 286.442912 -204.496924)
				)
				(arc
					(start 285.830264 -204.496924)
					(mid 285.436564 -204.888092)
					(end 285.042864 -204.496924)
				)
				(arc
					(start 285.042864 -204.494384)
					(mid 285.436564 -204.100684)
					(end 285.830264 -204.494384)
				)
				(arc
					(start 286.442912 -204.494384)
					(mid 286.836612 -204.100684)
					(end 287.230312 -204.494384)
				)
				(arc
					(start 287.385252 -204.494384)
					(mid 287.224559 -204.106437)
					(end 286.836612 -203.945744)
				)
			)
		)
	)
	(zone
		(layers "F.Cu" "B.Cu" "In2.Cu")
		(hatch none 0.5)
		(connect_pads
			(clearance 0)
		)
		(min_thickness 0.25)
		(keepout
			(tracks not_allowed)
			(vias allowed)
			(pads allowed)
			(copperpour not_allowed)
			(footprints allowed)
		)
		(placement
			(enabled no)
			(sheetname "")
		)
		(fill yes
			(thermal_gap 0.5)
			(thermal_bridge_width 0.5)
			(island_removal_mode 0)
		)
		(polygon
			(pts
				(arc
					(start 286.436562 -136.945878)
					(mid 285.887922 -137.494518)
					(end 286.436562 -138.043158)
				)
				(arc
					(start 287.83661 -138.043158)
					(mid 288.223658 -137.883362)
					(end 288.38525 -137.497058)
				)
				(arc
					(start 288.23031 -137.497058)
					(mid 287.83661 -137.888226)
					(end 287.44291 -137.497058)
				)
				(arc
					(start 286.830262 -137.497058)
					(mid 286.436562 -137.888226)
					(end 286.042862 -137.497058)
				)
				(arc
					(start 286.042862 -137.494518)
					(mid 286.436562 -137.100818)
					(end 286.830262 -137.494518)
				)
				(arc
					(start 287.44291 -137.494518)
					(mid 287.83661 -137.100818)
					(end 288.23031 -137.494518)
				)
				(arc
					(start 288.38525 -137.494518)
					(mid 288.224557 -137.106571)
					(end 287.83661 -136.945878)
				)
			)
		)
	)
	(zone
		(layers "F.Cu" "B.Cu" "In2.Cu")
		(hatch none 0.5)
		(connect_pads
			(clearance 0)
		)
		(min_thickness 0.25)
		(keepout
			(tracks not_allowed)
			(vias allowed)
			(pads allowed)
			(copperpour not_allowed)
			(footprints allowed)
		)
		(placement
			(enabled no)
			(sheetname "")
		)
		(fill yes
			(thermal_gap 0.5)
			(thermal_bridge_width 0.5)
			(island_removal_mode 0)
		)
		(polygon
			(pts
				(arc
					(start 285.436564 -182.345838)
					(mid 284.887924 -182.894478)
					(end 285.436564 -183.443118)
				)
				(arc
					(start 286.836612 -183.443118)
					(mid 287.22366 -183.283322)
					(end 287.385252 -182.897018)
				)
				(arc
					(start 287.230312 -182.897018)
					(mid 286.836612 -183.288186)
					(end 286.442912 -182.897018)
				)
				(arc
					(start 285.830264 -182.897018)
					(mid 285.436564 -183.288186)
					(end 285.042864 -182.897018)
				)
				(arc
					(start 285.042864 -182.894478)
					(mid 285.436564 -182.500778)
					(end 285.830264 -182.894478)
				)
				(arc
					(start 286.442912 -182.894478)
					(mid 286.836612 -182.500778)
					(end 287.230312 -182.894478)
				)
				(arc
					(start 287.385252 -182.894478)
					(mid 287.224559 -182.506531)
					(end 286.836612 -182.345838)
				)
			)
		)
	)
	(zone
		(layers "F.Cu" "B.Cu" "In2.Cu")
		(hatch none 0.5)
		(connect_pads
			(clearance 0)
		)
		(min_thickness 0.25)
		(keepout
			(tracks not_allowed)
			(vias allowed)
			(pads allowed)
			(copperpour not_allowed)
			(footprints allowed)
		)
		(placement
			(enabled no)
			(sheetname "")
		)
		(fill yes
			(thermal_gap 0.5)
			(thermal_bridge_width 0.5)
			(island_removal_mode 0)
		)
		(polygon
			(pts
				(arc
					(start 285.436564 -189.545722)
					(mid 284.887924 -190.094362)
					(end 285.436564 -190.643002)
				)
				(arc
					(start 286.836612 -190.643002)
					(mid 287.22366 -190.483206)
					(end 287.385252 -190.096902)
				)
				(arc
					(start 287.230312 -190.096902)
					(mid 286.836612 -190.48807)
					(end 286.442912 -190.096902)
				)
				(arc
					(start 285.830264 -190.096902)
					(mid 285.436564 -190.48807)
					(end 285.042864 -190.096902)
				)
				(arc
					(start 285.042864 -190.094362)
					(mid 285.436564 -189.700662)
					(end 285.830264 -190.094362)
				)
				(arc
					(start 286.442912 -190.094362)
					(mid 286.836612 -189.700662)
					(end 287.230312 -190.094362)
				)
				(arc
					(start 287.385252 -190.094362)
					(mid 287.224559 -189.706415)
					(end 286.836612 -189.545722)
				)
			)
		)
	)
	(zone
		(layers "F.Cu" "B.Cu" "In2.Cu")
		(hatch none 0.5)
		(connect_pads
			(clearance 0)
		)
		(min_thickness 0.25)
		(keepout
			(tracks not_allowed)
			(vias allowed)
			(pads allowed)
			(copperpour not_allowed)
			(footprints allowed)
		)
		(placement
			(enabled no)
			(sheetname "")
		)
		(fill yes
			(thermal_gap 0.5)
			(thermal_bridge_width 0.5)
			(island_removal_mode 0)
		)
		(polygon
			(pts
				(arc
					(start 286.436562 -184.145936)
					(mid 285.887922 -184.694576)
					(end 286.436562 -185.243216)
				)
				(arc
					(start 287.83661 -185.243216)
					(mid 288.223658 -185.08342)
					(end 288.38525 -184.697116)
				)
				(arc
					(start 288.23031 -184.697116)
					(mid 287.83661 -185.088284)
					(end 287.44291 -184.697116)
				)
				(arc
					(start 286.830262 -184.697116)
					(mid 286.436562 -185.088284)
					(end 286.042862 -184.697116)
				)
				(arc
					(start 286.042862 -184.694576)
					(mid 286.436562 -184.300876)
					(end 286.830262 -184.694576)
				)
				(arc
					(start 287.44291 -184.694576)
					(mid 287.83661 -184.300876)
					(end 288.23031 -184.694576)
				)
				(arc
					(start 288.38525 -184.694576)
					(mid 288.224557 -184.306629)
					(end 287.83661 -184.145936)
				)
			)
		)
	)
	(zone
		(layers "F.Cu" "B.Cu" "In2.Cu")
		(hatch none 0.5)
		(connect_pads
			(clearance 0)
		)
		(min_thickness 0.25)
		(keepout
			(tracks not_allowed)
			(vias allowed)
			(pads allowed)
			(copperpour not_allowed)
			(footprints allowed)
		)
		(placement
			(enabled no)
			(sheetname "")
		)
		(fill yes
			(thermal_gap 0.5)
			(thermal_bridge_width 0.5)
			(island_removal_mode 0)
		)
		(polygon
			(pts
				(arc
					(start 286.436562 -238.145828)
					(mid 285.887922 -238.694468)
					(end 286.436562 -239.243108)
				)
				(arc
					(start 287.83661 -239.243108)
					(mid 288.223658 -239.083312)
					(end 288.38525 -238.697008)
				)
				(arc
					(start 288.23031 -238.697008)
					(mid 287.83661 -239.088176)
					(end 287.44291 -238.697008)
				)
				(arc
					(start 286.830262 -238.697008)
					(mid 286.436562 -239.088176)
					(end 286.042862 -238.697008)
				)
				(arc
					(start 286.042862 -238.694468)
					(mid 286.436562 -238.300768)
					(end 286.830262 -238.694468)
				)
				(arc
					(start 287.44291 -238.694468)
					(mid 287.83661 -238.300768)
					(end 288.23031 -238.694468)
				)
				(arc
					(start 288.38525 -238.694468)
					(mid 288.224557 -238.306521)
					(end 287.83661 -238.145828)
				)
			)
		)
	)
	(zone
		(layers "F.Cu" "B.Cu" "In2.Cu")
		(hatch none 0.5)
		(connect_pads
			(clearance 0)
		)
		(min_thickness 0.25)
		(keepout
			(tracks not_allowed)
			(vias allowed)
			(pads allowed)
			(copperpour not_allowed)
			(footprints allowed)
		)
		(placement
			(enabled no)
			(sheetname "")
		)
		(fill yes
			(thermal_gap 0.5)
			(thermal_bridge_width 0.5)
			(island_removal_mode 0)
		)
		(polygon
			(pts
				(arc
					(start 286.436562 -187.745878)
					(mid 285.887922 -188.294518)
					(end 286.436562 -188.843158)
				)
				(arc
					(start 287.83661 -188.843158)
					(mid 288.223658 -188.683362)
					(end 288.38525 -188.297058)
				)
				(arc
					(start 288.23031 -188.297058)
					(mid 287.83661 -188.688226)
					(end 287.44291 -188.297058)
				)
				(arc
					(start 286.830262 -188.297058)
					(mid 286.436562 -188.688226)
					(end 286.042862 -188.297058)
				)
				(arc
					(start 286.042862 -188.294518)
					(mid 286.436562 -187.900818)
					(end 286.830262 -188.294518)
				)
				(arc
					(start 287.44291 -188.294518)
					(mid 287.83661 -187.900818)
					(end 288.23031 -188.294518)
				)
				(arc
					(start 288.38525 -188.294518)
					(mid 288.224557 -187.906571)
					(end 287.83661 -187.745878)
				)
			)
		)
	)
	(zone
		(layers "F.Cu" "B.Cu" "In2.Cu")
		(hatch none 0.5)
		(connect_pads
			(clearance 0)
		)
		(min_thickness 0.25)
		(keepout
			(tracks not_allowed)
			(vias allowed)
			(pads allowed)
			(copperpour not_allowed)
			(footprints allowed)
		)
		(placement
			(enabled no)
			(sheetname "")
		)
		(fill yes
			(thermal_gap 0.5)
			(thermal_bridge_width 0.5)
			(island_removal_mode 0)
		)
		(polygon
			(pts
				(arc
					(start 286.436562 -176.945798)
					(mid 285.887922 -177.494438)
					(end 286.436562 -178.043078)
				)
				(arc
					(start 287.83661 -178.043078)
					(mid 288.223658 -177.883282)
					(end 288.38525 -177.496978)
				)
				(arc
					(start 288.23031 -177.496978)
					(mid 287.83661 -177.888146)
					(end 287.44291 -177.496978)
				)
				(arc
					(start 286.830262 -177.496978)
					(mid 286.436562 -177.888146)
					(end 286.042862 -177.496978)
				)
				(arc
					(start 286.042862 -177.494438)
					(mid 286.436562 -177.100738)
					(end 286.830262 -177.494438)
				)
				(arc
					(start 287.44291 -177.494438)
					(mid 287.83661 -177.100738)
					(end 288.23031 -177.494438)
				)
				(arc
					(start 288.38525 -177.494438)
					(mid 288.224557 -177.106491)
					(end 287.83661 -176.945798)
				)
			)
		)
	)
	(zone
		(layers "F.Cu" "B.Cu" "In2.Cu")
		(hatch none 0.5)
		(connect_pads
			(clearance 0)
		)
		(min_thickness 0.25)
		(keepout
			(tracks not_allowed)
			(vias allowed)
			(pads allowed)
			(copperpour not_allowed)
			(footprints allowed)
		)
		(placement
			(enabled no)
			(sheetname "")
		)
		(fill yes
			(thermal_gap 0.5)
			(thermal_bridge_width 0.5)
			(island_removal_mode 0)
		)
		(polygon
			(pts
				(arc
					(start 285.436564 -211.145882)
					(mid 284.887924 -211.694522)
					(end 285.436564 -212.243162)
				)
				(arc
					(start 286.836612 -212.243162)
					(mid 287.22366 -212.083366)
					(end 287.385252 -211.697062)
				)
				(arc
					(start 287.230312 -211.697062)
					(mid 286.836612 -212.08823)
					(end 286.442912 -211.697062)
				)
				(arc
					(start 285.830264 -211.697062)
					(mid 285.436564 -212.08823)
					(end 285.042864 -211.697062)
				)
				(arc
					(start 285.042864 -211.694522)
					(mid 285.436564 -211.300822)
					(end 285.830264 -211.694522)
				)
				(arc
					(start 286.442912 -211.694522)
					(mid 286.836612 -211.300822)
					(end 287.230312 -211.694522)
				)
				(arc
					(start 287.385252 -211.694522)
					(mid 287.224559 -211.306575)
					(end 286.836612 -211.145882)
				)
			)
		)
	)
	(zone
		(layers "F.Cu" "B.Cu" "In2.Cu")
		(hatch none 0.5)
		(connect_pads
			(clearance 0)
		)
		(min_thickness 0.25)
		(keepout
			(tracks not_allowed)
			(vias allowed)
			(pads allowed)
			(copperpour not_allowed)
			(footprints allowed)
		)
		(placement
			(enabled no)
			(sheetname "")
		)
		(fill yes
			(thermal_gap 0.5)
			(thermal_bridge_width 0.5)
			(island_removal_mode 0)
		)
		(polygon
			(pts
				(arc
					(start 286.436562 -230.945944)
					(mid 285.887922 -231.494584)
					(end 286.436562 -232.043224)
				)
				(arc
					(start 287.83661 -232.043224)
					(mid 288.223658 -231.883428)
					(end 288.38525 -231.497124)
				)
				(arc
					(start 288.23031 -231.497124)
					(mid 287.83661 -231.888292)
					(end 287.44291 -231.497124)
				)
				(arc
					(start 286.830262 -231.497124)
					(mid 286.436562 -231.888292)
					(end 286.042862 -231.497124)
				)
				(arc
					(start 286.042862 -231.494584)
					(mid 286.436562 -231.100884)
					(end 286.830262 -231.494584)
				)
				(arc
					(start 287.44291 -231.494584)
					(mid 287.83661 -231.100884)
					(end 288.23031 -231.494584)
				)
				(arc
					(start 288.38525 -231.494584)
					(mid 288.224557 -231.106637)
					(end 287.83661 -230.945944)
				)
			)
		)
	)
	(zone
		(layers "F.Cu" "B.Cu" "In2.Cu")
		(hatch none 0.5)
		(connect_pads
			(clearance 0)
		)
		(min_thickness 0.25)
		(keepout
			(tracks not_allowed)
			(vias allowed)
			(pads allowed)
			(copperpour not_allowed)
			(footprints allowed)
		)
		(placement
			(enabled no)
			(sheetname "")
		)
		(fill yes
			(thermal_gap 0.5)
			(thermal_bridge_width 0.5)
			(island_removal_mode 0)
		)
		(polygon
			(pts
				(arc
					(start 285.436564 -232.745788)
					(mid 284.887924 -233.294428)
					(end 285.436564 -233.843068)
				)
				(arc
					(start 286.836612 -233.843068)
					(mid 287.22366 -233.683272)
					(end 287.385252 -233.296968)
				)
				(arc
					(start 287.230312 -233.296968)
					(mid 286.836612 -233.688136)
					(end 286.442912 -233.296968)
				)
				(arc
					(start 285.830264 -233.296968)
					(mid 285.436564 -233.688136)
					(end 285.042864 -233.296968)
				)
				(arc
					(start 285.042864 -233.294428)
					(mid 285.436564 -232.900728)
					(end 285.830264 -233.294428)
				)
				(arc
					(start 286.442912 -233.294428)
					(mid 286.836612 -232.900728)
					(end 287.230312 -233.294428)
				)
				(arc
					(start 287.385252 -233.294428)
					(mid 287.224559 -232.906481)
					(end 286.836612 -232.745788)
				)
			)
		)
	)
	(zone
		(layers "F.Cu" "B.Cu" "In2.Cu")
		(hatch none 0.5)
		(connect_pads
			(clearance 0)
		)
		(min_thickness 0.25)
		(keepout
			(tracks not_allowed)
			(vias allowed)
			(pads allowed)
			(copperpour not_allowed)
			(footprints allowed)
		)
		(placement
			(enabled no)
			(sheetname "")
		)
		(fill yes
			(thermal_gap 0.5)
			(thermal_bridge_width 0.5)
			(island_removal_mode 0)
		)
		(polygon
			(pts
				(arc
					(start 285.436564 -229.145846)
					(mid 284.887924 -229.694486)
					(end 285.436564 -230.243126)
				)
				(arc
					(start 286.836612 -230.243126)
					(mid 287.22366 -230.08333)
					(end 287.385252 -229.697026)
				)
				(arc
					(start 287.230312 -229.697026)
					(mid 286.836612 -230.088194)
					(end 286.442912 -229.697026)
				)
				(arc
					(start 285.830264 -229.697026)
					(mid 285.436564 -230.088194)
					(end 285.042864 -229.697026)
				)
				(arc
					(start 285.042864 -229.694486)
					(mid 285.436564 -229.300786)
					(end 285.830264 -229.694486)
				)
				(arc
					(start 286.442912 -229.694486)
					(mid 286.836612 -229.300786)
					(end 287.230312 -229.694486)
				)
				(arc
					(start 287.385252 -229.694486)
					(mid 287.224559 -229.306539)
					(end 286.836612 -229.145846)
				)
			)
		)
	)
	(zone
		(layers "F.Cu" "B.Cu" "In2.Cu")
		(hatch none 0.5)
		(connect_pads
			(clearance 0)
		)
		(min_thickness 0.25)
		(keepout
			(tracks not_allowed)
			(vias allowed)
			(pads allowed)
			(copperpour not_allowed)
			(footprints allowed)
		)
		(placement
			(enabled no)
			(sheetname "")
		)
		(fill yes
			(thermal_gap 0.5)
			(thermal_bridge_width 0.5)
			(island_removal_mode 0)
		)
		(polygon
			(pts
				(arc
					(start 286.436562 -140.54582)
					(mid 285.887922 -141.09446)
					(end 286.436562 -141.6431)
				)
				(arc
					(start 287.83661 -141.6431)
					(mid 288.223658 -141.483304)
					(end 288.38525 -141.097)
				)
				(arc
					(start 288.23031 -141.097)
					(mid 287.83661 -141.488168)
					(end 287.44291 -141.097)
				)
				(arc
					(start 286.830262 -141.097)
					(mid 286.436562 -141.488168)
					(end 286.042862 -141.097)
				)
				(arc
					(start 286.042862 -141.09446)
					(mid 286.436562 -140.70076)
					(end 286.830262 -141.09446)
				)
				(arc
					(start 287.44291 -141.09446)
					(mid 287.83661 -140.70076)
					(end 288.23031 -141.09446)
				)
				(arc
					(start 288.38525 -141.09446)
					(mid 288.224557 -140.706513)
					(end 287.83661 -140.54582)
				)
			)
		)
	)
	(zone
		(layers "F.Cu" "B.Cu" "In2.Cu")
		(hatch none 0.5)
		(connect_pads
			(clearance 0)
		)
		(min_thickness 0.25)
		(keepout
			(tracks not_allowed)
			(vias allowed)
			(pads allowed)
			(copperpour not_allowed)
			(footprints allowed)
		)
		(placement
			(enabled no)
			(sheetname "")
		)
		(fill yes
			(thermal_gap 0.5)
			(thermal_bridge_width 0.5)
			(island_removal_mode 0)
		)
		(polygon
			(pts
				(arc
					(start 286.436562 -144.145762)
					(mid 285.887922 -144.694402)
					(end 286.436562 -145.243042)
				)
				(arc
					(start 287.83661 -145.243042)
					(mid 288.223658 -145.083246)
					(end 288.38525 -144.696942)
				)
				(arc
					(start 288.23031 -144.696942)
					(mid 287.83661 -145.08811)
					(end 287.44291 -144.696942)
				)
				(arc
					(start 286.830262 -144.696942)
					(mid 286.436562 -145.08811)
					(end 286.042862 -144.696942)
				)
				(arc
					(start 286.042862 -144.694402)
					(mid 286.436562 -144.300702)
					(end 286.830262 -144.694402)
				)
				(arc
					(start 287.44291 -144.694402)
					(mid 287.83661 -144.300702)
					(end 288.23031 -144.694402)
				)
				(arc
					(start 288.38525 -144.694402)
					(mid 288.224557 -144.306455)
					(end 287.83661 -144.145762)
				)
			)
		)
	)
	(zone
		(layers "F.Cu" "B.Cu" "In2.Cu")
		(hatch none 0.5)
		(connect_pads
			(clearance 0)
		)
		(min_thickness 0.25)
		(keepout
			(tracks not_allowed)
			(vias allowed)
			(pads allowed)
			(copperpour not_allowed)
			(footprints allowed)
		)
		(placement
			(enabled no)
			(sheetname "")
		)
		(fill yes
			(thermal_gap 0.5)
			(thermal_bridge_width 0.5)
			(island_removal_mode 0)
		)
		(polygon
			(pts
				(arc
					(start 285.436564 -193.145918)
					(mid 284.887924 -193.694558)
					(end 285.436564 -194.243198)
				)
				(arc
					(start 286.836612 -194.243198)
					(mid 287.22366 -194.083402)
					(end 287.385252 -193.697098)
				)
				(arc
					(start 287.230312 -193.697098)
					(mid 286.836612 -194.088266)
					(end 286.442912 -193.697098)
				)
				(arc
					(start 285.830264 -193.697098)
					(mid 285.436564 -194.088266)
					(end 285.042864 -193.697098)
				)
				(arc
					(start 285.042864 -193.694558)
					(mid 285.436564 -193.300858)
					(end 285.830264 -193.694558)
				)
				(arc
					(start 286.442912 -193.694558)
					(mid 286.836612 -193.300858)
					(end 287.230312 -193.694558)
				)
				(arc
					(start 287.385252 -193.694558)
					(mid 287.224559 -193.306611)
					(end 286.836612 -193.145918)
				)
			)
		)
	)
	(zone
		(layers "F.Cu" "B.Cu" "In2.Cu")
		(hatch none 0.5)
		(connect_pads
			(clearance 0)
		)
		(min_thickness 0.25)
		(keepout
			(tracks not_allowed)
			(vias allowed)
			(pads allowed)
			(copperpour not_allowed)
			(footprints allowed)
		)
		(placement
			(enabled no)
			(sheetname "")
		)
		(fill yes
			(thermal_gap 0.5)
			(thermal_bridge_width 0.5)
			(island_removal_mode 0)
		)
		(polygon
			(pts
				(arc
					(start 212.348826 -65.600072)
					(mid 211.800186 -65.051432)
					(end 211.251546 -65.600072)
				)
				(arc
					(start 211.251546 -66.999612)
					(mid 211.798789 -67.548504)
					(end 212.348826 -67.002406)
				)
				(arc
					(start 212.193886 -67.002406)
					(mid 211.800186 -67.393574)
					(end 211.406486 -67.002406)
				)
				(arc
					(start 211.406486 -66.999866)
					(mid 211.800186 -66.606166)
					(end 212.193886 -66.999866)
				)
				(xy 212.348826 -66.999866) (xy 212.348826 -65.602612)
				(arc
					(start 212.193886 -65.602612)
					(mid 211.800186 -65.99378)
					(end 211.406486 -65.602612)
				)
				(arc
					(start 211.406486 -65.600072)
					(mid 211.800186 -65.206372)
					(end 212.193886 -65.600072)
				)
			)
		)
	)
	(zone
		(layers "F.Cu" "B.Cu" "In2.Cu")
		(hatch none 0.5)
		(connect_pads
			(clearance 0)
		)
		(min_thickness 0.25)
		(keepout
			(tracks not_allowed)
			(vias allowed)
			(pads allowed)
			(copperpour not_allowed)
			(footprints allowed)
		)
		(placement
			(enabled no)
			(sheetname "")
		)
		(fill yes
			(thermal_gap 0.5)
			(thermal_bridge_width 0.5)
			(island_removal_mode 0)
		)
		(polygon
			(pts
				(arc
					(start 285.436564 -225.545904)
					(mid 284.887924 -226.094544)
					(end 285.436564 -226.643184)
				)
				(arc
					(start 286.836612 -226.643184)
					(mid 287.22366 -226.483388)
					(end 287.385252 -226.097084)
				)
				(arc
					(start 287.230312 -226.097084)
					(mid 286.836612 -226.488252)
					(end 286.442912 -226.097084)
				)
				(arc
					(start 285.830264 -226.097084)
					(mid 285.436564 -226.488252)
					(end 285.042864 -226.097084)
				)
				(arc
					(start 285.042864 -226.094544)
					(mid 285.436564 -225.700844)
					(end 285.830264 -226.094544)
				)
				(arc
					(start 286.442912 -226.094544)
					(mid 286.836612 -225.700844)
					(end 287.230312 -226.094544)
				)
				(arc
					(start 287.385252 -226.094544)
					(mid 287.224559 -225.706597)
					(end 286.836612 -225.545904)
				)
			)
		)
	)
	(zone
		(layers "F.Cu" "B.Cu" "In2.Cu")
		(hatch none 0.5)
		(connect_pads
			(clearance 0)
		)
		(min_thickness 0.25)
		(keepout
			(tracks not_allowed)
			(vias allowed)
			(pads allowed)
			(copperpour not_allowed)
			(footprints allowed)
		)
		(placement
			(enabled no)
			(sheetname "")
		)
		(fill yes
			(thermal_gap 0.5)
			(thermal_bridge_width 0.5)
			(island_removal_mode 0)
		)
		(polygon
			(pts
				(arc
					(start 286.436562 -234.545886)
					(mid 285.887922 -235.094526)
					(end 286.436562 -235.643166)
				)
				(arc
					(start 287.83661 -235.643166)
					(mid 288.223658 -235.48337)
					(end 288.38525 -235.097066)
				)
				(arc
					(start 288.23031 -235.097066)
					(mid 287.83661 -235.488234)
					(end 287.44291 -235.097066)
				)
				(arc
					(start 286.830262 -235.097066)
					(mid 286.436562 -235.488234)
					(end 286.042862 -235.097066)
				)
				(arc
					(start 286.042862 -235.094526)
					(mid 286.436562 -234.700826)
					(end 286.830262 -235.094526)
				)
				(arc
					(start 287.44291 -235.094526)
					(mid 287.83661 -234.700826)
					(end 288.23031 -235.094526)
				)
				(arc
					(start 288.38525 -235.094526)
					(mid 288.224557 -234.706579)
					(end 287.83661 -234.545886)
				)
			)
		)
	)
	(zone
		(layers "F.Cu" "B.Cu" "In2.Cu")
		(hatch none 0.5)
		(connect_pads
			(clearance 0)
		)
		(min_thickness 0.25)
		(keepout
			(tracks not_allowed)
			(vias allowed)
			(pads allowed)
			(copperpour not_allowed)
			(footprints allowed)
		)
		(placement
			(enabled no)
			(sheetname "")
		)
		(fill yes
			(thermal_gap 0.5)
			(thermal_bridge_width 0.5)
			(island_removal_mode 0)
		)
		(polygon
			(pts
				(arc
					(start 285.436564 -218.345766)
					(mid 284.887924 -218.894406)
					(end 285.436564 -219.443046)
				)
				(arc
					(start 286.836612 -219.443046)
					(mid 287.22366 -219.28325)
					(end 287.385252 -218.896946)
				)
				(arc
					(start 287.230312 -218.896946)
					(mid 286.836612 -219.288114)
					(end 286.442912 -218.896946)
				)
				(arc
					(start 285.830264 -218.896946)
					(mid 285.436564 -219.288114)
					(end 285.042864 -218.896946)
				)
				(arc
					(start 285.042864 -218.894406)
					(mid 285.436564 -218.500706)
					(end 285.830264 -218.894406)
				)
				(arc
					(start 286.442912 -218.894406)
					(mid 286.836612 -218.500706)
					(end 287.230312 -218.894406)
				)
				(arc
					(start 287.385252 -218.894406)
					(mid 287.224559 -218.506459)
					(end 286.836612 -218.345766)
				)
			)
		)
	)
	(zone
		(layers "F.Cu" "B.Cu" "In2.Cu")
		(hatch none 0.5)
		(connect_pads
			(clearance 0)
		)
		(min_thickness 0.25)
		(keepout
			(tracks not_allowed)
			(vias allowed)
			(pads allowed)
			(copperpour not_allowed)
			(footprints allowed)
		)
		(placement
			(enabled no)
			(sheetname "")
		)
		(fill yes
			(thermal_gap 0.5)
			(thermal_bridge_width 0.5)
			(island_removal_mode 0)
		)
		(polygon
			(pts
				(arc
					(start 286.436562 -205.745842)
					(mid 285.887922 -206.294482)
					(end 286.436562 -206.843122)
				)
				(arc
					(start 287.83661 -206.843122)
					(mid 288.223658 -206.683326)
					(end 288.38525 -206.297022)
				)
				(arc
					(start 288.23031 -206.297022)
					(mid 287.83661 -206.68819)
					(end 287.44291 -206.297022)
				)
				(arc
					(start 286.830262 -206.297022)
					(mid 286.436562 -206.68819)
					(end 286.042862 -206.297022)
				)
				(arc
					(start 286.042862 -206.294482)
					(mid 286.436562 -205.900782)
					(end 286.830262 -206.294482)
				)
				(arc
					(start 287.44291 -206.294482)
					(mid 287.83661 -205.900782)
					(end 288.23031 -206.294482)
				)
				(arc
					(start 288.38525 -206.294482)
					(mid 288.224557 -205.906535)
					(end 287.83661 -205.745842)
				)
			)
		)
	)
	(zone
		(layers "F.Cu" "B.Cu" "In2.Cu")
		(hatch none 0.5)
		(connect_pads
			(clearance 0)
		)
		(min_thickness 0.25)
		(keepout
			(tracks not_allowed)
			(vias allowed)
			(pads allowed)
			(copperpour not_allowed)
			(footprints allowed)
		)
		(placement
			(enabled no)
			(sheetname "")
		)
		(fill yes
			(thermal_gap 0.5)
			(thermal_bridge_width 0.5)
			(island_removal_mode 0)
		)
		(polygon
			(pts
				(arc
					(start 223.148652 -65.600072)
					(mid 222.600012 -65.051432)
					(end 222.051372 -65.600072)
				)
				(arc
					(start 222.051372 -66.999866)
					(mid 222.598742 -67.548505)
					(end 223.148652 -67.002406)
				)
				(arc
					(start 222.993712 -67.002406)
					(mid 222.600012 -67.393574)
					(end 222.206312 -67.002406)
				)
				(arc
					(start 222.206312 -66.999866)
					(mid 222.600012 -66.606166)
					(end 222.993712 -66.999866)
				)
				(xy 223.148652 -66.999866) (xy 223.148652 -65.602612)
				(arc
					(start 222.993712 -65.602612)
					(mid 222.600012 -65.99378)
					(end 222.206312 -65.602612)
				)
				(arc
					(start 222.206312 -65.600072)
					(mid 222.600012 -65.206372)
					(end 222.993712 -65.600072)
				)
			)
		)
	)
	(zone
		(layers "F.Cu" "B.Cu" "In2.Cu")
		(hatch none 0.5)
		(connect_pads
			(clearance 0)
		)
		(min_thickness 0.25)
		(keepout
			(tracks not_allowed)
			(vias allowed)
			(pads allowed)
			(copperpour not_allowed)
			(footprints allowed)
		)
		(placement
			(enabled no)
			(sheetname "")
		)
		(fill yes
			(thermal_gap 0.5)
			(thermal_bridge_width 0.5)
			(island_removal_mode 0)
		)
		(polygon
			(pts
				(arc
					(start 214.14867 -70.39991)
					(mid 213.60003 -69.85127)
					(end 213.05139 -70.39991)
				)
				(arc
					(start 213.05139 -71.799704)
					(mid 213.598633 -72.348596)
					(end 214.14867 -71.802498)
				)
				(arc
					(start 213.99373 -71.802498)
					(mid 213.60003 -72.193666)
					(end 213.20633 -71.802498)
				)
				(arc
					(start 213.20633 -71.799958)
					(mid 213.60003 -71.406258)
					(end 213.99373 -71.799958)
				)
				(xy 214.14867 -71.799958) (xy 214.14867 -70.40245)
				(arc
					(start 213.99373 -70.40245)
					(mid 213.60003 -70.793618)
					(end 213.20633 -70.40245)
				)
				(arc
					(start 213.20633 -70.39991)
					(mid 213.60003 -70.00621)
					(end 213.99373 -70.39991)
				)
			)
		)
	)
	(zone
		(layers "F.Cu" "B.Cu" "In2.Cu")
		(hatch none 0.5)
		(connect_pads
			(clearance 0)
		)
		(min_thickness 0.25)
		(keepout
			(tracks not_allowed)
			(vias allowed)
			(pads allowed)
			(copperpour not_allowed)
			(footprints allowed)
		)
		(placement
			(enabled no)
			(sheetname "")
		)
		(fill yes
			(thermal_gap 0.5)
			(thermal_bridge_width 0.5)
			(island_removal_mode 0)
		)
		(polygon
			(pts
				(arc
					(start 286.436562 -209.345784)
					(mid 285.887922 -209.894424)
					(end 286.436562 -210.443064)
				)
				(arc
					(start 287.83661 -210.443064)
					(mid 288.223658 -210.283268)
					(end 288.38525 -209.896964)
				)
				(arc
					(start 288.23031 -209.896964)
					(mid 287.83661 -210.288132)
					(end 287.44291 -209.896964)
				)
				(arc
					(start 286.830262 -209.896964)
					(mid 286.436562 -210.288132)
					(end 286.042862 -209.896964)
				)
				(arc
					(start 286.042862 -209.894424)
					(mid 286.436562 -209.500724)
					(end 286.830262 -209.894424)
				)
				(arc
					(start 287.44291 -209.894424)
					(mid 287.83661 -209.500724)
					(end 288.23031 -209.894424)
				)
				(arc
					(start 288.38525 -209.894424)
					(mid 288.224557 -209.506477)
					(end 287.83661 -209.345784)
				)
			)
		)
	)
	(zone
		(layers "F.Cu" "B.Cu" "In2.Cu")
		(hatch none 0.5)
		(connect_pads
			(clearance 0)
		)
		(min_thickness 0.25)
		(keepout
			(tracks not_allowed)
			(vias allowed)
			(pads allowed)
			(copperpour not_allowed)
			(footprints allowed)
		)
		(placement
			(enabled no)
			(sheetname "")
		)
		(fill yes
			(thermal_gap 0.5)
			(thermal_bridge_width 0.5)
			(island_removal_mode 0)
		)
		(polygon
			(pts
				(arc
					(start 286.436562 -220.145864)
					(mid 285.887922 -220.694504)
					(end 286.436562 -221.243144)
				)
				(arc
					(start 287.83661 -221.243144)
					(mid 288.223658 -221.083348)
					(end 288.38525 -220.697044)
				)
				(arc
					(start 288.23031 -220.697044)
					(mid 287.83661 -221.088212)
					(end 287.44291 -220.697044)
				)
				(arc
					(start 286.830262 -220.697044)
					(mid 286.436562 -221.088212)
					(end 286.042862 -220.697044)
				)
				(arc
					(start 286.042862 -220.694504)
					(mid 286.436562 -220.300804)
					(end 286.830262 -220.694504)
				)
				(arc
					(start 287.44291 -220.694504)
					(mid 287.83661 -220.300804)
					(end 288.23031 -220.694504)
				)
				(arc
					(start 288.38525 -220.694504)
					(mid 288.224557 -220.306557)
					(end 287.83661 -220.145864)
				)
			)
		)
	)
	(zone
		(layers "F.Cu" "B.Cu" "In2.Cu")
		(hatch none 0.5)
		(connect_pads
			(clearance 0)
		)
		(min_thickness 0.25)
		(keepout
			(tracks not_allowed)
			(vias allowed)
			(pads allowed)
			(copperpour not_allowed)
			(footprints allowed)
		)
		(placement
			(enabled no)
			(sheetname "")
		)
		(fill yes
			(thermal_gap 0.5)
			(thermal_bridge_width 0.5)
			(island_removal_mode 0)
		)
		(polygon
			(pts
				(arc
					(start 286.436562 -133.345682)
					(mid 285.887922 -133.894322)
					(end 286.436562 -134.442962)
				)
				(arc
					(start 287.83661 -134.442962)
					(mid 288.223658 -134.283166)
					(end 288.38525 -133.896862)
				)
				(arc
					(start 288.23031 -133.896862)
					(mid 287.83661 -134.28803)
					(end 287.44291 -133.896862)
				)
				(arc
					(start 286.830262 -133.896862)
					(mid 286.436562 -134.28803)
					(end 286.042862 -133.896862)
				)
				(arc
					(start 286.042862 -133.894322)
					(mid 286.436562 -133.500622)
					(end 286.830262 -133.894322)
				)
				(arc
					(start 287.44291 -133.894322)
					(mid 287.83661 -133.500622)
					(end 288.23031 -133.894322)
				)
				(arc
					(start 288.38525 -133.894322)
					(mid 288.224557 -133.506375)
					(end 287.83661 -133.345682)
				)
			)
		)
	)
	(zone
		(layers "F.Cu" "B.Cu" "In2.Cu")
		(hatch none 0.5)
		(connect_pads
			(clearance 0)
		)
		(min_thickness 0.25)
		(keepout
			(tracks not_allowed)
			(vias allowed)
			(pads allowed)
			(copperpour not_allowed)
			(footprints allowed)
		)
		(placement
			(enabled no)
			(sheetname "")
		)
		(fill yes
			(thermal_gap 0.5)
			(thermal_bridge_width 0.5)
			(island_removal_mode 0)
		)
		(polygon
			(pts
				(arc
					(start 286.436562 -227.345748)
					(mid 285.887922 -227.894388)
					(end 286.436562 -228.443028)
				)
				(arc
					(start 287.83661 -228.443028)
					(mid 288.223658 -228.283232)
					(end 288.38525 -227.896928)
				)
				(arc
					(start 288.23031 -227.896928)
					(mid 287.83661 -228.288096)
					(end 287.44291 -227.896928)
				)
				(arc
					(start 286.830262 -227.896928)
					(mid 286.436562 -228.288096)
					(end 286.042862 -227.896928)
				)
				(arc
					(start 286.042862 -227.894388)
					(mid 286.436562 -227.500688)
					(end 286.830262 -227.894388)
				)
				(arc
					(start 287.44291 -227.894388)
					(mid 287.83661 -227.500688)
					(end 288.23031 -227.894388)
				)
				(arc
					(start 288.38525 -227.894388)
					(mid 288.224557 -227.506441)
					(end 287.83661 -227.345748)
				)
			)
		)
	)
	(zone
		(layers "F.Cu" "B.Cu" "In2.Cu")
		(hatch none 0.5)
		(connect_pads
			(clearance 0)
		)
		(min_thickness 0.25)
		(keepout
			(tracks not_allowed)
			(vias allowed)
			(pads allowed)
			(copperpour not_allowed)
			(footprints allowed)
		)
		(placement
			(enabled no)
			(sheetname "")
		)
		(fill yes
			(thermal_gap 0.5)
			(thermal_bridge_width 0.5)
			(island_removal_mode 0)
		)
		(polygon
			(pts
				(arc
					(start 285.436564 -236.34573)
					(mid 284.887924 -236.89437)
					(end 285.436564 -237.44301)
				)
				(arc
					(start 286.836612 -237.44301)
					(mid 287.22366 -237.283214)
					(end 287.385252 -236.89691)
				)
				(arc
					(start 287.230312 -236.89691)
					(mid 286.836612 -237.288078)
					(end 286.442912 -236.89691)
				)
				(arc
					(start 285.830264 -236.89691)
					(mid 285.436564 -237.288078)
					(end 285.042864 -236.89691)
				)
				(arc
					(start 285.042864 -236.89437)
					(mid 285.436564 -236.50067)
					(end 285.830264 -236.89437)
				)
				(arc
					(start 286.442912 -236.89437)
					(mid 286.836612 -236.50067)
					(end 287.230312 -236.89437)
				)
				(arc
					(start 287.385252 -236.89437)
					(mid 287.224559 -236.506423)
					(end 286.836612 -236.34573)
				)
			)
		)
	)
	(zone
		(layers "F.Cu" "B.Cu" "In2.Cu")
		(hatch none 0.5)
		(connect_pads
			(clearance 0)
		)
		(min_thickness 0.25)
		(keepout
			(tracks not_allowed)
			(vias allowed)
			(pads allowed)
			(copperpour not_allowed)
			(footprints allowed)
		)
		(placement
			(enabled no)
			(sheetname "")
		)
		(fill yes
			(thermal_gap 0.5)
			(thermal_bridge_width 0.5)
			(island_removal_mode 0)
		)
		(polygon
			(pts
				(arc
					(start 285.436564 -196.74586)
					(mid 284.887924 -197.2945)
					(end 285.436564 -197.84314)
				)
				(arc
					(start 286.836612 -197.84314)
					(mid 287.22366 -197.683344)
					(end 287.385252 -197.29704)
				)
				(arc
					(start 287.230312 -197.29704)
					(mid 286.836612 -197.688208)
					(end 286.442912 -197.29704)
				)
				(arc
					(start 285.830264 -197.29704)
					(mid 285.436564 -197.688208)
					(end 285.042864 -197.29704)
				)
				(arc
					(start 285.042864 -197.2945)
					(mid 285.436564 -196.9008)
					(end 285.830264 -197.2945)
				)
				(arc
					(start 286.442912 -197.2945)
					(mid 286.836612 -196.9008)
					(end 287.230312 -197.2945)
				)
				(arc
					(start 287.385252 -197.2945)
					(mid 287.224559 -196.906553)
					(end 286.836612 -196.74586)
				)
			)
		)
	)
	(zone
		(layers "F.Cu" "B.Cu" "In2.Cu")
		(hatch none 0.5)
		(connect_pads
			(clearance 0)
		)
		(min_thickness 0.25)
		(keepout
			(tracks not_allowed)
			(vias allowed)
			(pads allowed)
			(copperpour not_allowed)
			(footprints allowed)
		)
		(placement
			(enabled no)
			(sheetname "")
		)
		(fill yes
			(thermal_gap 0.5)
			(thermal_bridge_width 0.5)
			(island_removal_mode 0)
		)
		(polygon
			(pts
				(arc
					(start 286.436562 -216.545922)
					(mid 285.887922 -217.094562)
					(end 286.436562 -217.643202)
				)
				(arc
					(start 287.83661 -217.643202)
					(mid 288.223658 -217.483406)
					(end 288.38525 -217.097102)
				)
				(arc
					(start 288.23031 -217.097102)
					(mid 287.83661 -217.48827)
					(end 287.44291 -217.097102)
				)
				(arc
					(start 286.830262 -217.097102)
					(mid 286.436562 -217.48827)
					(end 286.042862 -217.097102)
				)
				(arc
					(start 286.042862 -217.094562)
					(mid 286.436562 -216.700862)
					(end 286.830262 -217.094562)
				)
				(arc
					(start 287.44291 -217.094562)
					(mid 287.83661 -216.700862)
					(end 288.23031 -217.094562)
				)
				(arc
					(start 288.38525 -217.094562)
					(mid 288.224557 -216.706615)
					(end 287.83661 -216.545922)
				)
			)
		)
	)
	(zone
		(layers "F.Cu" "B.Cu" "In2.Cu")
		(hatch none 0.5)
		(connect_pads
			(clearance 0)
		)
		(min_thickness 0.25)
		(keepout
			(tracks not_allowed)
			(vias allowed)
			(pads allowed)
			(copperpour not_allowed)
			(footprints allowed)
		)
		(placement
			(enabled no)
			(sheetname "")
		)
		(fill yes
			(thermal_gap 0.5)
			(thermal_bridge_width 0.5)
			(island_removal_mode 0)
		)
		(polygon
			(pts
				(arc
					(start 221.348808 -70.39991)
					(mid 220.800168 -69.85127)
					(end 220.251528 -70.39991)
				)
				(arc
					(start 220.251528 -71.799704)
					(mid 220.798771 -72.348596)
					(end 221.348808 -71.802498)
				)
				(arc
					(start 221.193868 -71.802498)
					(mid 220.800168 -72.193666)
					(end 220.406468 -71.802498)
				)
				(arc
					(start 220.406468 -71.799958)
					(mid 220.800168 -71.406258)
					(end 221.193868 -71.799958)
				)
				(xy 221.348808 -71.799958) (xy 221.348808 -70.40245)
				(arc
					(start 221.193868 -70.40245)
					(mid 220.800168 -70.793618)
					(end 220.406468 -70.40245)
				)
				(arc
					(start 220.406468 -70.39991)
					(mid 220.800168 -70.00621)
					(end 221.193868 -70.39991)
				)
			)
		)
	)
	(zone
		(layers "F.Cu" "B.Cu" "In2.Cu")
		(hatch none 0.5)
		(connect_pads
			(clearance 0)
		)
		(min_thickness 0.25)
		(keepout
			(tracks not_allowed)
			(vias allowed)
			(pads allowed)
			(copperpour not_allowed)
			(footprints allowed)
		)
		(placement
			(enabled no)
			(sheetname "")
		)
		(fill yes
			(thermal_gap 0.5)
			(thermal_bridge_width 0.5)
			(island_removal_mode 0)
		)
		(polygon
			(pts
				(arc
					(start 219.54871 -65.600072)
					(mid 219.00007 -65.051432)
					(end 218.45143 -65.600072)
				)
				(arc
					(start 218.45143 -66.999612)
					(mid 218.998673 -67.548504)
					(end 219.54871 -67.002406)
				)
				(arc
					(start 219.39377 -67.002406)
					(mid 219.00007 -67.393574)
					(end 218.60637 -67.002406)
				)
				(arc
					(start 218.60637 -66.999866)
					(mid 219.00007 -66.606166)
					(end 219.39377 -66.999866)
				)
				(xy 219.54871 -66.999866) (xy 219.54871 -65.602612)
				(arc
					(start 219.39377 -65.602612)
					(mid 219.00007 -65.99378)
					(end 218.60637 -65.602612)
				)
				(arc
					(start 218.60637 -65.600072)
					(mid 219.00007 -65.206372)
					(end 219.39377 -65.600072)
				)
			)
		)
	)
	(zone
		(layers "F.Cu" "B.Cu" "In2.Cu")
		(hatch none 0.5)
		(connect_pads
			(clearance 0)
		)
		(min_thickness 0.25)
		(keepout
			(tracks not_allowed)
			(vias allowed)
			(pads allowed)
			(copperpour not_allowed)
			(footprints allowed)
		)
		(placement
			(enabled no)
			(sheetname "")
		)
		(fill yes
			(thermal_gap 0.5)
			(thermal_bridge_width 0.5)
			(island_removal_mode 0)
		)
		(polygon
			(pts
				(arc
					(start 286.436562 -194.945762)
					(mid 285.887922 -195.494402)
					(end 286.436562 -196.043042)
				)
				(arc
					(start 287.83661 -196.043042)
					(mid 288.223658 -195.883246)
					(end 288.38525 -195.496942)
				)
				(arc
					(start 288.23031 -195.496942)
					(mid 287.83661 -195.88811)
					(end 287.44291 -195.496942)
				)
				(arc
					(start 286.830262 -195.496942)
					(mid 286.436562 -195.88811)
					(end 286.042862 -195.496942)
				)
				(arc
					(start 286.042862 -195.494402)
					(mid 286.436562 -195.100702)
					(end 286.830262 -195.494402)
				)
				(arc
					(start 287.44291 -195.494402)
					(mid 287.83661 -195.100702)
					(end 288.23031 -195.494402)
				)
				(arc
					(start 288.38525 -195.494402)
					(mid 288.224557 -195.106455)
					(end 287.83661 -194.945762)
				)
			)
		)
	)
	(zone
		(layers "F.Cu" "B.Cu" "In2.Cu")
		(hatch none 0.5)
		(connect_pads
			(clearance 0)
		)
		(min_thickness 0.25)
		(keepout
			(tracks not_allowed)
			(vias allowed)
			(pads allowed)
			(copperpour not_allowed)
			(footprints allowed)
		)
		(placement
			(enabled no)
			(sheetname "")
		)
		(fill yes
			(thermal_gap 0.5)
			(thermal_bridge_width 0.5)
			(island_removal_mode 0)
		)
		(polygon
			(pts
				(arc
					(start 286.436562 -191.34582)
					(mid 285.887922 -191.89446)
					(end 286.436562 -192.4431)
				)
				(arc
					(start 287.83661 -192.4431)
					(mid 288.223658 -192.283304)
					(end 288.38525 -191.897)
				)
				(arc
					(start 288.23031 -191.897)
					(mid 287.83661 -192.288168)
					(end 287.44291 -191.897)
				)
				(arc
					(start 286.830262 -191.897)
					(mid 286.436562 -192.288168)
					(end 286.042862 -191.897)
				)
				(arc
					(start 286.042862 -191.89446)
					(mid 286.436562 -191.50076)
					(end 286.830262 -191.89446)
				)
				(arc
					(start 287.44291 -191.89446)
					(mid 287.83661 -191.50076)
					(end 288.23031 -191.89446)
				)
				(arc
					(start 288.38525 -191.89446)
					(mid 288.224557 -191.506513)
					(end 287.83661 -191.34582)
				)
			)
		)
	)
	(zone
		(layers "F.Cu" "B.Cu" "In2.Cu")
		(hatch none 0.5)
		(connect_pads
			(clearance 0)
		)
		(min_thickness 0.25)
		(keepout
			(tracks not_allowed)
			(vias allowed)
			(pads allowed)
			(copperpour not_allowed)
			(footprints allowed)
		)
		(placement
			(enabled no)
			(sheetname "")
		)
		(fill yes
			(thermal_gap 0.5)
			(thermal_bridge_width 0.5)
			(island_removal_mode 0)
		)
		(polygon
			(pts
				(arc
					(start 286.436562 -223.682306)
					(mid 285.824422 -224.294446)
					(end 286.436562 -224.906586)
				)
				(arc
					(start 287.83661 -224.906586)
					(mid 288.268559 -224.728191)
					(end 288.44875 -224.296986)
				)
				(arc
					(start 288.23031 -224.296986)
					(mid 287.83661 -224.688154)
					(end 287.44291 -224.296986)
				)
				(arc
					(start 286.830262 -224.296986)
					(mid 286.436562 -224.688154)
					(end 286.042862 -224.296986)
				)
				(arc
					(start 286.042862 -224.294446)
					(mid 286.436562 -223.900746)
					(end 286.830262 -224.294446)
				)
				(arc
					(start 287.44291 -224.294446)
					(mid 287.83661 -223.900746)
					(end 288.23031 -224.294446)
				)
				(arc
					(start 288.44875 -224.294446)
					(mid 288.269458 -223.861598)
					(end 287.83661 -223.682306)
				)
				(xy 286.436816 -223.682306)
			)
		)
	)
	(zone
		(layers "F.Cu" "B.Cu" "In2.Cu")
		(hatch none 0.5)
		(connect_pads
			(clearance 0)
		)
		(min_thickness 0.25)
		(keepout
			(tracks not_allowed)
			(vias allowed)
			(pads allowed)
			(copperpour not_allowed)
			(footprints allowed)
		)
		(placement
			(enabled no)
			(sheetname "")
		)
		(fill yes
			(thermal_gap 0.5)
			(thermal_bridge_width 0.5)
			(island_removal_mode 0)
		)
		(polygon
			(pts
				(arc
					(start 285.436564 -131.545838)
					(mid 284.887924 -132.094478)
					(end 285.436564 -132.643118)
				)
				(arc
					(start 286.836612 -132.643118)
					(mid 287.22366 -132.483322)
					(end 287.385252 -132.097018)
				)
				(arc
					(start 287.230312 -132.097018)
					(mid 286.836612 -132.488186)
					(end 286.442912 -132.097018)
				)
				(arc
					(start 285.830264 -132.097018)
					(mid 285.436564 -132.488186)
					(end 285.042864 -132.097018)
				)
				(arc
					(start 285.042864 -132.094478)
					(mid 285.436564 -131.700778)
					(end 285.830264 -132.094478)
				)
				(arc
					(start 286.442912 -132.094478)
					(mid 286.836612 -131.700778)
					(end 287.230312 -132.094478)
				)
				(arc
					(start 287.385252 -132.094478)
					(mid 287.224559 -131.706531)
					(end 286.836612 -131.545838)
				)
			)
		)
	)
	(zone
		(layers "F.Cu" "B.Cu" "In2.Cu")
		(hatch none 0.5)
		(connect_pads
			(clearance 0)
		)
		(min_thickness 0.25)
		(keepout
			(tracks not_allowed)
			(vias allowed)
			(pads allowed)
			(copperpour not_allowed)
			(footprints allowed)
		)
		(placement
			(enabled no)
			(sheetname "")
		)
		(fill yes
			(thermal_gap 0.5)
			(thermal_bridge_width 0.5)
			(island_removal_mode 0)
		)
		(polygon
			(pts
				(arc
					(start 285.436564 -221.945708)
					(mid 284.887924 -222.494348)
					(end 285.436564 -223.042988)
				)
				(arc
					(start 286.836612 -223.042988)
					(mid 287.22366 -222.883192)
					(end 287.385252 -222.496888)
				)
				(arc
					(start 287.230312 -222.496888)
					(mid 286.836612 -222.888056)
					(end 286.442912 -222.496888)
				)
				(arc
					(start 285.830264 -222.496888)
					(mid 285.436564 -222.888056)
					(end 285.042864 -222.496888)
				)
				(arc
					(start 285.042864 -222.494348)
					(mid 285.436564 -222.100648)
					(end 285.830264 -222.494348)
				)
				(arc
					(start 286.442912 -222.494348)
					(mid 286.836612 -222.100648)
					(end 287.230312 -222.494348)
				)
				(arc
					(start 287.385252 -222.494348)
					(mid 287.224559 -222.106401)
					(end 286.836612 -221.945708)
				)
			)
		)
	)
	(zone
		(layers "F.Cu" "B.Cu" "In2.Cu")
		(hatch none 0.5)
		(connect_pads
			(clearance 0)
		)
		(min_thickness 0.25)
		(keepout
			(tracks not_allowed)
			(vias allowed)
			(pads allowed)
			(copperpour not_allowed)
			(footprints allowed)
		)
		(placement
			(enabled no)
			(sheetname "")
		)
		(fill yes
			(thermal_gap 0.5)
			(thermal_bridge_width 0.5)
			(island_removal_mode 0)
		)
		(polygon
			(pts
				(arc
					(start 210.548728 -70.39991)
					(mid 210.000088 -69.85127)
					(end 209.451448 -70.39991)
				)
				(arc
					(start 209.451448 -71.799704)
					(mid 209.998691 -72.348596)
					(end 210.548728 -71.802498)
				)
				(arc
					(start 210.393788 -71.802498)
					(mid 210.000088 -72.193666)
					(end 209.606388 -71.802498)
				)
				(arc
					(start 209.606388 -71.799958)
					(mid 210.000088 -71.406258)
					(end 210.393788 -71.799958)
				)
				(xy 210.548728 -71.799958) (xy 210.548728 -70.40245)
				(arc
					(start 210.393788 -70.40245)
					(mid 210.000088 -70.793618)
					(end 209.606388 -70.40245)
				)
				(arc
					(start 209.606388 -70.39991)
					(mid 210.000088 -70.00621)
					(end 210.393788 -70.39991)
				)
			)
		)
	)
	(zone
		(layers "F.Cu" "B.Cu" "In2.Cu")
		(hatch none 0.5)
		(connect_pads
			(clearance 0)
		)
		(min_thickness 0.25)
		(keepout
			(tracks not_allowed)
			(vias allowed)
			(pads allowed)
			(copperpour not_allowed)
			(footprints allowed)
		)
		(placement
			(enabled no)
			(sheetname "")
		)
		(fill yes
			(thermal_gap 0.5)
			(thermal_bridge_width 0.5)
			(island_removal_mode 0)
		)
		(polygon
			(pts
				(arc
					(start 286.436562 -202.1459)
					(mid 285.887922 -202.69454)
					(end 286.436562 -203.24318)
				)
				(arc
					(start 287.83661 -203.24318)
					(mid 288.223658 -203.083384)
					(end 288.38525 -202.69708)
				)
				(arc
					(start 288.23031 -202.69708)
					(mid 287.83661 -203.088248)
					(end 287.44291 -202.69708)
				)
				(arc
					(start 286.830262 -202.69708)
					(mid 286.436562 -203.088248)
					(end 286.042862 -202.69708)
				)
				(arc
					(start 286.042862 -202.69454)
					(mid 286.436562 -202.30084)
					(end 286.830262 -202.69454)
				)
				(arc
					(start 287.44291 -202.69454)
					(mid 287.83661 -202.30084)
					(end 288.23031 -202.69454)
				)
				(arc
					(start 288.38525 -202.69454)
					(mid 288.224557 -202.306593)
					(end 287.83661 -202.1459)
				)
			)
		)
	)
	(zone
		(layers "F.Cu" "B.Cu" "In2.Cu")
		(hatch none 0.5)
		(connect_pads
			(clearance 0)
		)
		(min_thickness 0.25)
		(keepout
			(tracks not_allowed)
			(vias allowed)
			(pads allowed)
			(copperpour not_allowed)
			(footprints allowed)
		)
		(placement
			(enabled no)
			(sheetname "")
		)
		(fill yes
			(thermal_gap 0.5)
			(thermal_bridge_width 0.5)
			(island_removal_mode 0)
		)
		(polygon
			(pts
				(arc
					(start 285.436564 -138.745722)
					(mid 284.887924 -139.294362)
					(end 285.436564 -139.843002)
				)
				(arc
					(start 286.836612 -139.843002)
					(mid 287.22366 -139.683206)
					(end 287.385252 -139.296902)
				)
				(arc
					(start 287.230312 -139.296902)
					(mid 286.836612 -139.68807)
					(end 286.442912 -139.296902)
				)
				(arc
					(start 285.830264 -139.296902)
					(mid 285.436564 -139.68807)
					(end 285.042864 -139.296902)
				)
				(arc
					(start 285.042864 -139.294362)
					(mid 285.436564 -138.900662)
					(end 285.830264 -139.294362)
				)
				(arc
					(start 286.442912 -139.294362)
					(mid 286.836612 -138.900662)
					(end 287.230312 -139.294362)
				)
				(arc
					(start 287.385252 -139.294362)
					(mid 287.224559 -138.906415)
					(end 286.836612 -138.745722)
				)
			)
		)
	)
	(zone
		(layers "F.Cu" "B.Cu" "In2.Cu")
		(hatch none 0.5)
		(connect_pads
			(clearance 0)
		)
		(min_thickness 0.25)
		(keepout
			(tracks not_allowed)
			(vias allowed)
			(pads allowed)
			(copperpour not_allowed)
			(footprints allowed)
		)
		(placement
			(enabled no)
			(sheetname "")
		)
		(fill yes
			(thermal_gap 0.5)
			(thermal_bridge_width 0.5)
			(island_removal_mode 0)
		)
		(polygon
			(pts
				(arc
					(start 285.436564 -135.14578)
					(mid 284.887924 -135.69442)
					(end 285.436564 -136.24306)
				)
				(arc
					(start 286.836612 -136.24306)
					(mid 287.22366 -136.083264)
					(end 287.385252 -135.69696)
				)
				(arc
					(start 287.230312 -135.69696)
					(mid 286.836612 -136.088128)
					(end 286.442912 -135.69696)
				)
				(arc
					(start 285.830264 -135.69696)
					(mid 285.436564 -136.088128)
					(end 285.042864 -135.69696)
				)
				(arc
					(start 285.042864 -135.69442)
					(mid 285.436564 -135.30072)
					(end 285.830264 -135.69442)
				)
				(arc
					(start 286.442912 -135.69442)
					(mid 286.836612 -135.30072)
					(end 287.230312 -135.69442)
				)
				(arc
					(start 287.385252 -135.69442)
					(mid 287.224559 -135.306473)
					(end 286.836612 -135.14578)
				)
			)
		)
	)
	(zone
		(layers "F.Cu" "B.Cu" "In2.Cu")
		(hatch none 0.5)
		(connect_pads
			(clearance 0)
		)
		(min_thickness 0.25)
		(keepout
			(tracks not_allowed)
			(vias allowed)
			(pads allowed)
			(copperpour not_allowed)
			(footprints allowed)
		)
		(placement
			(enabled no)
			(sheetname "")
		)
		(fill yes
			(thermal_gap 0.5)
			(thermal_bridge_width 0.5)
			(island_removal_mode 0)
		)
		(polygon
			(pts
				(arc
					(start 215.948768 -65.600072)
					(mid 215.400128 -65.051432)
					(end 214.851488 -65.600072)
				)
				(arc
					(start 214.851488 -66.999612)
					(mid 215.398731 -67.548504)
					(end 215.948768 -67.002406)
				)
				(arc
					(start 215.793828 -67.002406)
					(mid 215.400128 -67.393574)
					(end 215.006428 -67.002406)
				)
				(arc
					(start 215.006428 -66.999866)
					(mid 215.400128 -66.606166)
					(end 215.793828 -66.999866)
				)
				(xy 215.948768 -66.999866) (xy 215.948768 -65.602612)
				(arc
					(start 215.793828 -65.602612)
					(mid 215.400128 -65.99378)
					(end 215.006428 -65.602612)
				)
				(arc
					(start 215.006428 -65.600072)
					(mid 215.400128 -65.206372)
					(end 215.793828 -65.600072)
				)
			)
		)
	)
	(zone
		(layers "F.Cu" "B.Cu" "In2.Cu")
		(hatch none 0.5)
		(connect_pads
			(clearance 0)
		)
		(min_thickness 0.25)
		(keepout
			(tracks not_allowed)
			(vias allowed)
			(pads allowed)
			(copperpour not_allowed)
			(footprints allowed)
		)
		(placement
			(enabled no)
			(sheetname "")
		)
		(fill yes
			(thermal_gap 0.5)
			(thermal_bridge_width 0.5)
			(island_removal_mode 0)
		)
		(polygon
			(pts
				(arc
					(start 285.436564 -185.94578)
					(mid 284.887924 -186.49442)
					(end 285.436564 -187.04306)
				)
				(arc
					(start 286.836612 -187.04306)
					(mid 287.22366 -186.883264)
					(end 287.385252 -186.49696)
				)
				(arc
					(start 287.230312 -186.49696)
					(mid 286.836612 -186.888128)
					(end 286.442912 -186.49696)
				)
				(arc
					(start 285.830264 -186.49696)
					(mid 285.436564 -186.888128)
					(end 285.042864 -186.49696)
				)
				(arc
					(start 285.042864 -186.49442)
					(mid 285.436564 -186.10072)
					(end 285.830264 -186.49442)
				)
				(arc
					(start 286.442912 -186.49442)
					(mid 286.836612 -186.10072)
					(end 287.230312 -186.49442)
				)
				(arc
					(start 287.385252 -186.49442)
					(mid 287.224559 -186.106473)
					(end 286.836612 -185.94578)
				)
			)
		)
	)
	(zone
		(layers "F.Cu" "B.Cu" "In2.Cu")
		(hatch none 0.5)
		(connect_pads
			(clearance 0)
		)
		(min_thickness 0.25)
		(keepout
			(tracks not_allowed)
			(vias allowed)
			(pads allowed)
			(copperpour not_allowed)
			(footprints allowed)
		)
		(placement
			(enabled no)
			(sheetname "")
		)
		(fill yes
			(thermal_gap 0.5)
			(thermal_bridge_width 0.5)
			(island_removal_mode 0)
		)
		(polygon
			(pts
				(arc
					(start 285.436564 -142.345664)
					(mid 284.887924 -142.894304)
					(end 285.436564 -143.442944)
				)
				(arc
					(start 286.836612 -143.442944)
					(mid 287.22366 -143.283148)
					(end 287.385252 -142.896844)
				)
				(arc
					(start 287.230312 -142.896844)
					(mid 286.836612 -143.288012)
					(end 286.442912 -142.896844)
				)
				(arc
					(start 285.830264 -142.896844)
					(mid 285.436564 -143.288012)
					(end 285.042864 -142.896844)
				)
				(arc
					(start 285.042864 -142.894304)
					(mid 285.436564 -142.500604)
					(end 285.830264 -142.894304)
				)
				(arc
					(start 286.442912 -142.894304)
					(mid 286.836612 -142.500604)
					(end 287.230312 -142.894304)
				)
				(arc
					(start 287.385252 -142.894304)
					(mid 287.224559 -142.506357)
					(end 286.836612 -142.345664)
				)
			)
		)
	)
	(zone
		(layers "F.Cu" "B.Cu" "In2.Cu")
		(hatch none 0.5)
		(connect_pads
			(clearance 0)
		)
		(min_thickness 0.25)
		(keepout
			(tracks not_allowed)
			(vias allowed)
			(pads allowed)
			(copperpour not_allowed)
			(footprints allowed)
		)
		(placement
			(enabled no)
			(sheetname "")
		)
		(fill yes
			(thermal_gap 0.5)
			(thermal_bridge_width 0.5)
			(island_removal_mode 0)
		)
		(polygon
			(pts
				(arc
					(start 217.748612 -70.39991)
					(mid 217.199972 -69.85127)
					(end 216.651332 -70.39991)
				)
				(arc
					(start 216.651332 -71.799704)
					(mid 217.198575 -72.348596)
					(end 217.748612 -71.802498)
				)
				(arc
					(start 217.593672 -71.802498)
					(mid 217.199972 -72.193666)
					(end 216.806272 -71.802498)
				)
				(arc
					(start 216.806272 -71.799958)
					(mid 217.199972 -71.406258)
					(end 217.593672 -71.799958)
				)
				(xy 217.748612 -71.799958) (xy 217.748612 -70.40245)
				(arc
					(start 217.593672 -70.40245)
					(mid 217.199972 -70.793618)
					(end 216.806272 -70.40245)
				)
				(arc
					(start 216.806272 -70.39991)
					(mid 217.199972 -70.00621)
					(end 217.593672 -70.39991)
				)
			)
		)
	)
	(zone
		(layers "F.Cu" "B.Cu" "In2.Cu" "In5.Cu")
		(hatch none 0.5)
		(connect_pads
			(clearance 0)
		)
		(min_thickness 0.25)
		(keepout
			(tracks not_allowed)
			(vias allowed)
			(pads allowed)
			(copperpour not_allowed)
			(footprints allowed)
		)
		(placement
			(enabled no)
			(sheetname "")
		)
		(fill yes
			(thermal_gap 0.5)
			(thermal_bridge_width 0.5)
			(island_removal_mode 0)
		)
		(polygon
			(pts
				(arc
					(start 307.327046 -244.00002)
					(mid 300.20006 -236.873034)
					(end 293.073074 -244.00002)
				)
				(arc
					(start 293.073074 -250.000008)
					(mid 300.20006 -257.126994)
					(end 307.327046 -250.000008)
				)
			)
		)
	)
	(zone
		(layers "F.Cu" "B.Cu" "In2.Cu" "In5.Cu")
		(hatch none 0.5)
		(connect_pads
			(clearance 0)
		)
		(min_thickness 0.25)
		(keepout
			(tracks not_allowed)
			(vias allowed)
			(pads allowed)
			(copperpour not_allowed)
			(footprints allowed)
		)
		(placement
			(enabled no)
			(sheetname "")
		)
		(fill yes
			(thermal_gap 0.5)
			(thermal_bridge_width 0.5)
			(island_removal_mode 0)
		)
		(polygon
			(pts
				(arc
					(start 182.67299 -100.000054)
					(mid 189.799976 -107.12704)
					(end 196.926962 -100.000054)
				)
				(arc
					(start 196.926962 -93.999812)
					(mid 189.799976 -86.87308)
					(end 182.67299 -93.999812)
				)
			)
		)
	)
	(zone
		(layers "F.Cu" "B.Cu" "In2.Cu" "In5.Cu")
		(hatch none 0.5)
		(connect_pads
			(clearance 0)
		)
		(min_thickness 0.25)
		(keepout
			(tracks not_allowed)
			(vias allowed)
			(pads allowed)
			(copperpour not_allowed)
			(footprints allowed)
		)
		(placement
			(enabled no)
			(sheetname "")
		)
		(fill yes
			(thermal_gap 0.5)
			(thermal_bridge_width 0.5)
			(island_removal_mode 0)
		)
		(polygon
			(pts
				(arc
					(start 182.67299 -210.000088)
					(mid 189.799976 -217.127074)
					(end 196.926962 -210.000088)
				)
				(arc
					(start 196.926962 -203.999846)
					(mid 189.799976 -196.873114)
					(end 182.67299 -203.999846)
				)
			)
		)
	)
	(zone
		(layers "F.Cu" "B.Cu" "In2.Cu" "In5.Cu")
		(hatch none 0.5)
		(connect_pads
			(clearance 0)
		)
		(min_thickness 0.25)
		(keepout
			(tracks not_allowed)
			(vias allowed)
			(pads allowed)
			(copperpour not_allowed)
			(footprints allowed)
		)
		(placement
			(enabled no)
			(sheetname "")
		)
		(fill yes
			(thermal_gap 0.5)
			(thermal_bridge_width 0.5)
			(island_removal_mode 0)
		)
		(polygon
			(pts
				(arc
					(start 237.072932 -181.799992)
					(mid 244.199918 -188.926978)
					(end 251.326904 -181.799992)
				)
				(arc
					(start 251.326904 -175.800004)
					(mid 244.199918 -168.673018)
					(end 237.072932 -175.800004)
				)
			)
		)
	)
	(zone
		(net "P12V_CLIP")
		(layers "F.Cu" "B.Cu" "In2.Cu" "In5.Cu")
		(hatch none 0.5)
		(connect_pads
			(clearance 0.5)
		)
		(min_thickness 0.25)
		(fill yes
			(thermal_gap 0.5)
			(thermal_bridge_width 0.5)
			(island_removal_mode 0)
		)
		(polygon
			(pts
				(xy 152.351994 -327.2155) (xy 151.8285 -327.738994) (xy 151.8285 -330.913994) (xy 151.342598 -331.399896)
				(xy 104.225598 -331.399896) (xy 102.9335 -332.691994) (xy 102.9335 -346.123006) (xy 103.8225 -347.012006)
				(xy 103.8225 -364.184692) (xy 104.127808 -364.49) (xy 109.22 -364.49) (xy 112.141 -361.569) (xy 122.936 -361.569)
				(xy 122.936 -361.6198) (xy 126.3523 -358.2035) (xy 160.5915 -358.2035) (xy 160.5915 -329.1205) (xy 157.909006 -329.1205)
				(xy 157.4165 -328.627994) (xy 157.4165 -327.357994) (xy 157.274006 -327.2155)
			)
		)
	)
	(zone
		(layers "F.Cu" "B.Cu" "In2.Cu" "In5.Cu")
		(hatch none 0.5)
		(connect_pads
			(clearance 0)
		)
		(min_thickness 0.25)
		(keepout
			(tracks not_allowed)
			(vias allowed)
			(pads allowed)
			(copperpour not_allowed)
			(footprints allowed)
		)
		(placement
			(enabled no)
			(sheetname "")
		)
		(fill yes
			(thermal_gap 0.5)
			(thermal_bridge_width 0.5)
			(island_removal_mode 0)
		)
		(polygon
			(pts
				(arc
					(start 293.073074 -100.000054)
					(mid 300.20006 -107.12704)
					(end 307.327046 -100.000054)
				)
				(arc
					(start 307.327046 -93.999812)
					(mid 300.20006 -86.87308)
					(end 293.073074 -93.999812)
				)
			)
		)
	)
	(zone
		(layers "F.Cu" "B.Cu" "In2.Cu" "In5.Cu")
		(hatch none 0.5)
		(connect_pads
			(clearance 0)
		)
		(min_thickness 0.25)
		(keepout
			(tracks not_allowed)
			(vias allowed)
			(pads allowed)
			(copperpour not_allowed)
			(footprints allowed)
		)
		(placement
			(enabled no)
			(sheetname "")
		)
		(fill yes
			(thermal_gap 0.5)
			(thermal_bridge_width 0.5)
			(island_removal_mode 0)
		)
		(polygon
			(pts
				(arc
					(start 251.326904 -244.00002)
					(mid 244.199918 -236.873034)
					(end 237.072932 -244.00002)
				)
				(arc
					(start 237.072932 -250.000008)
					(mid 244.199918 -257.126994)
					(end 251.326904 -250.000008)
				)
			)
		)
	)
	(zone
		(layers "F.Cu" "In2.Cu" "In5.Cu")
		(hatch none 0.5)
		(connect_pads
			(clearance 0)
		)
		(min_thickness 0.25)
		(keepout
			(tracks not_allowed)
			(vias allowed)
			(pads allowed)
			(copperpour not_allowed)
			(footprints allowed)
		)
		(placement
			(enabled no)
			(sheetname "")
		)
		(fill yes
			(thermal_gap 0.5)
			(thermal_bridge_width 0.5)
			(island_removal_mode 0)
		)
		(polygon
			(pts
				(arc
					(start 278.23668 -200.345802)
					(mid 277.68804 -200.894442)
					(end 278.23668 -201.443082)
				)
				(arc
					(start 279.636728 -201.443082)
					(mid 280.023776 -201.283286)
					(end 280.185368 -200.896982)
				)
				(arc
					(start 280.030428 -200.896982)
					(mid 279.636728 -201.28815)
					(end 279.243028 -200.896982)
				)
				(arc
					(start 278.63038 -200.896982)
					(mid 278.23668 -201.28815)
					(end 277.84298 -200.896982)
				)
				(arc
					(start 277.84298 -200.894442)
					(mid 278.23668 -200.500742)
					(end 278.63038 -200.894442)
				)
				(arc
					(start 279.243028 -200.894442)
					(mid 279.636728 -200.500742)
					(end 280.030428 -200.894442)
				)
				(arc
					(start 280.185368 -200.894442)
					(mid 280.024675 -200.506495)
					(end 279.636728 -200.345802)
				)
			)
		)
	)
	(zone
		(layers "F.Cu" "In2.Cu" "In5.Cu")
		(hatch none 0.5)
		(connect_pads
			(clearance 0)
		)
		(min_thickness 0.25)
		(keepout
			(tracks not_allowed)
			(vias allowed)
			(pads allowed)
			(copperpour not_allowed)
			(footprints allowed)
		)
		(placement
			(enabled no)
			(sheetname "")
		)
		(fill yes
			(thermal_gap 0.5)
			(thermal_bridge_width 0.5)
			(island_removal_mode 0)
		)
		(polygon
			(pts
				(arc
					(start 279.236678 -191.34582)
					(mid 278.688038 -191.89446)
					(end 279.236678 -192.4431)
				)
				(arc
					(start 280.636726 -192.4431)
					(mid 281.023774 -192.283304)
					(end 281.185366 -191.897)
				)
				(arc
					(start 281.030426 -191.897)
					(mid 280.636726 -192.288168)
					(end 280.243026 -191.897)
				)
				(arc
					(start 279.630378 -191.897)
					(mid 279.236678 -192.288168)
					(end 278.842978 -191.897)
				)
				(arc
					(start 278.842978 -191.89446)
					(mid 279.236678 -191.50076)
					(end 279.630378 -191.89446)
				)
				(arc
					(start 280.243026 -191.89446)
					(mid 280.636726 -191.50076)
					(end 281.030426 -191.89446)
				)
				(arc
					(start 281.185366 -191.89446)
					(mid 281.024673 -191.506513)
					(end 280.636726 -191.34582)
				)
			)
		)
	)
	(zone
		(layers "F.Cu" "In2.Cu" "In5.Cu")
		(hatch none 0.5)
		(connect_pads
			(clearance 0)
		)
		(min_thickness 0.25)
		(keepout
			(tracks not_allowed)
			(vias allowed)
			(pads allowed)
			(copperpour not_allowed)
			(footprints allowed)
		)
		(placement
			(enabled no)
			(sheetname "")
		)
		(fill yes
			(thermal_gap 0.5)
			(thermal_bridge_width 0.5)
			(island_removal_mode 0)
		)
		(polygon
			(pts
				(arc
					(start 278.23668 -131.545838)
					(mid 277.68804 -132.094478)
					(end 278.23668 -132.643118)
				)
				(arc
					(start 279.636728 -132.643118)
					(mid 280.023776 -132.483322)
					(end 280.185368 -132.097018)
				)
				(arc
					(start 280.030428 -132.097018)
					(mid 279.636728 -132.488186)
					(end 279.243028 -132.097018)
				)
				(arc
					(start 278.63038 -132.097018)
					(mid 278.23668 -132.488186)
					(end 277.84298 -132.097018)
				)
				(arc
					(start 277.84298 -132.094478)
					(mid 278.23668 -131.700778)
					(end 278.63038 -132.094478)
				)
				(arc
					(start 279.243028 -132.094478)
					(mid 279.636728 -131.700778)
					(end 280.030428 -132.094478)
				)
				(arc
					(start 280.185368 -132.094478)
					(mid 280.024675 -131.706531)
					(end 279.636728 -131.545838)
				)
			)
		)
	)
	(zone
		(layers "F.Cu" "In2.Cu" "In5.Cu")
		(hatch none 0.5)
		(connect_pads
			(clearance 0)
		)
		(min_thickness 0.25)
		(keepout
			(tracks not_allowed)
			(vias allowed)
			(pads allowed)
			(copperpour not_allowed)
			(footprints allowed)
		)
		(placement
			(enabled no)
			(sheetname "")
		)
		(fill yes
			(thermal_gap 0.5)
			(thermal_bridge_width 0.5)
			(island_removal_mode 0)
		)
		(polygon
			(pts
				(arc
					(start 217.748612 -77.600048)
					(mid 217.199972 -77.051408)
					(end 216.651332 -77.600048)
				)
				(arc
					(start 216.651332 -78.999842)
					(mid 217.198702 -79.548481)
					(end 217.748612 -79.002382)
				)
				(arc
					(start 217.593672 -79.002382)
					(mid 217.199972 -79.39355)
					(end 216.806272 -79.002382)
				)
				(arc
					(start 216.806272 -78.999842)
					(mid 217.199972 -78.606142)
					(end 217.593672 -78.999842)
				)
				(xy 217.748612 -78.999842) (xy 217.748612 -77.602588)
				(arc
					(start 217.593672 -77.602588)
					(mid 217.199972 -77.993756)
					(end 216.806272 -77.602588)
				)
				(arc
					(start 216.806272 -77.600048)
					(mid 217.199972 -77.206348)
					(end 217.593672 -77.600048)
				)
			)
		)
	)
	(zone
		(layers "F.Cu" "In2.Cu" "In5.Cu")
		(hatch none 0.5)
		(connect_pads
			(clearance 0)
		)
		(min_thickness 0.25)
		(keepout
			(tracks not_allowed)
			(vias allowed)
			(pads allowed)
			(copperpour not_allowed)
			(footprints allowed)
		)
		(placement
			(enabled no)
			(sheetname "")
		)
		(fill yes
			(thermal_gap 0.5)
			(thermal_bridge_width 0.5)
			(island_removal_mode 0)
		)
		(polygon
			(pts
				(arc
					(start 279.236678 -216.545922)
					(mid 278.688038 -217.094562)
					(end 279.236678 -217.643202)
				)
				(arc
					(start 280.636726 -217.643202)
					(mid 281.023774 -217.483406)
					(end 281.185366 -217.097102)
				)
				(arc
					(start 281.030426 -217.097102)
					(mid 280.636726 -217.48827)
					(end 280.243026 -217.097102)
				)
				(arc
					(start 279.630378 -217.097102)
					(mid 279.236678 -217.48827)
					(end 278.842978 -217.097102)
				)
				(arc
					(start 278.842978 -217.094562)
					(mid 279.236678 -216.700862)
					(end 279.630378 -217.094562)
				)
				(arc
					(start 280.243026 -217.094562)
					(mid 280.636726 -216.700862)
					(end 281.030426 -217.094562)
				)
				(arc
					(start 281.185366 -217.094562)
					(mid 281.024673 -216.706615)
					(end 280.636726 -216.545922)
				)
			)
		)
	)
	(zone
		(layers "F.Cu" "In2.Cu" "In5.Cu")
		(hatch none 0.5)
		(connect_pads
			(clearance 0)
		)
		(min_thickness 0.25)
		(keepout
			(tracks not_allowed)
			(vias allowed)
			(pads allowed)
			(copperpour not_allowed)
			(footprints allowed)
		)
		(placement
			(enabled no)
			(sheetname "")
		)
		(fill yes
			(thermal_gap 0.5)
			(thermal_bridge_width 0.5)
			(island_removal_mode 0)
		)
		(polygon
			(pts
				(arc
					(start 215.948768 -76.399898)
					(mid 215.400128 -75.851258)
					(end 214.851488 -76.399898)
				)
				(arc
					(start 214.851488 -77.799692)
					(mid 215.398731 -78.348584)
					(end 215.948768 -77.802486)
				)
				(arc
					(start 215.793828 -77.802486)
					(mid 215.400128 -78.193654)
					(end 215.006428 -77.802486)
				)
				(arc
					(start 215.006428 -77.799946)
					(mid 215.400128 -77.406246)
					(end 215.793828 -77.799946)
				)
				(xy 215.948768 -77.799946) (xy 215.948768 -76.402438)
				(arc
					(start 215.793828 -76.402438)
					(mid 215.400128 -76.793606)
					(end 215.006428 -76.402438)
				)
				(arc
					(start 215.006428 -76.399898)
					(mid 215.400128 -76.006198)
					(end 215.793828 -76.399898)
				)
			)
		)
	)
	(zone
		(layers "F.Cu" "In2.Cu" "In5.Cu")
		(hatch none 0.5)
		(connect_pads
			(clearance 0)
		)
		(min_thickness 0.25)
		(keepout
			(tracks not_allowed)
			(vias allowed)
			(pads allowed)
			(copperpour not_allowed)
			(footprints allowed)
		)
		(placement
			(enabled no)
			(sheetname "")
		)
		(fill yes
			(thermal_gap 0.5)
			(thermal_bridge_width 0.5)
			(island_removal_mode 0)
		)
		(polygon
			(pts
				(arc
					(start 279.236678 -209.345784)
					(mid 278.688038 -209.894424)
					(end 279.236678 -210.443064)
				)
				(arc
					(start 280.636726 -210.443064)
					(mid 281.023774 -210.283268)
					(end 281.185366 -209.896964)
				)
				(arc
					(start 281.030426 -209.896964)
					(mid 280.636726 -210.288132)
					(end 280.243026 -209.896964)
				)
				(arc
					(start 279.630378 -209.896964)
					(mid 279.236678 -210.288132)
					(end 278.842978 -209.896964)
				)
				(arc
					(start 278.842978 -209.894424)
					(mid 279.236678 -209.500724)
					(end 279.630378 -209.894424)
				)
				(arc
					(start 280.243026 -209.894424)
					(mid 280.636726 -209.500724)
					(end 281.030426 -209.894424)
				)
				(arc
					(start 281.185366 -209.894424)
					(mid 281.024673 -209.506477)
					(end 280.636726 -209.345784)
				)
			)
		)
	)
	(zone
		(layers "F.Cu" "In2.Cu" "In5.Cu")
		(hatch none 0.5)
		(connect_pads
			(clearance 0)
		)
		(min_thickness 0.25)
		(keepout
			(tracks not_allowed)
			(vias allowed)
			(pads allowed)
			(copperpour not_allowed)
			(footprints allowed)
		)
		(placement
			(enabled no)
			(sheetname "")
		)
		(fill yes
			(thermal_gap 0.5)
			(thermal_bridge_width 0.5)
			(island_removal_mode 0)
		)
		(polygon
			(pts
				(arc
					(start 278.23668 -229.145846)
					(mid 277.68804 -229.694486)
					(end 278.23668 -230.243126)
				)
				(arc
					(start 279.636728 -230.243126)
					(mid 280.023776 -230.08333)
					(end 280.185368 -229.697026)
				)
				(arc
					(start 280.030428 -229.697026)
					(mid 279.636728 -230.088194)
					(end 279.243028 -229.697026)
				)
				(arc
					(start 278.63038 -229.697026)
					(mid 278.23668 -230.088194)
					(end 277.84298 -229.697026)
				)
				(arc
					(start 277.84298 -229.694486)
					(mid 278.23668 -229.300786)
					(end 278.63038 -229.694486)
				)
				(arc
					(start 279.243028 -229.694486)
					(mid 279.636728 -229.300786)
					(end 280.030428 -229.694486)
				)
				(arc
					(start 280.185368 -229.694486)
					(mid 280.024675 -229.306539)
					(end 279.636728 -229.145846)
				)
			)
		)
	)
	(zone
		(layers "F.Cu" "In2.Cu" "In5.Cu")
		(hatch none 0.5)
		(connect_pads
			(clearance 0)
		)
		(min_thickness 0.25)
		(keepout
			(tracks not_allowed)
			(vias allowed)
			(pads allowed)
			(copperpour not_allowed)
			(footprints allowed)
		)
		(placement
			(enabled no)
			(sheetname "")
		)
		(fill yes
			(thermal_gap 0.5)
			(thermal_bridge_width 0.5)
			(island_removal_mode 0)
		)
		(polygon
			(pts
				(arc
					(start 279.236678 -133.345682)
					(mid 278.688038 -133.894322)
					(end 279.236678 -134.442962)
				)
				(arc
					(start 280.636726 -134.442962)
					(mid 281.023774 -134.283166)
					(end 281.185366 -133.896862)
				)
				(arc
					(start 281.030426 -133.896862)
					(mid 280.636726 -134.28803)
					(end 280.243026 -133.896862)
				)
				(arc
					(start 279.630378 -133.896862)
					(mid 279.236678 -134.28803)
					(end 278.842978 -133.896862)
				)
				(arc
					(start 278.842978 -133.894322)
					(mid 279.236678 -133.500622)
					(end 279.630378 -133.894322)
				)
				(arc
					(start 280.243026 -133.894322)
					(mid 280.636726 -133.500622)
					(end 281.030426 -133.894322)
				)
				(arc
					(start 281.185366 -133.894322)
					(mid 281.024673 -133.506375)
					(end 280.636726 -133.345682)
				)
			)
		)
	)
	(zone
		(layers "F.Cu" "In2.Cu" "In5.Cu")
		(hatch none 0.5)
		(connect_pads
			(clearance 0)
		)
		(min_thickness 0.25)
		(keepout
			(tracks not_allowed)
			(vias allowed)
			(pads allowed)
			(copperpour not_allowed)
			(footprints allowed)
		)
		(placement
			(enabled no)
			(sheetname "")
		)
		(fill yes
			(thermal_gap 0.5)
			(thermal_bridge_width 0.5)
			(island_removal_mode 0)
		)
		(polygon
			(pts
				(arc
					(start 278.23668 -203.945744)
					(mid 277.68804 -204.494384)
					(end 278.23668 -205.043024)
				)
				(arc
					(start 279.636728 -205.043024)
					(mid 280.023776 -204.883228)
					(end 280.185368 -204.496924)
				)
				(arc
					(start 280.030428 -204.496924)
					(mid 279.636728 -204.888092)
					(end 279.243028 -204.496924)
				)
				(arc
					(start 278.63038 -204.496924)
					(mid 278.23668 -204.888092)
					(end 277.84298 -204.496924)
				)
				(arc
					(start 277.84298 -204.494384)
					(mid 278.23668 -204.100684)
					(end 278.63038 -204.494384)
				)
				(arc
					(start 279.243028 -204.494384)
					(mid 279.636728 -204.100684)
					(end 280.030428 -204.494384)
				)
				(arc
					(start 280.185368 -204.494384)
					(mid 280.024675 -204.106437)
					(end 279.636728 -203.945744)
				)
			)
		)
	)
	(zone
		(layers "F.Cu" "In2.Cu" "In5.Cu")
		(hatch none 0.5)
		(connect_pads
			(clearance 0)
		)
		(min_thickness 0.25)
		(keepout
			(tracks not_allowed)
			(vias allowed)
			(pads allowed)
			(copperpour not_allowed)
			(footprints allowed)
		)
		(placement
			(enabled no)
			(sheetname "")
		)
		(fill yes
			(thermal_gap 0.5)
			(thermal_bridge_width 0.5)
			(island_removal_mode 0)
		)
		(polygon
			(pts
				(arc
					(start 278.23668 -207.54594)
					(mid 277.68804 -208.09458)
					(end 278.23668 -208.64322)
				)
				(arc
					(start 279.636728 -208.64322)
					(mid 280.023776 -208.483424)
					(end 280.185368 -208.09712)
				)
				(arc
					(start 280.030428 -208.09712)
					(mid 279.636728 -208.488288)
					(end 279.243028 -208.09712)
				)
				(arc
					(start 278.63038 -208.09712)
					(mid 278.23668 -208.488288)
					(end 277.84298 -208.09712)
				)
				(arc
					(start 277.84298 -208.09458)
					(mid 278.23668 -207.70088)
					(end 278.63038 -208.09458)
				)
				(arc
					(start 279.243028 -208.09458)
					(mid 279.636728 -207.70088)
					(end 280.030428 -208.09458)
				)
				(arc
					(start 280.185368 -208.09458)
					(mid 280.024675 -207.706633)
					(end 279.636728 -207.54594)
				)
			)
		)
	)
	(zone
		(layers "F.Cu" "In2.Cu" "In5.Cu")
		(hatch none 0.5)
		(connect_pads
			(clearance 0)
		)
		(min_thickness 0.25)
		(keepout
			(tracks not_allowed)
			(vias allowed)
			(pads allowed)
			(copperpour not_allowed)
			(footprints allowed)
		)
		(placement
			(enabled no)
			(sheetname "")
		)
		(fill yes
			(thermal_gap 0.5)
			(thermal_bridge_width 0.5)
			(island_removal_mode 0)
		)
		(polygon
			(pts
				(arc
					(start 278.23668 -221.945708)
					(mid 277.68804 -222.494348)
					(end 278.23668 -223.042988)
				)
				(arc
					(start 279.636728 -223.042988)
					(mid 280.023776 -222.883192)
					(end 280.185368 -222.496888)
				)
				(arc
					(start 280.030428 -222.496888)
					(mid 279.636728 -222.888056)
					(end 279.243028 -222.496888)
				)
				(arc
					(start 278.63038 -222.496888)
					(mid 278.23668 -222.888056)
					(end 277.84298 -222.496888)
				)
				(arc
					(start 277.84298 -222.494348)
					(mid 278.23668 -222.100648)
					(end 278.63038 -222.494348)
				)
				(arc
					(start 279.243028 -222.494348)
					(mid 279.636728 -222.100648)
					(end 280.030428 -222.494348)
				)
				(arc
					(start 280.185368 -222.494348)
					(mid 280.024675 -222.106401)
					(end 279.636728 -221.945708)
				)
			)
		)
	)
	(zone
		(layers "F.Cu" "In2.Cu" "In5.Cu")
		(hatch none 0.5)
		(connect_pads
			(clearance 0)
		)
		(min_thickness 0.25)
		(keepout
			(tracks not_allowed)
			(vias allowed)
			(pads allowed)
			(copperpour not_allowed)
			(footprints allowed)
		)
		(placement
			(enabled no)
			(sheetname "")
		)
		(fill yes
			(thermal_gap 0.5)
			(thermal_bridge_width 0.5)
			(island_removal_mode 0)
		)
		(polygon
			(pts
				(arc
					(start 282.83662 -144.145762)
					(mid 282.28798 -144.694402)
					(end 282.83662 -145.243042)
				)
				(arc
					(start 284.236668 -145.243042)
					(mid 284.623716 -145.083246)
					(end 284.785308 -144.696942)
				)
				(arc
					(start 284.630368 -144.696942)
					(mid 284.236668 -145.08811)
					(end 283.842968 -144.696942)
				)
				(arc
					(start 283.23032 -144.696942)
					(mid 282.83662 -145.08811)
					(end 282.44292 -144.696942)
				)
				(arc
					(start 282.44292 -144.694402)
					(mid 282.83662 -144.300702)
					(end 283.23032 -144.694402)
				)
				(arc
					(start 283.842968 -144.694402)
					(mid 284.236668 -144.300702)
					(end 284.630368 -144.694402)
				)
				(arc
					(start 284.785308 -144.694402)
					(mid 284.624615 -144.306455)
					(end 284.236668 -144.145762)
				)
			)
		)
	)
	(zone
		(layers "F.Cu" "In2.Cu" "In5.Cu")
		(hatch none 0.5)
		(connect_pads
			(clearance 0)
		)
		(min_thickness 0.25)
		(keepout
			(tracks not_allowed)
			(vias allowed)
			(pads allowed)
			(copperpour not_allowed)
			(footprints allowed)
		)
		(placement
			(enabled no)
			(sheetname "")
		)
		(fill yes
			(thermal_gap 0.5)
			(thermal_bridge_width 0.5)
			(island_removal_mode 0)
		)
		(polygon
			(pts
				(arc
					(start 279.236678 -184.145936)
					(mid 278.688038 -184.694576)
					(end 279.236678 -185.243216)
				)
				(arc
					(start 280.636726 -185.243216)
					(mid 281.023774 -185.08342)
					(end 281.185366 -184.697116)
				)
				(arc
					(start 281.030426 -184.697116)
					(mid 280.636726 -185.088284)
					(end 280.243026 -184.697116)
				)
				(arc
					(start 279.630378 -184.697116)
					(mid 279.236678 -185.088284)
					(end 278.842978 -184.697116)
				)
				(arc
					(start 278.842978 -184.694576)
					(mid 279.236678 -184.300876)
					(end 279.630378 -184.694576)
				)
				(arc
					(start 280.243026 -184.694576)
					(mid 280.636726 -184.300876)
					(end 281.030426 -184.694576)
				)
				(arc
					(start 281.185366 -184.694576)
					(mid 281.024673 -184.306629)
					(end 280.636726 -184.145936)
				)
			)
		)
	)
	(zone
		(layers "F.Cu" "In2.Cu" "In5.Cu")
		(hatch none 0.5)
		(connect_pads
			(clearance 0)
		)
		(min_thickness 0.25)
		(keepout
			(tracks not_allowed)
			(vias allowed)
			(pads allowed)
			(copperpour not_allowed)
			(footprints allowed)
		)
		(placement
			(enabled no)
			(sheetname "")
		)
		(fill yes
			(thermal_gap 0.5)
			(thermal_bridge_width 0.5)
			(island_removal_mode 0)
		)
		(polygon
			(pts
				(arc
					(start 219.54871 -76.399898)
					(mid 219.00007 -75.851258)
					(end 218.45143 -76.399898)
				)
				(arc
					(start 218.45143 -77.799692)
					(mid 218.998673 -78.348584)
					(end 219.54871 -77.802486)
				)
				(arc
					(start 219.39377 -77.802486)
					(mid 219.00007 -78.193654)
					(end 218.60637 -77.802486)
				)
				(arc
					(start 218.60637 -77.799946)
					(mid 219.00007 -77.406246)
					(end 219.39377 -77.799946)
				)
				(xy 219.54871 -77.799946) (xy 219.54871 -76.402438)
				(arc
					(start 219.39377 -76.402438)
					(mid 219.00007 -76.793606)
					(end 218.60637 -76.402438)
				)
				(arc
					(start 218.60637 -76.399898)
					(mid 219.00007 -76.006198)
					(end 219.39377 -76.399898)
				)
			)
		)
	)
	(zone
		(layers "F.Cu" "In2.Cu" "In5.Cu")
		(hatch none 0.5)
		(connect_pads
			(clearance 0)
		)
		(min_thickness 0.25)
		(keepout
			(tracks not_allowed)
			(vias allowed)
			(pads allowed)
			(copperpour not_allowed)
			(footprints allowed)
		)
		(placement
			(enabled no)
			(sheetname "")
		)
		(fill yes
			(thermal_gap 0.5)
			(thermal_bridge_width 0.5)
			(island_removal_mode 0)
		)
		(polygon
			(pts
				(arc
					(start 278.23668 -196.74586)
					(mid 277.68804 -197.2945)
					(end 278.23668 -197.84314)
				)
				(arc
					(start 279.636728 -197.84314)
					(mid 280.023776 -197.683344)
					(end 280.185368 -197.29704)
				)
				(arc
					(start 280.030428 -197.29704)
					(mid 279.636728 -197.688208)
					(end 279.243028 -197.29704)
				)
				(arc
					(start 278.63038 -197.29704)
					(mid 278.23668 -197.688208)
					(end 277.84298 -197.29704)
				)
				(arc
					(start 277.84298 -197.2945)
					(mid 278.23668 -196.9008)
					(end 278.63038 -197.2945)
				)
				(arc
					(start 279.243028 -197.2945)
					(mid 279.636728 -196.9008)
					(end 280.030428 -197.2945)
				)
				(arc
					(start 280.185368 -197.2945)
					(mid 280.024675 -196.906553)
					(end 279.636728 -196.74586)
				)
			)
		)
	)
	(zone
		(layers "F.Cu" "In2.Cu" "In5.Cu")
		(hatch none 0.5)
		(connect_pads
			(clearance 0)
		)
		(min_thickness 0.25)
		(keepout
			(tracks not_allowed)
			(vias allowed)
			(pads allowed)
			(copperpour not_allowed)
			(footprints allowed)
		)
		(placement
			(enabled no)
			(sheetname "")
		)
		(fill yes
			(thermal_gap 0.5)
			(thermal_bridge_width 0.5)
			(island_removal_mode 0)
		)
		(polygon
			(pts
				(arc
					(start 279.236678 -230.945944)
					(mid 278.688038 -231.494584)
					(end 279.236678 -232.043224)
				)
				(arc
					(start 280.636726 -232.043224)
					(mid 281.023774 -231.883428)
					(end 281.185366 -231.497124)
				)
				(arc
					(start 281.030426 -231.497124)
					(mid 280.636726 -231.888292)
					(end 280.243026 -231.497124)
				)
				(arc
					(start 279.630378 -231.497124)
					(mid 279.236678 -231.888292)
					(end 278.842978 -231.497124)
				)
				(arc
					(start 278.842978 -231.494584)
					(mid 279.236678 -231.100884)
					(end 279.630378 -231.494584)
				)
				(arc
					(start 280.243026 -231.494584)
					(mid 280.636726 -231.100884)
					(end 281.030426 -231.494584)
				)
				(arc
					(start 281.185366 -231.494584)
					(mid 281.024673 -231.106637)
					(end 280.636726 -230.945944)
				)
			)
		)
	)
	(zone
		(layers "F.Cu" "In2.Cu" "In5.Cu")
		(hatch none 0.5)
		(connect_pads
			(clearance 0)
		)
		(min_thickness 0.25)
		(keepout
			(tracks not_allowed)
			(vias allowed)
			(pads allowed)
			(copperpour not_allowed)
			(footprints allowed)
		)
		(placement
			(enabled no)
			(sheetname "")
		)
		(fill yes
			(thermal_gap 0.5)
			(thermal_bridge_width 0.5)
			(island_removal_mode 0)
		)
		(polygon
			(pts
				(arc
					(start 279.236678 -198.545704)
					(mid 278.688038 -199.094344)
					(end 279.236678 -199.642984)
				)
				(arc
					(start 280.636726 -199.642984)
					(mid 281.023774 -199.483188)
					(end 281.185366 -199.096884)
				)
				(arc
					(start 281.030426 -199.096884)
					(mid 280.636726 -199.488052)
					(end 280.243026 -199.096884)
				)
				(arc
					(start 279.630378 -199.096884)
					(mid 279.236678 -199.488052)
					(end 278.842978 -199.096884)
				)
				(arc
					(start 278.842978 -199.094344)
					(mid 279.236678 -198.700644)
					(end 279.630378 -199.094344)
				)
				(arc
					(start 280.243026 -199.094344)
					(mid 280.636726 -198.700644)
					(end 281.030426 -199.094344)
				)
				(arc
					(start 281.185366 -199.094344)
					(mid 281.024673 -198.706397)
					(end 280.636726 -198.545704)
				)
			)
		)
	)
	(zone
		(layers "F.Cu" "In2.Cu" "In5.Cu")
		(hatch none 0.5)
		(connect_pads
			(clearance 0)
		)
		(min_thickness 0.25)
		(keepout
			(tracks not_allowed)
			(vias allowed)
			(pads allowed)
			(copperpour not_allowed)
			(footprints allowed)
		)
		(placement
			(enabled no)
			(sheetname "")
		)
		(fill yes
			(thermal_gap 0.5)
			(thermal_bridge_width 0.5)
			(island_removal_mode 0)
		)
		(polygon
			(pts
				(arc
					(start 279.236678 -223.745806)
					(mid 278.688038 -224.294446)
					(end 279.236678 -224.843086)
				)
				(arc
					(start 280.636726 -224.843086)
					(mid 281.023774 -224.68329)
					(end 281.185366 -224.296986)
				)
				(arc
					(start 281.030426 -224.296986)
					(mid 280.636726 -224.688154)
					(end 280.243026 -224.296986)
				)
				(arc
					(start 279.630378 -224.296986)
					(mid 279.236678 -224.688154)
					(end 278.842978 -224.296986)
				)
				(arc
					(start 278.842978 -224.294446)
					(mid 279.236678 -223.900746)
					(end 279.630378 -224.294446)
				)
				(arc
					(start 280.243026 -224.294446)
					(mid 280.636726 -223.900746)
					(end 281.030426 -224.294446)
				)
				(arc
					(start 281.185366 -224.294446)
					(mid 281.024673 -223.906499)
					(end 280.636726 -223.745806)
				)
			)
		)
	)
	(zone
		(layers "F.Cu" "In2.Cu" "In5.Cu")
		(hatch none 0.5)
		(connect_pads
			(clearance 0)
		)
		(min_thickness 0.25)
		(keepout
			(tracks not_allowed)
			(vias allowed)
			(pads allowed)
			(copperpour not_allowed)
			(footprints allowed)
		)
		(placement
			(enabled no)
			(sheetname "")
		)
		(fill yes
			(thermal_gap 0.5)
			(thermal_bridge_width 0.5)
			(island_removal_mode 0)
		)
		(polygon
			(pts
				(arc
					(start 279.236678 -234.545886)
					(mid 278.688038 -235.094526)
					(end 279.236678 -235.643166)
				)
				(arc
					(start 280.636726 -235.643166)
					(mid 281.023774 -235.48337)
					(end 281.185366 -235.097066)
				)
				(arc
					(start 281.030426 -235.097066)
					(mid 280.636726 -235.488234)
					(end 280.243026 -235.097066)
				)
				(arc
					(start 279.630378 -235.097066)
					(mid 279.236678 -235.488234)
					(end 278.842978 -235.097066)
				)
				(arc
					(start 278.842978 -235.094526)
					(mid 279.236678 -234.700826)
					(end 279.630378 -235.094526)
				)
				(arc
					(start 280.243026 -235.094526)
					(mid 280.636726 -234.700826)
					(end 281.030426 -235.094526)
				)
				(arc
					(start 281.185366 -235.094526)
					(mid 281.024673 -234.706579)
					(end 280.636726 -234.545886)
				)
			)
		)
	)
	(zone
		(layers "F.Cu" "In2.Cu" "In5.Cu")
		(hatch none 0.5)
		(connect_pads
			(clearance 0)
		)
		(min_thickness 0.25)
		(keepout
			(tracks not_allowed)
			(vias allowed)
			(pads allowed)
			(copperpour not_allowed)
			(footprints allowed)
		)
		(placement
			(enabled no)
			(sheetname "")
		)
		(fill yes
			(thermal_gap 0.5)
			(thermal_bridge_width 0.5)
			(island_removal_mode 0)
		)
		(polygon
			(pts
				(arc
					(start 279.236678 -176.945798)
					(mid 278.688038 -177.494438)
					(end 279.236678 -178.043078)
				)
				(arc
					(start 280.636726 -178.043078)
					(mid 281.023774 -177.883282)
					(end 281.185366 -177.496978)
				)
				(arc
					(start 281.030426 -177.496978)
					(mid 280.636726 -177.888146)
					(end 280.243026 -177.496978)
				)
				(arc
					(start 279.630378 -177.496978)
					(mid 279.236678 -177.888146)
					(end 278.842978 -177.496978)
				)
				(arc
					(start 278.842978 -177.494438)
					(mid 279.236678 -177.100738)
					(end 279.630378 -177.494438)
				)
				(arc
					(start 280.243026 -177.494438)
					(mid 280.636726 -177.100738)
					(end 281.030426 -177.494438)
				)
				(arc
					(start 281.185366 -177.494438)
					(mid 281.024673 -177.106491)
					(end 280.636726 -176.945798)
				)
			)
		)
	)
	(zone
		(layers "F.Cu" "In2.Cu" "In5.Cu")
		(hatch none 0.5)
		(connect_pads
			(clearance 0)
		)
		(min_thickness 0.25)
		(keepout
			(tracks not_allowed)
			(vias allowed)
			(pads allowed)
			(copperpour not_allowed)
			(footprints allowed)
		)
		(placement
			(enabled no)
			(sheetname "")
		)
		(fill yes
			(thermal_gap 0.5)
			(thermal_bridge_width 0.5)
			(island_removal_mode 0)
		)
		(polygon
			(pts
				(arc
					(start 279.236678 -220.145864)
					(mid 278.688038 -220.694504)
					(end 279.236678 -221.243144)
				)
				(arc
					(start 280.636726 -221.243144)
					(mid 281.023774 -221.083348)
					(end 281.185366 -220.697044)
				)
				(arc
					(start 281.030426 -220.697044)
					(mid 280.636726 -221.088212)
					(end 280.243026 -220.697044)
				)
				(arc
					(start 279.630378 -220.697044)
					(mid 279.236678 -221.088212)
					(end 278.842978 -220.697044)
				)
				(arc
					(start 278.842978 -220.694504)
					(mid 279.236678 -220.300804)
					(end 279.630378 -220.694504)
				)
				(arc
					(start 280.243026 -220.694504)
					(mid 280.636726 -220.300804)
					(end 281.030426 -220.694504)
				)
				(arc
					(start 281.185366 -220.694504)
					(mid 281.024673 -220.306557)
					(end 280.636726 -220.145864)
				)
			)
		)
	)
	(zone
		(layers "F.Cu" "In2.Cu" "In5.Cu")
		(hatch none 0.5)
		(connect_pads
			(clearance 0)
		)
		(min_thickness 0.25)
		(keepout
			(tracks not_allowed)
			(vias allowed)
			(pads allowed)
			(copperpour not_allowed)
			(footprints allowed)
		)
		(placement
			(enabled no)
			(sheetname "")
		)
		(fill yes
			(thermal_gap 0.5)
			(thermal_bridge_width 0.5)
			(island_removal_mode 0)
		)
		(polygon
			(pts
				(arc
					(start 279.236678 -202.1459)
					(mid 278.688038 -202.69454)
					(end 279.236678 -203.24318)
				)
				(arc
					(start 280.636726 -203.24318)
					(mid 281.023774 -203.083384)
					(end 281.185366 -202.69708)
				)
				(arc
					(start 281.030426 -202.69708)
					(mid 280.636726 -203.088248)
					(end 280.243026 -202.69708)
				)
				(arc
					(start 279.630378 -202.69708)
					(mid 279.236678 -203.088248)
					(end 278.842978 -202.69708)
				)
				(arc
					(start 278.842978 -202.69454)
					(mid 279.236678 -202.30084)
					(end 279.630378 -202.69454)
				)
				(arc
					(start 280.243026 -202.69454)
					(mid 280.636726 -202.30084)
					(end 281.030426 -202.69454)
				)
				(arc
					(start 281.185366 -202.69454)
					(mid 281.024673 -202.306593)
					(end 280.636726 -202.1459)
				)
			)
		)
	)
	(zone
		(layers "F.Cu" "In2.Cu" "In5.Cu")
		(hatch none 0.5)
		(connect_pads
			(clearance 0)
		)
		(min_thickness 0.25)
		(keepout
			(tracks not_allowed)
			(vias allowed)
			(pads allowed)
			(copperpour not_allowed)
			(footprints allowed)
		)
		(placement
			(enabled no)
			(sheetname "")
		)
		(fill yes
			(thermal_gap 0.5)
			(thermal_bridge_width 0.5)
			(island_removal_mode 0)
		)
		(polygon
			(pts
				(arc
					(start 212.348826 -76.399898)
					(mid 211.800186 -75.851258)
					(end 211.251546 -76.399898)
				)
				(arc
					(start 211.251546 -77.799692)
					(mid 211.798789 -78.348584)
					(end 212.348826 -77.802486)
				)
				(arc
					(start 212.193886 -77.802486)
					(mid 211.800186 -78.193654)
					(end 211.406486 -77.802486)
				)
				(arc
					(start 211.406486 -77.799946)
					(mid 211.800186 -77.406246)
					(end 212.193886 -77.799946)
				)
				(xy 212.348826 -77.799946) (xy 212.348826 -76.402438)
				(arc
					(start 212.193886 -76.402438)
					(mid 211.800186 -76.793606)
					(end 211.406486 -76.402438)
				)
				(arc
					(start 211.406486 -76.399898)
					(mid 211.800186 -76.006198)
					(end 212.193886 -76.399898)
				)
			)
		)
	)
	(zone
		(layers "F.Cu" "In2.Cu" "In5.Cu")
		(hatch none 0.5)
		(connect_pads
			(clearance 0)
		)
		(min_thickness 0.25)
		(keepout
			(tracks not_allowed)
			(vias allowed)
			(pads allowed)
			(copperpour not_allowed)
			(footprints allowed)
		)
		(placement
			(enabled no)
			(sheetname "")
		)
		(fill yes
			(thermal_gap 0.5)
			(thermal_bridge_width 0.5)
			(island_removal_mode 0)
		)
		(polygon
			(pts
				(arc
					(start 278.23668 -211.145882)
					(mid 277.68804 -211.694522)
					(end 278.23668 -212.243162)
				)
				(arc
					(start 279.636728 -212.243162)
					(mid 280.023776 -212.083366)
					(end 280.185368 -211.697062)
				)
				(arc
					(start 280.030428 -211.697062)
					(mid 279.636728 -212.08823)
					(end 279.243028 -211.697062)
				)
				(arc
					(start 278.63038 -211.697062)
					(mid 278.23668 -212.08823)
					(end 277.84298 -211.697062)
				)
				(arc
					(start 277.84298 -211.694522)
					(mid 278.23668 -211.300822)
					(end 278.63038 -211.694522)
				)
				(arc
					(start 279.243028 -211.694522)
					(mid 279.636728 -211.300822)
					(end 280.030428 -211.694522)
				)
				(arc
					(start 280.185368 -211.694522)
					(mid 280.024675 -211.306575)
					(end 279.636728 -211.145882)
				)
			)
		)
	)
	(zone
		(layers "F.Cu" "In2.Cu" "In5.Cu")
		(hatch none 0.5)
		(connect_pads
			(clearance 0)
		)
		(min_thickness 0.25)
		(keepout
			(tracks not_allowed)
			(vias allowed)
			(pads allowed)
			(copperpour not_allowed)
			(footprints allowed)
		)
		(placement
			(enabled no)
			(sheetname "")
		)
		(fill yes
			(thermal_gap 0.5)
			(thermal_bridge_width 0.5)
			(island_removal_mode 0)
		)
		(polygon
			(pts
				(arc
					(start 279.236678 -194.945762)
					(mid 278.688038 -195.494402)
					(end 279.236678 -196.043042)
				)
				(arc
					(start 280.636726 -196.043042)
					(mid 281.023774 -195.883246)
					(end 281.185366 -195.496942)
				)
				(arc
					(start 281.030426 -195.496942)
					(mid 280.636726 -195.88811)
					(end 280.243026 -195.496942)
				)
				(arc
					(start 279.630378 -195.496942)
					(mid 279.236678 -195.88811)
					(end 278.842978 -195.496942)
				)
				(arc
					(start 278.842978 -195.494402)
					(mid 279.236678 -195.100702)
					(end 279.630378 -195.494402)
				)
				(arc
					(start 280.243026 -195.494402)
					(mid 280.636726 -195.100702)
					(end 281.030426 -195.494402)
				)
				(arc
					(start 281.185366 -195.494402)
					(mid 281.024673 -195.106455)
					(end 280.636726 -194.945762)
				)
			)
		)
	)
	(zone
		(layers "F.Cu" "In2.Cu" "In5.Cu")
		(hatch none 0.5)
		(connect_pads
			(clearance 0)
		)
		(min_thickness 0.25)
		(keepout
			(tracks not_allowed)
			(vias allowed)
			(pads allowed)
			(copperpour not_allowed)
			(footprints allowed)
		)
		(placement
			(enabled no)
			(sheetname "")
		)
		(fill yes
			(thermal_gap 0.5)
			(thermal_bridge_width 0.5)
			(island_removal_mode 0)
		)
		(polygon
			(pts
				(arc
					(start 223.148652 -76.399898)
					(mid 222.600012 -75.851258)
					(end 222.051372 -76.399898)
				)
				(arc
					(start 222.051372 -77.799692)
					(mid 222.598615 -78.348584)
					(end 223.148652 -77.802486)
				)
				(arc
					(start 222.993712 -77.802486)
					(mid 222.600012 -78.193654)
					(end 222.206312 -77.802486)
				)
				(arc
					(start 222.206312 -77.799946)
					(mid 222.600012 -77.406246)
					(end 222.993712 -77.799946)
				)
				(xy 223.148652 -77.799946) (xy 223.148652 -76.402438)
				(arc
					(start 222.993712 -76.402438)
					(mid 222.600012 -76.793606)
					(end 222.206312 -76.402438)
				)
				(arc
					(start 222.206312 -76.399898)
					(mid 222.600012 -76.006198)
					(end 222.993712 -76.399898)
				)
			)
		)
	)
	(zone
		(layers "F.Cu" "In2.Cu" "In5.Cu")
		(hatch none 0.5)
		(connect_pads
			(clearance 0)
		)
		(min_thickness 0.25)
		(keepout
			(tracks not_allowed)
			(vias allowed)
			(pads allowed)
			(copperpour not_allowed)
			(footprints allowed)
		)
		(placement
			(enabled no)
			(sheetname "")
		)
		(fill yes
			(thermal_gap 0.5)
			(thermal_bridge_width 0.5)
			(island_removal_mode 0)
		)
		(polygon
			(pts
				(arc
					(start 278.23668 -214.745824)
					(mid 277.68804 -215.294464)
					(end 278.23668 -215.843104)
				)
				(arc
					(start 279.636728 -215.843104)
					(mid 280.023776 -215.683308)
					(end 280.185368 -215.297004)
				)
				(arc
					(start 280.030428 -215.297004)
					(mid 279.636728 -215.688172)
					(end 279.243028 -215.297004)
				)
				(arc
					(start 278.63038 -215.297004)
					(mid 278.23668 -215.688172)
					(end 277.84298 -215.297004)
				)
				(arc
					(start 277.84298 -215.294464)
					(mid 278.23668 -214.900764)
					(end 278.63038 -215.294464)
				)
				(arc
					(start 279.243028 -215.294464)
					(mid 279.636728 -214.900764)
					(end 280.030428 -215.294464)
				)
				(arc
					(start 280.185368 -215.294464)
					(mid 280.024675 -214.906517)
					(end 279.636728 -214.745824)
				)
			)
		)
	)
	(zone
		(layers "F.Cu" "In2.Cu" "In5.Cu")
		(hatch none 0.5)
		(connect_pads
			(clearance 0)
		)
		(min_thickness 0.25)
		(keepout
			(tracks not_allowed)
			(vias allowed)
			(pads allowed)
			(copperpour not_allowed)
			(footprints allowed)
		)
		(placement
			(enabled no)
			(sheetname "")
		)
		(fill yes
			(thermal_gap 0.5)
			(thermal_bridge_width 0.5)
			(island_removal_mode 0)
		)
		(polygon
			(pts
				(arc
					(start 279.236678 -212.945726)
					(mid 278.688038 -213.494366)
					(end 279.236678 -214.043006)
				)
				(arc
					(start 280.636726 -214.043006)
					(mid 281.023774 -213.88321)
					(end 281.185366 -213.496906)
				)
				(arc
					(start 281.030426 -213.496906)
					(mid 280.636726 -213.888074)
					(end 280.243026 -213.496906)
				)
				(arc
					(start 279.630378 -213.496906)
					(mid 279.236678 -213.888074)
					(end 278.842978 -213.496906)
				)
				(arc
					(start 278.842978 -213.494366)
					(mid 279.236678 -213.100666)
					(end 279.630378 -213.494366)
				)
				(arc
					(start 280.243026 -213.494366)
					(mid 280.636726 -213.100666)
					(end 281.030426 -213.494366)
				)
				(arc
					(start 281.185366 -213.494366)
					(mid 281.024673 -213.106419)
					(end 280.636726 -212.945726)
				)
			)
		)
	)
	(zone
		(layers "F.Cu" "In2.Cu" "In5.Cu")
		(hatch none 0.5)
		(connect_pads
			(clearance 0)
		)
		(min_thickness 0.25)
		(keepout
			(tracks not_allowed)
			(vias allowed)
			(pads allowed)
			(copperpour not_allowed)
			(footprints allowed)
		)
		(placement
			(enabled no)
			(sheetname "")
		)
		(fill yes
			(thermal_gap 0.5)
			(thermal_bridge_width 0.5)
			(island_removal_mode 0)
		)
		(polygon
			(pts
				(arc
					(start 279.236678 -180.54574)
					(mid 278.688038 -181.09438)
					(end 279.236678 -181.64302)
				)
				(arc
					(start 280.636726 -181.64302)
					(mid 281.023774 -181.483224)
					(end 281.185366 -181.09692)
				)
				(arc
					(start 281.030426 -181.09692)
					(mid 280.636726 -181.488088)
					(end 280.243026 -181.09692)
				)
				(arc
					(start 279.630378 -181.09692)
					(mid 279.236678 -181.488088)
					(end 278.842978 -181.09692)
				)
				(arc
					(start 278.842978 -181.09438)
					(mid 279.236678 -180.70068)
					(end 279.630378 -181.09438)
				)
				(arc
					(start 280.243026 -181.09438)
					(mid 280.636726 -180.70068)
					(end 281.030426 -181.09438)
				)
				(arc
					(start 281.185366 -181.09438)
					(mid 281.024673 -180.706433)
					(end 280.636726 -180.54574)
				)
			)
		)
	)
	(zone
		(layers "F.Cu" "In2.Cu" "In5.Cu")
		(hatch none 0.5)
		(connect_pads
			(clearance 0)
		)
		(min_thickness 0.25)
		(keepout
			(tracks not_allowed)
			(vias allowed)
			(pads allowed)
			(copperpour not_allowed)
			(footprints allowed)
		)
		(placement
			(enabled no)
			(sheetname "")
		)
		(fill yes
			(thermal_gap 0.5)
			(thermal_bridge_width 0.5)
			(island_removal_mode 0)
		)
		(polygon
			(pts
				(arc
					(start 278.23668 -142.345664)
					(mid 277.68804 -142.894304)
					(end 278.23668 -143.442944)
				)
				(arc
					(start 279.636728 -143.442944)
					(mid 280.023776 -143.283148)
					(end 280.185368 -142.896844)
				)
				(arc
					(start 280.030428 -142.896844)
					(mid 279.636728 -143.288012)
					(end 279.243028 -142.896844)
				)
				(arc
					(start 278.63038 -142.896844)
					(mid 278.23668 -143.288012)
					(end 277.84298 -142.896844)
				)
				(arc
					(start 277.84298 -142.894304)
					(mid 278.23668 -142.500604)
					(end 278.63038 -142.894304)
				)
				(arc
					(start 279.243028 -142.894304)
					(mid 279.636728 -142.500604)
					(end 280.030428 -142.894304)
				)
				(arc
					(start 280.185368 -142.894304)
					(mid 280.024675 -142.506357)
					(end 279.636728 -142.345664)
				)
			)
		)
	)
	(zone
		(layers "F.Cu" "In2.Cu" "In5.Cu")
		(hatch none 0.5)
		(connect_pads
			(clearance 0)
		)
		(min_thickness 0.25)
		(keepout
			(tracks not_allowed)
			(vias allowed)
			(pads allowed)
			(copperpour not_allowed)
			(footprints allowed)
		)
		(placement
			(enabled no)
			(sheetname "")
		)
		(fill yes
			(thermal_gap 0.5)
			(thermal_bridge_width 0.5)
			(island_removal_mode 0)
		)
		(polygon
			(pts
				(arc
					(start 279.236678 -136.943338)
					(mid 278.685498 -137.494518)
					(end 279.236678 -138.045698)
				)
				(arc
					(start 280.636726 -138.045698)
					(mid 281.02557 -137.885158)
					(end 281.187906 -137.497058)
				)
				(arc
					(start 281.030426 -137.497058)
					(mid 280.636726 -137.888226)
					(end 280.243026 -137.497058)
				)
				(arc
					(start 279.630378 -137.497058)
					(mid 279.236678 -137.888226)
					(end 278.842978 -137.497058)
				)
				(arc
					(start 278.842978 -137.494518)
					(mid 279.236678 -137.100818)
					(end 279.630378 -137.494518)
				)
				(arc
					(start 280.243026 -137.494518)
					(mid 280.636726 -137.100818)
					(end 281.030426 -137.494518)
				)
				(arc
					(start 281.187906 -137.494518)
					(mid 281.026469 -137.104775)
					(end 280.636726 -136.943338)
				)
				(xy 279.236932 -136.943338)
			)
		)
	)
	(zone
		(layers "F.Cu" "In2.Cu" "In5.Cu")
		(hatch none 0.5)
		(connect_pads
			(clearance 0)
		)
		(min_thickness 0.25)
		(keepout
			(tracks not_allowed)
			(vias allowed)
			(pads allowed)
			(copperpour not_allowed)
			(footprints allowed)
		)
		(placement
			(enabled no)
			(sheetname "")
		)
		(fill yes
			(thermal_gap 0.5)
			(thermal_bridge_width 0.5)
			(island_removal_mode 0)
		)
		(polygon
			(pts
				(arc
					(start 279.236678 -227.345748)
					(mid 278.688038 -227.894388)
					(end 279.236678 -228.443028)
				)
				(arc
					(start 280.636726 -228.443028)
					(mid 281.023774 -228.283232)
					(end 281.185366 -227.896928)
				)
				(arc
					(start 281.030426 -227.896928)
					(mid 280.636726 -228.288096)
					(end 280.243026 -227.896928)
				)
				(arc
					(start 279.630378 -227.896928)
					(mid 279.236678 -228.288096)
					(end 278.842978 -227.896928)
				)
				(arc
					(start 278.842978 -227.894388)
					(mid 279.236678 -227.500688)
					(end 279.630378 -227.894388)
				)
				(arc
					(start 280.243026 -227.894388)
					(mid 280.636726 -227.500688)
					(end 281.030426 -227.894388)
				)
				(arc
					(start 281.185366 -227.894388)
					(mid 281.024673 -227.506441)
					(end 280.636726 -227.345748)
				)
			)
		)
	)
	(zone
		(layers "F.Cu" "In2.Cu" "In5.Cu")
		(hatch none 0.5)
		(connect_pads
			(clearance 0)
		)
		(min_thickness 0.25)
		(keepout
			(tracks not_allowed)
			(vias allowed)
			(pads allowed)
			(copperpour not_allowed)
			(footprints allowed)
		)
		(placement
			(enabled no)
			(sheetname "")
		)
		(fill yes
			(thermal_gap 0.5)
			(thermal_bridge_width 0.5)
			(island_removal_mode 0)
		)
		(polygon
			(pts
				(arc
					(start 278.23668 -189.545722)
					(mid 277.68804 -190.094362)
					(end 278.23668 -190.643002)
				)
				(arc
					(start 279.636728 -190.643002)
					(mid 280.023776 -190.483206)
					(end 280.185368 -190.096902)
				)
				(arc
					(start 280.030428 -190.096902)
					(mid 279.636728 -190.48807)
					(end 279.243028 -190.096902)
				)
				(arc
					(start 278.63038 -190.096902)
					(mid 278.23668 -190.48807)
					(end 277.84298 -190.096902)
				)
				(arc
					(start 277.84298 -190.094362)
					(mid 278.23668 -189.700662)
					(end 278.63038 -190.094362)
				)
				(arc
					(start 279.243028 -190.094362)
					(mid 279.636728 -189.700662)
					(end 280.030428 -190.094362)
				)
				(arc
					(start 280.185368 -190.094362)
					(mid 280.024675 -189.706415)
					(end 279.636728 -189.545722)
				)
			)
		)
	)
	(zone
		(layers "F.Cu" "In2.Cu" "In5.Cu")
		(hatch none 0.5)
		(connect_pads
			(clearance 0)
		)
		(min_thickness 0.25)
		(keepout
			(tracks not_allowed)
			(vias allowed)
			(pads allowed)
			(copperpour not_allowed)
			(footprints allowed)
		)
		(placement
			(enabled no)
			(sheetname "")
		)
		(fill yes
			(thermal_gap 0.5)
			(thermal_bridge_width 0.5)
			(island_removal_mode 0)
		)
		(polygon
			(pts
				(arc
					(start 278.23668 -138.745722)
					(mid 277.68804 -139.294362)
					(end 278.23668 -139.843002)
				)
				(arc
					(start 279.636728 -139.843002)
					(mid 280.023776 -139.683206)
					(end 280.185368 -139.296902)
				)
				(arc
					(start 280.030428 -139.296902)
					(mid 279.636728 -139.68807)
					(end 279.243028 -139.296902)
				)
				(arc
					(start 278.63038 -139.296902)
					(mid 278.23668 -139.68807)
					(end 277.84298 -139.296902)
				)
				(arc
					(start 277.84298 -139.294362)
					(mid 278.23668 -138.900662)
					(end 278.63038 -139.294362)
				)
				(arc
					(start 279.243028 -139.294362)
					(mid 279.636728 -138.900662)
					(end 280.030428 -139.294362)
				)
				(arc
					(start 280.185368 -139.294362)
					(mid 280.024675 -138.906415)
					(end 279.636728 -138.745722)
				)
			)
		)
	)
	(zone
		(layers "F.Cu" "In2.Cu" "In5.Cu")
		(hatch none 0.5)
		(connect_pads
			(clearance 0)
		)
		(min_thickness 0.25)
		(keepout
			(tracks not_allowed)
			(vias allowed)
			(pads allowed)
			(copperpour not_allowed)
			(footprints allowed)
		)
		(placement
			(enabled no)
			(sheetname "")
		)
		(fill yes
			(thermal_gap 0.5)
			(thermal_bridge_width 0.5)
			(island_removal_mode 0)
		)
		(polygon
			(pts
				(arc
					(start 278.23668 -178.745896)
					(mid 277.68804 -179.294536)
					(end 278.23668 -179.843176)
				)
				(arc
					(start 279.636728 -179.843176)
					(mid 280.023776 -179.68338)
					(end 280.185368 -179.297076)
				)
				(arc
					(start 280.030428 -179.297076)
					(mid 279.636728 -179.688244)
					(end 279.243028 -179.297076)
				)
				(arc
					(start 278.63038 -179.297076)
					(mid 278.23668 -179.688244)
					(end 277.84298 -179.297076)
				)
				(arc
					(start 277.84298 -179.294536)
					(mid 278.23668 -178.900836)
					(end 278.63038 -179.294536)
				)
				(arc
					(start 279.243028 -179.294536)
					(mid 279.636728 -178.900836)
					(end 280.030428 -179.294536)
				)
				(arc
					(start 280.185368 -179.294536)
					(mid 280.024675 -178.906589)
					(end 279.636728 -178.745896)
				)
			)
		)
	)
	(zone
		(layers "F.Cu" "In2.Cu" "In5.Cu")
		(hatch none 0.5)
		(connect_pads
			(clearance 0)
		)
		(min_thickness 0.25)
		(keepout
			(tracks not_allowed)
			(vias allowed)
			(pads allowed)
			(copperpour not_allowed)
			(footprints allowed)
		)
		(placement
			(enabled no)
			(sheetname "")
		)
		(fill yes
			(thermal_gap 0.5)
			(thermal_bridge_width 0.5)
			(island_removal_mode 0)
		)
		(polygon
			(pts
				(arc
					(start 221.348808 -77.600048)
					(mid 220.800168 -77.051408)
					(end 220.251528 -77.600048)
				)
				(arc
					(start 220.251528 -78.999842)
					(mid 220.798898 -79.548481)
					(end 221.348808 -79.002382)
				)
				(arc
					(start 221.193868 -79.002382)
					(mid 220.800168 -79.39355)
					(end 220.406468 -79.002382)
				)
				(arc
					(start 220.406468 -78.999842)
					(mid 220.800168 -78.606142)
					(end 221.193868 -78.999842)
				)
				(xy 221.348808 -78.999842) (xy 221.348808 -77.602588)
				(arc
					(start 221.193868 -77.602588)
					(mid 220.800168 -77.993756)
					(end 220.406468 -77.602588)
				)
				(arc
					(start 220.406468 -77.600048)
					(mid 220.800168 -77.206348)
					(end 221.193868 -77.600048)
				)
			)
		)
	)
	(zone
		(layers "F.Cu" "In2.Cu" "In5.Cu")
		(hatch none 0.5)
		(connect_pads
			(clearance 0)
		)
		(min_thickness 0.25)
		(keepout
			(tracks not_allowed)
			(vias allowed)
			(pads allowed)
			(copperpour not_allowed)
			(footprints allowed)
		)
		(placement
			(enabled no)
			(sheetname "")
		)
		(fill yes
			(thermal_gap 0.5)
			(thermal_bridge_width 0.5)
			(island_removal_mode 0)
		)
		(polygon
			(pts
				(arc
					(start 278.23668 -232.745788)
					(mid 277.68804 -233.294428)
					(end 278.23668 -233.843068)
				)
				(arc
					(start 279.636728 -233.843068)
					(mid 280.023776 -233.683272)
					(end 280.185368 -233.296968)
				)
				(arc
					(start 280.030428 -233.296968)
					(mid 279.636728 -233.688136)
					(end 279.243028 -233.296968)
				)
				(arc
					(start 278.63038 -233.296968)
					(mid 278.23668 -233.688136)
					(end 277.84298 -233.296968)
				)
				(arc
					(start 277.84298 -233.294428)
					(mid 278.23668 -232.900728)
					(end 278.63038 -233.294428)
				)
				(arc
					(start 279.243028 -233.294428)
					(mid 279.636728 -232.900728)
					(end 280.030428 -233.294428)
				)
				(arc
					(start 280.185368 -233.294428)
					(mid 280.024675 -232.906481)
					(end 279.636728 -232.745788)
				)
			)
		)
	)
	(zone
		(layers "F.Cu" "In2.Cu" "In5.Cu")
		(hatch none 0.5)
		(connect_pads
			(clearance 0)
		)
		(min_thickness 0.25)
		(keepout
			(tracks not_allowed)
			(vias allowed)
			(pads allowed)
			(copperpour not_allowed)
			(footprints allowed)
		)
		(placement
			(enabled no)
			(sheetname "")
		)
		(fill yes
			(thermal_gap 0.5)
			(thermal_bridge_width 0.5)
			(island_removal_mode 0)
		)
		(polygon
			(pts
				(arc
					(start 279.236678 -205.745842)
					(mid 278.688038 -206.294482)
					(end 279.236678 -206.843122)
				)
				(arc
					(start 280.636726 -206.843122)
					(mid 281.023774 -206.683326)
					(end 281.185366 -206.297022)
				)
				(arc
					(start 281.030426 -206.297022)
					(mid 280.636726 -206.68819)
					(end 280.243026 -206.297022)
				)
				(arc
					(start 279.630378 -206.297022)
					(mid 279.236678 -206.68819)
					(end 278.842978 -206.297022)
				)
				(arc
					(start 278.842978 -206.294482)
					(mid 279.236678 -205.900782)
					(end 279.630378 -206.294482)
				)
				(arc
					(start 280.243026 -206.294482)
					(mid 280.636726 -205.900782)
					(end 281.030426 -206.294482)
				)
				(arc
					(start 281.185366 -206.294482)
					(mid 281.024673 -205.906535)
					(end 280.636726 -205.745842)
				)
			)
		)
	)
	(zone
		(layers "F.Cu" "In2.Cu" "In5.Cu")
		(hatch none 0.5)
		(connect_pads
			(clearance 0)
		)
		(min_thickness 0.25)
		(keepout
			(tracks not_allowed)
			(vias allowed)
			(pads allowed)
			(copperpour not_allowed)
			(footprints allowed)
		)
		(placement
			(enabled no)
			(sheetname "")
		)
		(fill yes
			(thermal_gap 0.5)
			(thermal_bridge_width 0.5)
			(island_removal_mode 0)
		)
		(polygon
			(pts
				(arc
					(start 279.236678 -238.145828)
					(mid 278.688038 -238.694468)
					(end 279.236678 -239.243108)
				)
				(arc
					(start 280.636726 -239.243108)
					(mid 281.023774 -239.083312)
					(end 281.185366 -238.697008)
				)
				(arc
					(start 281.030426 -238.697008)
					(mid 280.636726 -239.088176)
					(end 280.243026 -238.697008)
				)
				(arc
					(start 279.630378 -238.697008)
					(mid 279.236678 -239.088176)
					(end 278.842978 -238.697008)
				)
				(arc
					(start 278.842978 -238.694468)
					(mid 279.236678 -238.300768)
					(end 279.630378 -238.694468)
				)
				(arc
					(start 280.243026 -238.694468)
					(mid 280.636726 -238.300768)
					(end 281.030426 -238.694468)
				)
				(arc
					(start 281.185366 -238.694468)
					(mid 281.024673 -238.306521)
					(end 280.636726 -238.145828)
				)
			)
		)
	)
	(zone
		(layers "F.Cu" "In2.Cu" "In5.Cu")
		(hatch none 0.5)
		(connect_pads
			(clearance 0)
		)
		(min_thickness 0.25)
		(keepout
			(tracks not_allowed)
			(vias allowed)
			(pads allowed)
			(copperpour not_allowed)
			(footprints allowed)
		)
		(placement
			(enabled no)
			(sheetname "")
		)
		(fill yes
			(thermal_gap 0.5)
			(thermal_bridge_width 0.5)
			(island_removal_mode 0)
		)
		(polygon
			(pts
				(arc
					(start 214.14867 -77.600048)
					(mid 213.60003 -77.051408)
					(end 213.05139 -77.600048)
				)
				(arc
					(start 213.05139 -78.999842)
					(mid 213.59876 -79.548481)
					(end 214.14867 -79.002382)
				)
				(arc
					(start 213.99373 -79.002382)
					(mid 213.60003 -79.39355)
					(end 213.20633 -79.002382)
				)
				(arc
					(start 213.20633 -78.999842)
					(mid 213.60003 -78.606142)
					(end 213.99373 -78.999842)
				)
				(xy 214.14867 -78.999842) (xy 214.14867 -77.602588)
				(arc
					(start 213.99373 -77.602588)
					(mid 213.60003 -77.993756)
					(end 213.20633 -77.602588)
				)
				(arc
					(start 213.20633 -77.600048)
					(mid 213.60003 -77.206348)
					(end 213.99373 -77.600048)
				)
			)
		)
	)
	(zone
		(layers "F.Cu" "In2.Cu" "In5.Cu")
		(hatch none 0.5)
		(connect_pads
			(clearance 0)
		)
		(min_thickness 0.25)
		(keepout
			(tracks not_allowed)
			(vias allowed)
			(pads allowed)
			(copperpour not_allowed)
			(footprints allowed)
		)
		(placement
			(enabled no)
			(sheetname "")
		)
		(fill yes
			(thermal_gap 0.5)
			(thermal_bridge_width 0.5)
			(island_removal_mode 0)
		)
		(polygon
			(pts
				(arc
					(start 279.236678 -144.145762)
					(mid 278.688038 -144.694402)
					(end 279.236678 -145.243042)
				)
				(arc
					(start 280.636726 -145.243042)
					(mid 281.023774 -145.083246)
					(end 281.185366 -144.696942)
				)
				(arc
					(start 281.030426 -144.696942)
					(mid 280.636726 -145.08811)
					(end 280.243026 -144.696942)
				)
				(arc
					(start 279.630378 -144.696942)
					(mid 279.236678 -145.08811)
					(end 278.842978 -144.696942)
				)
				(arc
					(start 278.842978 -144.694402)
					(mid 279.236678 -144.300702)
					(end 279.630378 -144.694402)
				)
				(arc
					(start 280.243026 -144.694402)
					(mid 280.636726 -144.300702)
					(end 281.030426 -144.694402)
				)
				(arc
					(start 281.185366 -144.694402)
					(mid 281.024673 -144.306455)
					(end 280.636726 -144.145762)
				)
			)
		)
	)
	(zone
		(layers "F.Cu" "In2.Cu" "In5.Cu")
		(hatch none 0.5)
		(connect_pads
			(clearance 0)
		)
		(min_thickness 0.25)
		(keepout
			(tracks not_allowed)
			(vias allowed)
			(pads allowed)
			(copperpour not_allowed)
			(footprints allowed)
		)
		(placement
			(enabled no)
			(sheetname "")
		)
		(fill yes
			(thermal_gap 0.5)
			(thermal_bridge_width 0.5)
			(island_removal_mode 0)
		)
		(polygon
			(pts
				(arc
					(start 278.23668 -193.145918)
					(mid 277.68804 -193.694558)
					(end 278.23668 -194.243198)
				)
				(arc
					(start 279.636728 -194.243198)
					(mid 280.023776 -194.083402)
					(end 280.185368 -193.697098)
				)
				(arc
					(start 280.030428 -193.697098)
					(mid 279.636728 -194.088266)
					(end 279.243028 -193.697098)
				)
				(arc
					(start 278.63038 -193.697098)
					(mid 278.23668 -194.088266)
					(end 277.84298 -193.697098)
				)
				(arc
					(start 277.84298 -193.694558)
					(mid 278.23668 -193.300858)
					(end 278.63038 -193.694558)
				)
				(arc
					(start 279.243028 -193.694558)
					(mid 279.636728 -193.300858)
					(end 280.030428 -193.694558)
				)
				(arc
					(start 280.185368 -193.694558)
					(mid 280.024675 -193.306611)
					(end 279.636728 -193.145918)
				)
			)
		)
	)
	(zone
		(layers "F.Cu" "In2.Cu" "In5.Cu")
		(hatch none 0.5)
		(connect_pads
			(clearance 0)
		)
		(min_thickness 0.25)
		(keepout
			(tracks not_allowed)
			(vias allowed)
			(pads allowed)
			(copperpour not_allowed)
			(footprints allowed)
		)
		(placement
			(enabled no)
			(sheetname "")
		)
		(fill yes
			(thermal_gap 0.5)
			(thermal_bridge_width 0.5)
			(island_removal_mode 0)
		)
		(polygon
			(pts
				(arc
					(start 278.23668 -236.34573)
					(mid 277.68804 -236.89437)
					(end 278.23668 -237.44301)
				)
				(arc
					(start 279.636728 -237.44301)
					(mid 280.023776 -237.283214)
					(end 280.185368 -236.89691)
				)
				(arc
					(start 280.030428 -236.89691)
					(mid 279.636728 -237.288078)
					(end 279.243028 -236.89691)
				)
				(arc
					(start 278.63038 -236.89691)
					(mid 278.23668 -237.288078)
					(end 277.84298 -236.89691)
				)
				(arc
					(start 277.84298 -236.89437)
					(mid 278.23668 -236.50067)
					(end 278.63038 -236.89437)
				)
				(arc
					(start 279.243028 -236.89437)
					(mid 279.636728 -236.50067)
					(end 280.030428 -236.89437)
				)
				(arc
					(start 280.185368 -236.89437)
					(mid 280.024675 -236.506423)
					(end 279.636728 -236.34573)
				)
			)
		)
	)
	(zone
		(layers "F.Cu" "In2.Cu" "In5.Cu")
		(hatch none 0.5)
		(connect_pads
			(clearance 0)
		)
		(min_thickness 0.25)
		(keepout
			(tracks not_allowed)
			(vias allowed)
			(pads allowed)
			(copperpour not_allowed)
			(footprints allowed)
		)
		(placement
			(enabled no)
			(sheetname "")
		)
		(fill yes
			(thermal_gap 0.5)
			(thermal_bridge_width 0.5)
			(island_removal_mode 0)
		)
		(polygon
			(pts
				(arc
					(start 278.23668 -218.345766)
					(mid 277.68804 -218.894406)
					(end 278.23668 -219.443046)
				)
				(arc
					(start 279.636728 -219.443046)
					(mid 280.023776 -219.28325)
					(end 280.185368 -218.896946)
				)
				(arc
					(start 280.030428 -218.896946)
					(mid 279.636728 -219.288114)
					(end 279.243028 -218.896946)
				)
				(arc
					(start 278.63038 -218.896946)
					(mid 278.23668 -219.288114)
					(end 277.84298 -218.896946)
				)
				(arc
					(start 277.84298 -218.894406)
					(mid 278.23668 -218.500706)
					(end 278.63038 -218.894406)
				)
				(arc
					(start 279.243028 -218.894406)
					(mid 279.636728 -218.500706)
					(end 280.030428 -218.894406)
				)
				(arc
					(start 280.185368 -218.894406)
					(mid 280.024675 -218.506459)
					(end 279.636728 -218.345766)
				)
			)
		)
	)
	(zone
		(layers "F.Cu" "In2.Cu" "In5.Cu")
		(hatch none 0.5)
		(connect_pads
			(clearance 0)
		)
		(min_thickness 0.25)
		(keepout
			(tracks not_allowed)
			(vias allowed)
			(pads allowed)
			(copperpour not_allowed)
			(footprints allowed)
		)
		(placement
			(enabled no)
			(sheetname "")
		)
		(fill yes
			(thermal_gap 0.5)
			(thermal_bridge_width 0.5)
			(island_removal_mode 0)
		)
		(polygon
			(pts
				(arc
					(start 278.23668 -182.345838)
					(mid 277.68804 -182.894478)
					(end 278.23668 -183.443118)
				)
				(arc
					(start 279.636728 -183.443118)
					(mid 280.023776 -183.283322)
					(end 280.185368 -182.897018)
				)
				(arc
					(start 280.030428 -182.897018)
					(mid 279.636728 -183.288186)
					(end 279.243028 -182.897018)
				)
				(arc
					(start 278.63038 -182.897018)
					(mid 278.23668 -183.288186)
					(end 277.84298 -182.897018)
				)
				(arc
					(start 277.84298 -182.894478)
					(mid 278.23668 -182.500778)
					(end 278.63038 -182.894478)
				)
				(arc
					(start 279.243028 -182.894478)
					(mid 279.636728 -182.500778)
					(end 280.030428 -182.894478)
				)
				(arc
					(start 280.185368 -182.894478)
					(mid 280.024675 -182.506531)
					(end 279.636728 -182.345838)
				)
			)
		)
	)
	(zone
		(layers "F.Cu" "In2.Cu" "In5.Cu")
		(hatch none 0.5)
		(connect_pads
			(clearance 0)
		)
		(min_thickness 0.25)
		(keepout
			(tracks not_allowed)
			(vias allowed)
			(pads allowed)
			(copperpour not_allowed)
			(footprints allowed)
		)
		(placement
			(enabled no)
			(sheetname "")
		)
		(fill yes
			(thermal_gap 0.5)
			(thermal_bridge_width 0.5)
			(island_removal_mode 0)
		)
		(polygon
			(pts
				(arc
					(start 278.23668 -135.14578)
					(mid 277.68804 -135.69442)
					(end 278.23668 -136.24306)
				)
				(arc
					(start 279.636728 -136.24306)
					(mid 280.023776 -136.083264)
					(end 280.185368 -135.69696)
				)
				(arc
					(start 280.030428 -135.69696)
					(mid 279.636728 -136.088128)
					(end 279.243028 -135.69696)
				)
				(arc
					(start 278.63038 -135.69696)
					(mid 278.23668 -136.088128)
					(end 277.84298 -135.69696)
				)
				(arc
					(start 277.84298 -135.69442)
					(mid 278.23668 -135.30072)
					(end 278.63038 -135.69442)
				)
				(arc
					(start 279.243028 -135.69442)
					(mid 279.636728 -135.30072)
					(end 280.030428 -135.69442)
				)
				(arc
					(start 280.185368 -135.69442)
					(mid 280.024675 -135.306473)
					(end 279.636728 -135.14578)
				)
			)
		)
	)
	(zone
		(layers "F.Cu" "In2.Cu" "In5.Cu")
		(hatch none 0.5)
		(connect_pads
			(clearance 0)
		)
		(min_thickness 0.25)
		(keepout
			(tracks not_allowed)
			(vias allowed)
			(pads allowed)
			(copperpour not_allowed)
			(footprints allowed)
		)
		(placement
			(enabled no)
			(sheetname "")
		)
		(fill yes
			(thermal_gap 0.5)
			(thermal_bridge_width 0.5)
			(island_removal_mode 0)
		)
		(polygon
			(pts
				(arc
					(start 210.548728 -77.600048)
					(mid 210.000088 -77.051408)
					(end 209.451448 -77.600048)
				)
				(arc
					(start 209.451448 -78.999842)
					(mid 209.998818 -79.548481)
					(end 210.548728 -79.002382)
				)
				(arc
					(start 210.393788 -79.002382)
					(mid 210.000088 -79.39355)
					(end 209.606388 -79.002382)
				)
				(arc
					(start 209.606388 -78.999842)
					(mid 210.000088 -78.606142)
					(end 210.393788 -78.999842)
				)
				(xy 210.548728 -78.999842) (xy 210.548728 -77.602588)
				(arc
					(start 210.393788 -77.602588)
					(mid 210.000088 -77.993756)
					(end 209.606388 -77.602588)
				)
				(arc
					(start 209.606388 -77.600048)
					(mid 210.000088 -77.206348)
					(end 210.393788 -77.600048)
				)
			)
		)
	)
	(zone
		(layers "F.Cu" "In2.Cu" "In5.Cu")
		(hatch none 0.5)
		(connect_pads
			(clearance 0)
		)
		(min_thickness 0.25)
		(keepout
			(tracks not_allowed)
			(vias allowed)
			(pads allowed)
			(copperpour not_allowed)
			(footprints allowed)
		)
		(placement
			(enabled no)
			(sheetname "")
		)
		(fill yes
			(thermal_gap 0.5)
			(thermal_bridge_width 0.5)
			(island_removal_mode 0)
		)
		(polygon
			(pts
				(arc
					(start 278.23668 -185.94578)
					(mid 277.68804 -186.49442)
					(end 278.23668 -187.04306)
				)
				(arc
					(start 279.636728 -187.04306)
					(mid 280.023776 -186.883264)
					(end 280.185368 -186.49696)
				)
				(arc
					(start 280.030428 -186.49696)
					(mid 279.636728 -186.888128)
					(end 279.243028 -186.49696)
				)
				(arc
					(start 278.63038 -186.49696)
					(mid 278.23668 -186.888128)
					(end 277.84298 -186.49696)
				)
				(arc
					(start 277.84298 -186.49442)
					(mid 278.23668 -186.10072)
					(end 278.63038 -186.49442)
				)
				(arc
					(start 279.243028 -186.49442)
					(mid 279.636728 -186.10072)
					(end 280.030428 -186.49442)
				)
				(arc
					(start 280.185368 -186.49442)
					(mid 280.024675 -186.106473)
					(end 279.636728 -185.94578)
				)
			)
		)
	)
	(zone
		(layers "F.Cu" "In2.Cu" "In5.Cu")
		(hatch none 0.5)
		(connect_pads
			(clearance 0)
		)
		(min_thickness 0.25)
		(keepout
			(tracks not_allowed)
			(vias allowed)
			(pads allowed)
			(copperpour not_allowed)
			(footprints allowed)
		)
		(placement
			(enabled no)
			(sheetname "")
		)
		(fill yes
			(thermal_gap 0.5)
			(thermal_bridge_width 0.5)
			(island_removal_mode 0)
		)
		(polygon
			(pts
				(arc
					(start 279.236678 -140.54582)
					(mid 278.688038 -141.09446)
					(end 279.236678 -141.6431)
				)
				(arc
					(start 280.636726 -141.6431)
					(mid 281.023774 -141.483304)
					(end 281.185366 -141.097)
				)
				(arc
					(start 281.030426 -141.097)
					(mid 280.636726 -141.488168)
					(end 280.243026 -141.097)
				)
				(arc
					(start 279.630378 -141.097)
					(mid 279.236678 -141.488168)
					(end 278.842978 -141.097)
				)
				(arc
					(start 278.842978 -141.09446)
					(mid 279.236678 -140.70076)
					(end 279.630378 -141.09446)
				)
				(arc
					(start 280.243026 -141.09446)
					(mid 280.636726 -140.70076)
					(end 281.030426 -141.09446)
				)
				(arc
					(start 281.185366 -141.09446)
					(mid 281.024673 -140.706513)
					(end 280.636726 -140.54582)
				)
			)
		)
	)
	(zone
		(layers "F.Cu" "In2.Cu" "In5.Cu")
		(hatch none 0.5)
		(connect_pads
			(clearance 0)
		)
		(min_thickness 0.25)
		(keepout
			(tracks not_allowed)
			(vias allowed)
			(pads allowed)
			(copperpour not_allowed)
			(footprints allowed)
		)
		(placement
			(enabled no)
			(sheetname "")
		)
		(fill yes
			(thermal_gap 0.5)
			(thermal_bridge_width 0.5)
			(island_removal_mode 0)
		)
		(polygon
			(pts
				(arc
					(start 278.23668 -225.545904)
					(mid 277.68804 -226.094544)
					(end 278.23668 -226.643184)
				)
				(arc
					(start 279.636728 -226.643184)
					(mid 280.023776 -226.483388)
					(end 280.185368 -226.097084)
				)
				(arc
					(start 280.030428 -226.097084)
					(mid 279.636728 -226.488252)
					(end 279.243028 -226.097084)
				)
				(arc
					(start 278.63038 -226.097084)
					(mid 278.23668 -226.488252)
					(end 277.84298 -226.097084)
				)
				(arc
					(start 277.84298 -226.094544)
					(mid 278.23668 -225.700844)
					(end 278.63038 -226.094544)
				)
				(arc
					(start 279.243028 -226.094544)
					(mid 279.636728 -225.700844)
					(end 280.030428 -226.094544)
				)
				(arc
					(start 280.185368 -226.094544)
					(mid 280.024675 -225.706597)
					(end 279.636728 -225.545904)
				)
			)
		)
	)
	(zone
		(layers "F.Cu" "In2.Cu" "In5.Cu")
		(hatch none 0.5)
		(connect_pads
			(clearance 0)
		)
		(min_thickness 0.25)
		(keepout
			(tracks not_allowed)
			(vias allowed)
			(pads allowed)
			(copperpour not_allowed)
			(footprints allowed)
		)
		(placement
			(enabled no)
			(sheetname "")
		)
		(fill yes
			(thermal_gap 0.5)
			(thermal_bridge_width 0.5)
			(island_removal_mode 0)
		)
		(polygon
			(pts
				(arc
					(start 279.236678 -187.745878)
					(mid 278.688038 -188.294518)
					(end 279.236678 -188.843158)
				)
				(arc
					(start 280.636726 -188.843158)
					(mid 281.023774 -188.683362)
					(end 281.185366 -188.297058)
				)
				(arc
					(start 281.030426 -188.297058)
					(mid 280.636726 -188.688226)
					(end 280.243026 -188.297058)
				)
				(arc
					(start 279.630378 -188.297058)
					(mid 279.236678 -188.688226)
					(end 278.842978 -188.297058)
				)
				(arc
					(start 278.842978 -188.294518)
					(mid 279.236678 -187.900818)
					(end 279.630378 -188.294518)
				)
				(arc
					(start 280.243026 -188.294518)
					(mid 280.636726 -187.900818)
					(end 281.030426 -188.294518)
				)
				(arc
					(start 281.185366 -188.294518)
					(mid 281.024673 -187.906571)
					(end 280.636726 -187.745878)
				)
			)
		)
	)
	(zone
		(layers "F.Cu" "In2.Cu" "In5.Cu")
		(hatch none 0.5)
		(connect_pads
			(clearance 0)
		)
		(min_thickness 0.25)
		(keepout
			(tracks not_allowed)
			(vias allowed)
			(pads allowed)
			(copperpour not_allowed)
			(footprints allowed)
		)
		(placement
			(enabled no)
			(sheetname "")
		)
		(fill yes
			(thermal_gap 0.5)
			(thermal_bridge_width 0.5)
			(island_removal_mode 0)
		)
		(polygon
			(pts
				(arc
					(start 278.23668 -175.145954)
					(mid 277.68804 -175.694594)
					(end 278.23668 -176.243234)
				)
				(arc
					(start 279.636728 -176.243234)
					(mid 280.023776 -176.083438)
					(end 280.185368 -175.697134)
				)
				(arc
					(start 280.030428 -175.697134)
					(mid 279.636728 -176.088302)
					(end 279.243028 -175.697134)
				)
				(arc
					(start 278.63038 -175.697134)
					(mid 278.23668 -176.088302)
					(end 277.84298 -175.697134)
				)
				(arc
					(start 277.84298 -175.694594)
					(mid 278.23668 -175.300894)
					(end 278.63038 -175.694594)
				)
				(arc
					(start 279.243028 -175.694594)
					(mid 279.636728 -175.300894)
					(end 280.030428 -175.694594)
				)
				(arc
					(start 280.185368 -175.694594)
					(mid 280.024675 -175.306647)
					(end 279.636728 -175.145954)
				)
			)
		)
	)
	(zone
		(layers "F.Cu" "In2.Cu" "In5.Cu")
		(hatch none 0.5)
		(connect_pads
			(clearance 0)
		)
		(min_thickness 0.25)
		(keepout
			(tracks not_allowed)
			(vias allowed)
			(pads allowed)
			(copperpour not_allowed)
			(footprints allowed)
		)
		(placement
			(enabled no)
			(sheetname "")
		)
		(fill yes
			(thermal_gap 0.5)
			(thermal_bridge_width 0.5)
			(island_removal_mode 0)
		)
		(polygon
			(pts
				(arc
					(start 210.548728 -73.999852)
					(mid 210.000088 -73.451212)
					(end 209.451448 -73.999852)
				)
				(arc
					(start 209.451448 -75.399646)
					(mid 209.998691 -75.948538)
					(end 210.548728 -75.40244)
				)
				(arc
					(start 210.393788 -75.40244)
					(mid 210.000088 -75.793608)
					(end 209.606388 -75.40244)
				)
				(arc
					(start 209.606388 -75.3999)
					(mid 210.000088 -75.0062)
					(end 210.393788 -75.3999)
				)
				(xy 210.548728 -75.3999) (xy 210.548728 -74.002392)
				(arc
					(start 210.393788 -74.002392)
					(mid 210.000088 -74.39356)
					(end 209.606388 -74.002392)
				)
				(arc
					(start 209.606388 -73.999852)
					(mid 210.000088 -73.606152)
					(end 210.393788 -73.999852)
				)
			)
		)
	)
	(zone
		(layer "B.Cu")
		(hatch none 0.5)
		(connect_pads
			(clearance 0)
		)
		(min_thickness 0.25)
		(keepout
			(tracks not_allowed)
			(vias allowed)
			(pads allowed)
			(copperpour not_allowed)
			(footprints allowed)
		)
		(placement
			(enabled no)
			(sheetname "")
		)
		(fill
			(thermal_gap 0.5)
			(thermal_bridge_width 0.5)
			(island_removal_mode 0)
		)
		(polygon
			(pts
				(arc
					(start 414.527492 -244.444774)
					(mid 414.042352 -243.959634)
					(end 413.557212 -244.444774)
				)
				(xy 413.557212 -244.794024)
				(arc
					(start 413.907224 -244.794024)
					(mid 413.948892 -244.776764)
					(end 413.966152 -244.735096)
				)
				(arc
					(start 413.966152 -244.700298)
					(mid 414.042352 -244.17813)
					(end 414.118552 -244.700298)
				)
				(xy 414.118552 -244.766592)
				(arc
					(start 414.115758 -244.769386)
					(mid 414.05666 -244.884532)
					(end 413.941514 -244.94363)
				)
				(xy 413.93872 -244.946424) (xy 413.557212 -244.946424) (xy 413.557212 -245.086124) (xy 413.93872 -245.086124)
				(arc
					(start 413.941514 -245.088918)
					(mid 414.05666 -245.148016)
					(end 414.115758 -245.263162)
				)
				(xy 414.118552 -245.265956)
				(arc
					(start 414.118552 -245.33225)
					(mid 414.042352 -245.854418)
					(end 413.966152 -245.33225)
				)
				(arc
					(start 413.966152 -245.297452)
					(mid 413.948892 -245.255784)
					(end 413.907224 -245.238524)
				)
				(xy 413.557212 -245.238524)
				(arc
					(start 413.557212 -245.58752)
					(mid 414.042225 -246.072914)
					(end 414.527492 -245.587774)
				)
			)
		)
	)
	(zone
		(layer "B.Cu")
		(hatch none 0.5)
		(connect_pads
			(clearance 0)
		)
		(min_thickness 0.25)
		(keepout
			(tracks not_allowed)
			(vias allowed)
			(pads allowed)
			(copperpour not_allowed)
			(footprints allowed)
		)
		(placement
			(enabled no)
			(sheetname "")
		)
		(fill
			(thermal_gap 0.5)
			(thermal_bridge_width 0.5)
			(island_removal_mode 0)
		)
		(polygon
			(pts
				(arc
					(start 40.32504 -178.799998)
					(mid 33.325054 -171.800012)
					(end 26.325068 -178.799998)
				)
				(arc
					(start 26.325068 -184.799986)
					(mid 33.325054 -191.799972)
					(end 40.32504 -184.799986)
				)
			)
		)
	)
	(zone
		(layer "B.Cu")
		(hatch none 0.5)
		(connect_pads
			(clearance 0)
		)
		(min_thickness 0.25)
		(keepout
			(tracks not_allowed)
			(vias allowed)
			(pads allowed)
			(copperpour not_allowed)
			(footprints allowed)
		)
		(placement
			(enabled no)
			(sheetname "")
		)
		(fill
			(thermal_gap 0.5)
			(thermal_bridge_width 0.5)
			(island_removal_mode 0)
		)
		(polygon
			(pts
				(arc
					(start 102.350062 -23.999952)
					(mid 107.100116 -28.750006)
					(end 111.849916 -23.999952)
				)
				(arc
					(start 111.849916 -23.999952)
					(mid 107.100116 -19.250152)
					(end 102.350062 -23.999952)
				)
			)
		)
	)
	(zone
		(net "GND")
		(layer "B.Cu")
		(hatch none 0.5)
		(connect_pads
			(clearance 0.5)
		)
		(min_thickness 0.25)
		(fill yes
			(thermal_gap 0.5)
			(thermal_bridge_width 0.5)
			(island_removal_mode 0)
		)
		(polygon
			(pts
				(xy 371.10289 -166.653718) (xy 383.262124 -158.760922) (xy 384.762502 -157.260544)
				(arc
					(start 384.762502 -156.867352)
					(mid 384.688674 -156.423913)
					(end 384.66395 -155.97505)
				)
				(arc
					(start 384.66395 -153.43505)
					(mid 384.685227 -153.018611)
					(end 384.748786 -152.606502)
				)
				(xy 384.748786 -151.55672)
				(arc
					(start 382.372108 -149.180042)
					(mid 381.798903 -148.905919)
					(end 381.275082 -148.546312)
				)
				(xy 379.853444 -148.546312) (xy 379.764798 -148.565108) (xy 369.700302 -164.063172) (xy 369.700302 -166.208456)
				(xy 370.145564 -166.653718)
			)
		)
	)
	(zone
		(layer "B.Cu")
		(hatch none 0.5)
		(connect_pads
			(clearance 0)
		)
		(min_thickness 0.25)
		(keepout
			(tracks not_allowed)
			(vias allowed)
			(pads allowed)
			(copperpour not_allowed)
			(footprints allowed)
		)
		(placement
			(enabled no)
			(sheetname "")
		)
		(fill
			(thermal_gap 0.5)
			(thermal_bridge_width 0.5)
			(island_removal_mode 0)
		)
		(polygon
			(pts
				(arc
					(start 337.674966 -293.800022)
					(mid 330.67498 -286.800036)
					(end 323.674994 -293.800022)
				)
				(arc
					(start 323.674994 -299.80001)
					(mid 330.67498 -306.799996)
					(end 337.674966 -299.80001)
				)
			)
		)
	)
	(zone
		(layer "B.Cu")
		(hatch none 0.5)
		(connect_pads
			(clearance 0)
		)
		(min_thickness 0.25)
		(keepout
			(tracks not_allowed)
			(vias allowed)
			(pads allowed)
			(copperpour not_allowed)
			(footprints allowed)
		)
		(placement
			(enabled no)
			(sheetname "")
		)
		(fill
			(thermal_gap 0.5)
			(thermal_bridge_width 0.5)
			(island_removal_mode 0)
		)
		(polygon
			(pts
				(arc
					(start 210.548728 -73.999852)
					(mid 210.000088 -73.451212)
					(end 209.451448 -73.999852)
				)
				(arc
					(start 209.451448 -74.470768)
					(mid 209.496863 -74.463729)
					(end 209.542634 -74.459592)
				)
				(xy 209.543904 -74.458576)
				(arc
					(start 209.811874 -74.458576)
					(mid 209.87176 -74.436795)
					(end 209.903568 -74.381614)
				)
				(arc
					(start 209.903568 -74.381614)
					(mid 210.000234 -73.60614)
					(end 210.095338 -74.381868)
				)
				(xy 210.095338 -74.404982)
				(arc
					(start 210.092036 -74.408284)
					(mid 210.012263 -74.566001)
					(end 209.854546 -74.645774)
				)
				(xy 209.851244 -74.649076)
				(arc
					(start 209.583274 -74.649076)
					(mid 209.516847 -74.653224)
					(end 209.451448 -74.665586)
				)
				(arc
					(start 209.451448 -74.77125)
					(mid 209.496163 -74.759555)
					(end 209.541872 -74.752708)
				)
				(xy 209.543904 -74.750676) (xy 209.851244 -74.750676)
				(arc
					(start 209.854546 -74.753978)
					(mid 210.012263 -74.833751)
					(end 210.092036 -74.991468)
				)
				(xy 210.095338 -74.99477)
				(arc
					(start 210.095338 -75.017884)
					(mid 210.000234 -75.793673)
					(end 209.903568 -75.018138)
				)
				(arc
					(start 209.903568 -75.018138)
					(mid 209.8717 -74.963029)
					(end 209.811874 -74.941176)
				)
				(arc
					(start 209.583274 -74.941176)
					(mid 209.514518 -74.951157)
					(end 209.451448 -74.980292)
				)
				(arc
					(start 209.451448 -75.399646)
					(mid 209.999961 -75.94854)
					(end 210.548728 -75.3999)
				)
			)
		)
	)
	(zone
		(layer "B.Cu")
		(hatch none 0.5)
		(connect_pads
			(clearance 0)
		)
		(min_thickness 0.25)
		(keepout
			(tracks allowed)
			(vias allowed)
			(pads allowed)
			(copperpour allowed)
			(footprints allowed)
		)
		(placement
			(enabled no)
			(sheetname "")
		)
		(fill
			(thermal_gap 0.5)
			(thermal_bridge_width 0.5)
			(island_removal_mode 0)
		)
		(polygon
			(pts
				(xy 425.734226 -113.852198) (xy 425.734226 -111.701326) (xy 433.899564 -111.701326) (xy 433.899564 -113.852198)
			)
		)
	)
	(zone
		(net "P12V_B")
		(layer "B.Cu")
		(hatch none 0.5)
		(connect_pads
			(clearance 0.5)
		)
		(min_thickness 0.25)
		(fill yes
			(thermal_gap 0.5)
			(thermal_bridge_width 0.5)
			(island_removal_mode 0)
		)
		(polygon
			(pts
				(xy 31.301944 -107.839256) (xy 30.7086 -108.4326) (xy 30.7086 -111.2774) (xy 31.461456 -112.030256)
				(xy 33.915858 -112.030256) (xy 34.036 -111.910114) (xy 34.036 -110.109) (xy 34.601658 -109.543342)
				(xy 34.601658 -108.067856) (xy 34.373058 -107.839256)
			)
		)
		(polygon
			(pts
				(xy 33.24606 -110.995206) (xy 33.04286 -110.995206) (xy 33.04286 -111.198406) (xy 33.24606 -111.198406)
			)
		)
		(polygon
			(pts
				(xy 33.38576 -109.585506) (xy 33.18256 -109.585506) (xy 33.18256 -109.788706) (xy 33.38576 -109.788706)
			)
		)
		(polygon
			(pts
				(xy 33.38576 -108.188506) (xy 33.18256 -108.188506) (xy 33.18256 -108.391706) (xy 33.38576 -108.391706)
			)
		)
	)
	(zone
		(net "MB0_12V_CTRL_GATE5")
		(layer "B.Cu")
		(hatch none 0.5)
		(connect_pads
			(clearance 0.5)
		)
		(min_thickness 0.25)
		(fill yes
			(thermal_gap 0.5)
			(thermal_bridge_width 0.5)
			(island_removal_mode 0)
		)
		(polygon
			(pts
				(xy 205.232254 -347.599) (xy 204.9272 -347.904308) (xy 204.9272 -352.2218) (xy 205.0034 -352.298)
				(xy 206.502 -352.298) (xy 206.629 -352.171) (xy 206.629 -347.853) (xy 206.375 -347.599)
			)
		)
	)
	(zone
		(layer "B.Cu")
		(hatch none 0.5)
		(connect_pads
			(clearance 0)
		)
		(min_thickness 0.25)
		(keepout
			(tracks not_allowed)
			(vias allowed)
			(pads allowed)
			(copperpour not_allowed)
			(footprints allowed)
		)
		(placement
			(enabled no)
			(sheetname "")
		)
		(fill
			(thermal_gap 0.5)
			(thermal_bridge_width 0.5)
			(island_removal_mode 0)
		)
		(polygon
			(pts
				(arc
					(start 39.250112 -13.999972)
					(mid 44.000166 -18.750026)
					(end 48.749966 -13.999972)
				)
				(arc
					(start 48.749966 -13.999972)
					(mid 44.000166 -9.250172)
					(end 39.250112 -13.999972)
				)
			)
		)
	)
	(zone
		(net "GND")
		(layer "B.Cu")
		(hatch none 0.5)
		(connect_pads
			(clearance 0.5)
		)
		(min_thickness 0.25)
		(fill yes
			(thermal_gap 0.5)
			(thermal_bridge_width 0.5)
			(island_removal_mode 0)
		)
		(polygon
			(pts
				(xy 320.883788 -51.751992) (xy 320.684144 -54.20741) (xy 321.340226 -54.863492) (xy 323.892164 -54.863492)
				(xy 324.152514 -54.603142)
				(arc
					(start 324.152514 -53.227986)
					(mid 323.731147 -52.524568)
					(end 323.458586 -51.75123)
				)
				(arc
					(start 323.458586 -51.75123)
					(mid 323.005895 -51.477221)
					(end 322.588636 -51.15179)
				)
				(xy 321.48399 -51.15179)
			)
		)
	)
	(zone
		(layer "B.Cu")
		(hatch none 0.5)
		(connect_pads
			(clearance 0)
		)
		(min_thickness 0.25)
		(keepout
			(tracks not_allowed)
			(vias allowed)
			(pads allowed)
			(copperpour not_allowed)
			(footprints allowed)
		)
		(placement
			(enabled no)
			(sheetname "")
		)
		(fill
			(thermal_gap 0.5)
			(thermal_bridge_width 0.5)
			(island_removal_mode 0)
		)
		(polygon
			(pts
				(arc
					(start 166.325042 -63.799974)
					(mid 159.325056 -56.799988)
					(end 152.32507 -63.799974)
				)
				(arc
					(start 152.32507 -69.799962)
					(mid 159.325056 -76.799948)
					(end 166.325042 -69.799962)
				)
			)
		)
	)
	(zone
		(layer "B.Cu")
		(hatch none 0.5)
		(connect_pads
			(clearance 0)
		)
		(min_thickness 0.25)
		(keepout
			(tracks not_allowed)
			(vias allowed)
			(pads allowed)
			(copperpour not_allowed)
			(footprints allowed)
		)
		(placement
			(enabled no)
			(sheetname "")
		)
		(fill
			(thermal_gap 0.5)
			(thermal_bridge_width 0.5)
			(island_removal_mode 0)
		)
		(polygon
			(pts
				(arc
					(start 160.970722 -129.419604)
					(mid 160.485709 -128.93421)
					(end 160.000442 -129.41935)
				)
				(arc
					(start 160.000442 -130.56235)
					(mid 160.485582 -131.04749)
					(end 160.970722 -130.56235)
				)
				(xy 160.970722 -130.24612) (xy 160.919922 -130.2131)
				(arc
					(start 160.629854 -130.2131)
					(mid 160.58172 -130.233038)
					(end 160.561782 -130.281172)
				)
				(arc
					(start 160.561782 -130.306826)
					(mid 160.485582 -130.828994)
					(end 160.409382 -130.306826)
				)
				(xy 160.409382 -130.249676)
				(arc
					(start 160.412176 -130.246882)
					(mid 160.474034 -130.125352)
					(end 160.595564 -130.063494)
				)
				(xy 160.598358 -130.0607) (xy 160.934654 -130.0607) (xy 160.957514 -130.055874) (xy 160.965134 -130.0607)
				(xy 160.970722 -130.0607) (xy 160.970722 -129.921) (xy 160.588706 -129.921)
				(arc
					(start 160.585912 -129.918206)
					(mid 160.47112 -129.859262)
					(end 160.412176 -129.74447)
				)
				(xy 160.409382 -129.741676)
				(arc
					(start 160.409382 -129.674874)
					(mid 160.485582 -129.152706)
					(end 160.561782 -129.674874)
				)
				(arc
					(start 160.561782 -129.71018)
					(mid 160.578893 -129.751489)
					(end 160.620202 -129.7686)
				)
				(xy 160.970722 -129.7686)
			)
		)
	)
	(zone
		(net "GND")
		(layer "B.Cu")
		(hatch none 0.5)
		(connect_pads
			(clearance 0.5)
		)
		(min_thickness 0.25)
		(fill yes
			(thermal_gap 0.5)
			(thermal_bridge_width 0.5)
			(island_removal_mode 0)
		)
		(polygon
			(pts
				(xy 329.745848 -148.364702)
				(arc
					(start 330.962762 -149.581616)
					(mid 331.385329 -149.616863)
					(end 331.801978 -149.695662)
				)
				(arc
					(start 331.801978 -149.695662)
					(mid 332.53355 -149.385682)
					(end 333.311246 -149.222968)
				)
				(xy 333.852774 -148.68144) (xy 333.852774 -148.333714)
				(arc
					(start 333.177388 -147.658328)
					(mid 330.68179 -143.815321)
					(end 333.31785 -140.067284)
				)
				(xy 334.872076 -138.513058)
				(arc
					(start 334.872076 -137.033)
					(mid 334.962929 -136.175625)
					(end 335.231486 -135.356346)
				)
				(xy 334.947006 -135.071866)
				(arc
					(start 334.508094 -135.071866)
					(mid 334.385292 -135.236981)
					(end 334.254348 -135.395716)
				)
				(arc
					(start 334.254348 -135.395716)
					(mid 333.262839 -138.368844)
					(end 330.458064 -139.76731)
				)
				(xy 328.908918 -141.316456)
				(arc
					(start 328.908918 -143.335756)
					(mid 329.530985 -144.506675)
					(end 329.745848 -145.81505)
				)
				(xy 329.745848 -148.355304)
			)
		)
	)
	(zone
		(layer "B.Cu")
		(hatch none 0.5)
		(connect_pads
			(clearance 0)
		)
		(min_thickness 0.25)
		(keepout
			(tracks not_allowed)
			(vias allowed)
			(pads allowed)
			(copperpour not_allowed)
			(footprints allowed)
		)
		(placement
			(enabled no)
			(sheetname "")
		)
		(fill
			(thermal_gap 0.5)
			(thermal_bridge_width 0.5)
			(island_removal_mode 0)
		)
		(polygon
			(pts
				(arc
					(start 215.948768 -76.399898)
					(mid 215.400128 -75.851258)
					(end 214.851488 -76.399898)
				)
				(arc
					(start 214.851488 -77.799692)
					(mid 215.400001 -78.348586)
					(end 215.948768 -77.799946)
				)
				(arc
					(start 215.948768 -77.380338)
					(mid 215.885693 -77.351221)
					(end 215.816942 -77.341222)
				)
				(arc
					(start 215.588342 -77.341222)
					(mid 215.528456 -77.363003)
					(end 215.496648 -77.418184)
				)
				(arc
					(start 215.496648 -77.418184)
					(mid 215.399982 -78.193658)
					(end 215.304878 -77.41793)
				)
				(xy 215.304878 -77.394816)
				(arc
					(start 215.30818 -77.391514)
					(mid 215.387953 -77.233797)
					(end 215.54567 -77.154024)
				)
				(xy 215.548972 -77.150722) (xy 215.856312 -77.150722)
				(arc
					(start 215.858344 -77.152754)
					(mid 215.904052 -77.159607)
					(end 215.948768 -77.171296)
				)
				(arc
					(start 215.948768 -77.065632)
					(mid 215.883371 -77.053251)
					(end 215.816942 -77.049122)
				)
				(xy 215.548972 -77.049122)
				(arc
					(start 215.54567 -77.04582)
					(mid 215.387953 -76.966047)
					(end 215.30818 -76.80833)
				)
				(xy 215.304878 -76.805028)
				(arc
					(start 215.304878 -76.781914)
					(mid 215.399982 -76.006125)
					(end 215.496648 -76.78166)
				)
				(arc
					(start 215.496648 -76.78166)
					(mid 215.528516 -76.836769)
					(end 215.588342 -76.858622)
				)
				(xy 215.856312 -76.858622)
				(arc
					(start 215.857582 -76.859638)
					(mid 215.903352 -76.863783)
					(end 215.948768 -76.870814)
				)
			)
		)
	)
	(zone
		(layer "B.Cu")
		(hatch none 0.5)
		(connect_pads
			(clearance 0)
		)
		(min_thickness 0.25)
		(keepout
			(tracks allowed)
			(vias allowed)
			(pads allowed)
			(copperpour allowed)
			(footprints allowed)
		)
		(placement
			(enabled no)
			(sheetname "")
		)
		(fill
			(thermal_gap 0.5)
			(thermal_bridge_width 0.5)
			(island_removal_mode 0)
		)
		(polygon
			(pts
				(xy 453.6186 -225.6282) (xy 455.3966 -225.6282) (xy 455.3966 -227.203) (xy 453.6186 -227.203)
			)
		)
	)
	(zone
		(layer "B.Cu")
		(hatch none 0.5)
		(connect_pads
			(clearance 0)
		)
		(min_thickness 0.25)
		(keepout
			(tracks not_allowed)
			(vias allowed)
			(pads allowed)
			(copperpour not_allowed)
			(footprints allowed)
		)
		(placement
			(enabled no)
			(sheetname "")
		)
		(fill
			(thermal_gap 0.5)
			(thermal_bridge_width 0.5)
			(island_removal_mode 0)
		)
		(polygon
			(pts
				(arc
					(start 210.548728 -77.600302)
					(mid 210.000215 -77.051408)
					(end 209.451448 -77.600048)
				)
				(arc
					(start 209.451448 -78.999842)
					(mid 210.000088 -79.548482)
					(end 210.548728 -78.999842)
				)
				(arc
					(start 210.548728 -78.551786)
					(mid 210.519742 -78.543802)
					(end 210.4898 -78.541118)
				)
				(arc
					(start 210.188302 -78.541118)
					(mid 210.128416 -78.562899)
					(end 210.096608 -78.61808)
				)
				(arc
					(start 210.096608 -78.61808)
					(mid 209.999942 -79.393554)
					(end 209.904838 -78.617826)
				)
				(xy 209.904838 -78.594712)
				(arc
					(start 209.90814 -78.59141)
					(mid 209.987913 -78.433693)
					(end 210.14563 -78.35392)
				)
				(xy 210.148932 -78.350618) (xy 210.52917 -78.350618) (xy 210.53171 -78.353158) (xy 210.548728 -78.355444)
				(arc
					(start 210.548728 -78.252828)
					(mid 210.519325 -78.249976)
					(end 210.4898 -78.249018)
				)
				(xy 210.148932 -78.249018)
				(arc
					(start 210.14563 -78.245716)
					(mid 209.987913 -78.165943)
					(end 209.90814 -78.008226)
				)
				(xy 209.904838 -78.004924)
				(arc
					(start 209.904838 -77.982064)
					(mid 209.999818 -77.206275)
					(end 210.096862 -77.98181)
				)
				(arc
					(start 210.096862 -77.98181)
					(mid 210.128654 -78.036741)
					(end 210.188302 -78.058518)
				)
				(xy 210.52917 -78.058518) (xy 210.53044 -78.059788) (xy 210.548728 -78.061312)
			)
		)
	)
	(zone
		(layer "B.Cu")
		(hatch none 0.5)
		(connect_pads
			(clearance 0)
		)
		(min_thickness 0.25)
		(keepout
			(tracks not_allowed)
			(vias allowed)
			(pads allowed)
			(copperpour not_allowed)
			(footprints allowed)
		)
		(placement
			(enabled no)
			(sheetname "")
		)
		(fill
			(thermal_gap 0.5)
			(thermal_bridge_width 0.5)
			(island_removal_mode 0)
		)
		(polygon
			(pts
				(arc
					(start 279.236678 -202.1459)
					(mid 278.688038 -202.69454)
					(end 279.236678 -203.24318)
				)
				(arc
					(start 280.636726 -203.24318)
					(mid 281.185366 -202.69454)
					(end 280.636726 -202.1459)
				)
				(xy 280.160222 -202.1459) (xy 280.158952 -202.165458)
				(arc
					(start 280.158952 -202.546458)
					(mid 280.180006 -202.597286)
					(end 280.230834 -202.61834)
				)
				(arc
					(start 280.250392 -202.61834)
					(mid 281.030503 -202.69454)
					(end 280.250392 -202.77074)
				)
				(xy 280.199338 -202.77074)
				(arc
					(start 280.196544 -202.7682)
					(mid 280.072175 -202.705117)
					(end 280.009092 -202.580748)
				)
				(xy 280.006552 -202.577954) (xy 280.006552 -202.1459) (xy 279.86736 -202.1459) (xy 279.866852 -202.165458)
				(xy 279.866852 -202.577954)
				(arc
					(start 279.864312 -202.580748)
					(mid 279.801229 -202.705117)
					(end 279.67686 -202.7682)
				)
				(xy 279.674066 -202.77074)
				(arc
					(start 279.623012 -202.77074)
					(mid 278.842901 -202.69454)
					(end 279.623012 -202.61834)
				)
				(arc
					(start 279.64257 -202.61834)
					(mid 279.693398 -202.597286)
					(end 279.714452 -202.546458)
				)
				(xy 279.714452 -202.1459)
			)
		)
	)
	(zone
		(layer "B.Cu")
		(hatch none 0.5)
		(connect_pads
			(clearance 0)
		)
		(min_thickness 0.25)
		(keepout
			(tracks not_allowed)
			(vias allowed)
			(pads allowed)
			(copperpour not_allowed)
			(footprints allowed)
		)
		(placement
			(enabled no)
			(sheetname "")
		)
		(fill
			(thermal_gap 0.5)
			(thermal_bridge_width 0.5)
			(island_removal_mode 0)
		)
		(polygon
			(pts
				(arc
					(start 278.23668 -193.145918)
					(mid 277.68804 -193.694558)
					(end 278.23668 -194.243198)
				)
				(arc
					(start 279.636728 -194.243198)
					(mid 280.185368 -193.694558)
					(end 279.636728 -193.145918)
				)
				(arc
					(start 279.141936 -193.145918)
					(mid 279.152757 -193.207924)
					(end 279.158192 -193.270632)
				)
				(xy 279.158954 -193.271394)
				(arc
					(start 279.158954 -193.48069)
					(mid 279.184566 -193.560747)
					(end 279.251918 -193.610992)
				)
				(arc
					(start 279.251918 -193.610992)
					(mid 280.030466 -193.700261)
					(end 279.249632 -193.766948)
				)
				(arc
					(start 279.249632 -193.766948)
					(mid 279.086753 -193.680956)
					(end 279.008586 -193.514218)
				)
				(xy 279.006554 -193.512186)
				(arc
					(start 279.006554 -193.30289)
					(mid 279.001028 -193.223654)
					(end 278.98471 -193.145918)
				)
				(arc
					(start 278.837898 -193.145918)
					(mid 278.856274 -193.207011)
					(end 278.865584 -193.270124)
				)
				(xy 278.866854 -193.271394) (xy 278.866854 -193.512186)
				(arc
					(start 278.864822 -193.514218)
					(mid 278.786577 -193.680881)
					(end 278.623776 -193.766948)
				)
				(arc
					(start 278.623776 -193.766948)
					(mid 277.842915 -193.700262)
					(end 278.62149 -193.610992)
				)
				(arc
					(start 278.62149 -193.610992)
					(mid 278.688775 -193.560699)
					(end 278.714454 -193.48069)
				)
				(arc
					(start 278.714454 -193.30289)
					(mid 278.702457 -193.220961)
					(end 278.667464 -193.145918)
				)
			)
		)
	)
	(zone
		(layer "B.Cu")
		(hatch none 0.5)
		(connect_pads
			(clearance 0)
		)
		(min_thickness 0.25)
		(keepout
			(tracks not_allowed)
			(vias allowed)
			(pads allowed)
			(copperpour not_allowed)
			(footprints allowed)
		)
		(placement
			(enabled no)
			(sheetname "")
		)
		(fill
			(thermal_gap 0.5)
			(thermal_bridge_width 0.5)
			(island_removal_mode 0)
		)
		(polygon
			(pts
				(arc
					(start 278.23668 -207.54594)
					(mid 277.68804 -208.09458)
					(end 278.23668 -208.64322)
				)
				(arc
					(start 279.636728 -208.64322)
					(mid 280.185368 -208.09458)
					(end 279.636728 -207.54594)
				)
				(arc
					(start 279.141936 -207.54594)
					(mid 279.152757 -207.607946)
					(end 279.158192 -207.670654)
				)
				(xy 279.158954 -207.671416)
				(arc
					(start 279.158954 -207.880712)
					(mid 279.184566 -207.960769)
					(end 279.251918 -208.011014)
				)
				(arc
					(start 279.251918 -208.011014)
					(mid 280.030466 -208.100283)
					(end 279.249632 -208.16697)
				)
				(arc
					(start 279.249632 -208.16697)
					(mid 279.086753 -208.080978)
					(end 279.008586 -207.91424)
				)
				(xy 279.006554 -207.912208)
				(arc
					(start 279.006554 -207.702912)
					(mid 279.001028 -207.623676)
					(end 278.98471 -207.54594)
				)
				(arc
					(start 278.837898 -207.54594)
					(mid 278.856274 -207.607033)
					(end 278.865584 -207.670146)
				)
				(xy 278.866854 -207.671416) (xy 278.866854 -207.912208)
				(arc
					(start 278.864822 -207.91424)
					(mid 278.786577 -208.080903)
					(end 278.623776 -208.16697)
				)
				(arc
					(start 278.623776 -208.16697)
					(mid 277.842915 -208.100284)
					(end 278.62149 -208.011014)
				)
				(arc
					(start 278.62149 -208.011014)
					(mid 278.688775 -207.960721)
					(end 278.714454 -207.880712)
				)
				(arc
					(start 278.714454 -207.702912)
					(mid 278.702457 -207.620983)
					(end 278.667464 -207.54594)
				)
			)
		)
	)
	(zone
		(layer "B.Cu")
		(hatch none 0.5)
		(connect_pads
			(clearance 0)
		)
		(min_thickness 0.25)
		(keepout
			(tracks not_allowed)
			(vias allowed)
			(pads allowed)
			(copperpour not_allowed)
			(footprints allowed)
		)
		(placement
			(enabled no)
			(sheetname "")
		)
		(fill
			(thermal_gap 0.5)
			(thermal_bridge_width 0.5)
			(island_removal_mode 0)
		)
		(polygon
			(pts
				(arc
					(start 462.7499 -13.999972)
					(mid 467.499954 -18.750026)
					(end 472.250008 -13.999972)
				)
				(arc
					(start 472.250008 -13.999972)
					(mid 467.499954 -9.249918)
					(end 462.7499 -13.999972)
				)
			)
		)
	)
	(zone
		(layer "B.Cu")
		(hatch none 0.5)
		(connect_pads
			(clearance 0)
		)
		(min_thickness 0.25)
		(keepout
			(tracks not_allowed)
			(vias allowed)
			(pads allowed)
			(copperpour not_allowed)
			(footprints allowed)
		)
		(placement
			(enabled no)
			(sheetname "")
		)
		(fill
			(thermal_gap 0.5)
			(thermal_bridge_width 0.5)
			(island_removal_mode 0)
		)
		(polygon
			(pts
				(arc
					(start 212.348826 -76.399898)
					(mid 211.800186 -75.851258)
					(end 211.251546 -76.399898)
				)
				(arc
					(start 211.251546 -77.799692)
					(mid 211.800059 -78.348586)
					(end 212.348826 -77.799946)
				)
				(arc
					(start 212.348826 -77.380338)
					(mid 212.285751 -77.351221)
					(end 212.217 -77.341222)
				)
				(arc
					(start 211.9884 -77.341222)
					(mid 211.928514 -77.363003)
					(end 211.896706 -77.418184)
				)
				(arc
					(start 211.896706 -77.418184)
					(mid 211.80004 -78.193658)
					(end 211.704936 -77.41793)
				)
				(xy 211.704936 -77.394816)
				(arc
					(start 211.708238 -77.391514)
					(mid 211.788011 -77.233797)
					(end 211.945728 -77.154024)
				)
				(xy 211.94903 -77.150722) (xy 212.25637 -77.150722)
				(arc
					(start 212.258402 -77.152754)
					(mid 212.30411 -77.159607)
					(end 212.348826 -77.171296)
				)
				(arc
					(start 212.348826 -77.065632)
					(mid 212.283429 -77.053251)
					(end 212.217 -77.049122)
				)
				(xy 211.94903 -77.049122)
				(arc
					(start 211.945728 -77.04582)
					(mid 211.788011 -76.966047)
					(end 211.708238 -76.80833)
				)
				(xy 211.704936 -76.805028)
				(arc
					(start 211.704936 -76.781914)
					(mid 211.80004 -76.006125)
					(end 211.896706 -76.78166)
				)
				(arc
					(start 211.896706 -76.78166)
					(mid 211.928574 -76.836769)
					(end 211.9884 -76.858622)
				)
				(xy 212.25637 -76.858622)
				(arc
					(start 212.25764 -76.859638)
					(mid 212.30341 -76.863783)
					(end 212.348826 -76.870814)
				)
			)
		)
	)
	(zone
		(net "P5V_B_2")
		(layer "B.Cu")
		(hatch none 0.5)
		(connect_pads
			(clearance 0.5)
		)
		(min_thickness 0.25)
		(fill yes
			(thermal_gap 0.5)
			(thermal_bridge_width 0.5)
			(island_removal_mode 0)
		)
		(polygon
			(pts
				(xy 58.805064 -109.039406) (xy 58.31586 -109.52861) (xy 58.31586 -116.151406) (xy 59.20486 -117.040406)
				(xy 74.094594 -117.040406) (xy 74.5744 -116.5606) (xy 75.68692 -116.5606) (xy 76.47686 -115.770406)
				(xy 76.47686 -110.436406) (xy 75.07986 -109.039406)
			)
		)
	)
	(zone
		(net "GND")
		(layer "B.Cu")
		(hatch none 0.5)
		(connect_pads
			(clearance 0.5)
		)
		(min_thickness 0.25)
		(fill yes
			(thermal_gap 0.5)
			(thermal_bridge_width 0.5)
			(island_removal_mode 0)
		)
		(polygon
			(pts
				(xy 252.857 -278.638) (xy 252.6538 -278.8412) (xy 252.6538 -280.343102) (xy 253.5174 -281.206702)
				(xy 253.5174 -283.0576) (xy 253.619 -283.1592) (xy 255.2192 -283.1592) (xy 255.27 -283.1084) (xy 255.27 -281.5844)
				(xy 255.177544 -281.491944) (xy 254.429514 -281.491944) (xy 254.315468 -281.377898) (xy 254.315468 -280.096468)
				(xy 253.746 -279.527) (xy 253.746 -278.8666) (xy 253.5174 -278.638)
			)
		)
	)
	(zone
		(layer "B.Cu")
		(hatch none 0.5)
		(connect_pads
			(clearance 0)
		)
		(min_thickness 0.25)
		(keepout
			(tracks allowed)
			(vias allowed)
			(pads allowed)
			(copperpour allowed)
			(footprints not_allowed)
		)
		(placement
			(enabled no)
			(sheetname "")
		)
		(fill
			(thermal_gap 0.5)
			(thermal_bridge_width 0.5)
			(island_removal_mode 0)
		)
		(polygon
			(pts
				(xy 417.699952 -380.000002) (xy 417.699952 -358.000046) (xy 363.70006 -358.000046) (xy 363.70006 -380.000002)
			)
		)
	)
	(zone
		(net "P12V_IN")
		(layer "B.Cu")
		(hatch none 0.5)
		(connect_pads
			(clearance 0.5)
		)
		(min_thickness 0.25)
		(fill yes
			(thermal_gap 0.5)
			(thermal_bridge_width 0.5)
			(island_removal_mode 0)
		)
		(polygon
			(pts
				(xy 210.693 -328.93) (xy 209.042 -330.581) (xy 207.264 -330.581) (xy 207.01 -330.835) (xy 207.01 -331.978)
				(xy 206.756 -332.232) (xy 204.96784 -332.232) (xy 204.828394 -332.371446) (xy 204.828394 -336.908394)
				(xy 205.232 -337.312) (xy 209.169 -337.312) (xy 209.677 -337.82) (xy 209.677 -339.471) (xy 209.296 -339.852)
				(xy 207.391 -339.852) (xy 207.01 -340.233) (xy 207.01 -342.9) (xy 206.756 -343.154) (xy 205.013052 -343.154)
				(xy 204.958188 -343.208864) (xy 204.958188 -346.944188) (xy 205.105 -347.091) (xy 209.169 -347.091)
				(xy 209.677 -347.599) (xy 209.677 -349.123) (xy 209.169 -349.631) (xy 207.645 -349.631) (xy 207.01 -350.266)
				(xy 207.01 -352.425) (xy 206.827628 -352.607372) (xy 204.985112 -352.607372) (xy 204.893418 -352.699066)
				(xy 204.893418 -358.04094) (xy 205.169516 -358.317038) (xy 210.261962 -358.317038) (xy 211.455 -357.124)
				(xy 211.455 -354.838) (xy 211.836 -354.457) (xy 212.344 -354.457) (xy 213.36 -355.473) (xy 220.218 -355.473)
				(xy 220.599 -355.092) (xy 227.868734 -355.092) (xy 230.383334 -352.5774) (xy 241.9096 -352.5774)
				(xy 242.1382 -352.3488) (xy 242.1382 -346.4814) (xy 241.7826 -346.1258) (xy 239.4712 -346.1258)
				(xy 238.7346 -345.3892) (xy 238.7346 -343.7128) (xy 239.116616 -343.330784) (xy 241.985292 -343.330784)
				(xy 242.036346 -343.27973) (xy 242.036346 -337.718654) (xy 242.443 -337.312) (xy 244.6274 -337.312)
				(xy 245.3386 -336.6008) (xy 245.3386 -329.029822) (xy 245.238778 -328.93)
			)
		)
	)
	(zone
		(net "GND")
		(layer "B.Cu")
		(hatch none 0.5)
		(connect_pads
			(clearance 0.5)
		)
		(min_thickness 0.25)
		(fill yes
			(thermal_gap 0.5)
			(thermal_bridge_width 0.5)
			(island_removal_mode 0)
		)
		(polygon
			(pts
				(xy 37.450268 -135.115808)
				(arc
					(start 36.523676 -136.0424)
					(mid 35.637878 -137.997039)
					(end 33.880298 -139.228322)
				)
				(xy 32.423862 -140.684758) (xy 32.423862 -142.697962) (xy 32.684466 -142.958566)
				(arc
					(start 33.226248 -142.958566)
					(mid 37.001191 -142.282653)
					(end 39.676578 -145.03019)
				)
				(xy 41.468294 -146.821906)
				(arc
					(start 42.556176 -146.821906)
					(mid 44.09105 -146.531907)
					(end 45.622718 -146.838416)
				)
				(xy 45.838872 -146.838416) (xy 46.175422 -146.501866)
				(arc
					(start 46.175422 -146.443446)
					(mid 46.139807 -146.267739)
					(end 46.111922 -146.09064)
				)
				(xy 45.996606 -145.975324)
				(arc
					(start 44.0944 -145.975324)
					(mid 41.20168 -144.77712)
					(end 40.003476 -141.8844)
				)
				(arc
					(start 40.003476 -140.8176)
					(mid 40.220765 -139.501988)
					(end 40.84955 -138.326114)
				)
				(arc
					(start 40.84955 -137.911078)
					(mid 40.743317 -136.893481)
					(end 40.892984 -135.881364)
				)
				(xy 40.892984 -135.582914) (xy 40.425878 -135.115808)
			)
		)
	)
	(zone
		(net "MB0_12V_CTRL_GATE3")
		(layer "B.Cu")
		(hatch none 0.5)
		(connect_pads
			(clearance 0.5)
		)
		(min_thickness 0.25)
		(fill yes
			(thermal_gap 0.5)
			(thermal_bridge_width 0.5)
			(island_removal_mode 0)
		)
		(polygon
			(pts
				(xy 205.232 -337.82) (xy 204.983334 -338.06892) (xy 204.983334 -342.654128) (xy 205.059534 -342.730328)
				(xy 206.558134 -342.730328) (xy 206.685134 -342.603328) (xy 206.685134 -338.130134) (xy 206.375 -337.82)
			)
		)
	)
	(zone
		(layer "B.Cu")
		(hatch none 0.5)
		(connect_pads
			(clearance 0)
		)
		(min_thickness 0.25)
		(keepout
			(tracks allowed)
			(vias allowed)
			(pads allowed)
			(copperpour allowed)
			(footprints allowed)
		)
		(placement
			(enabled no)
			(sheetname "")
		)
		(fill
			(thermal_gap 0.5)
			(thermal_bridge_width 0.5)
			(island_removal_mode 0)
		)
		(polygon
			(pts
				(xy 48.7426 -114.0206) (xy 50.2158 -114.0206) (xy 50.2158 -116.3066) (xy 48.7426 -116.3066)
			)
		)
	)
	(zone
		(net "P3V3_STBY_VBST")
		(layer "B.Cu")
		(hatch none 0.5)
		(connect_pads
			(clearance 0.5)
		)
		(min_thickness 0.25)
		(fill yes
			(thermal_gap 0.5)
			(thermal_bridge_width 0.5)
			(island_removal_mode 0)
		)
		(polygon
			(pts
				(xy 252.4506 -282.9306) (xy 252.4252 -282.956) (xy 252.349 -282.956) (xy 251.968 -283.337) (xy 250.317 -283.337)
				(xy 250.063 -283.591) (xy 250.063 -284.353) (xy 250.19 -284.48) (xy 251.968 -284.48) (xy 253.365 -283.083)
				(xy 253.365 -283.0068) (xy 253.2888 -282.9306)
			)
		)
		(polygon
			(pts
				(xy 250.952 -283.7942) (xy 250.7488 -283.7942) (xy 250.7488 -283.9974) (xy 250.952 -283.9974)
			)
		)
		(polygon
			(pts
				(xy 250.3932 -283.7942) (xy 250.19 -283.7942) (xy 250.19 -283.9974) (xy 250.3932 -283.9974)
			)
		)
	)
	(zone
		(net "P5V_B_3")
		(layer "B.Cu")
		(hatch none 0.5)
		(connect_pads
			(clearance 0.5)
		)
		(min_thickness 0.25)
		(fill yes
			(thermal_gap 0.5)
			(thermal_bridge_width 0.5)
			(island_removal_mode 0)
		)
		(polygon
			(pts
				(xy 469.567006 -220.22435) (xy 469.077802 -220.713554) (xy 469.077802 -227.33635) (xy 469.966802 -228.22535)
				(xy 485.0384 -228.22535) (xy 485.1654 -228.09835) (xy 485.1654 -227.8126) (xy 485.2416 -227.7364)
				(xy 486.457752 -227.7364) (xy 487.238802 -226.95535) (xy 487.238802 -221.62135) (xy 485.841802 -220.22435)
			)
		)
	)
	(zone
		(net "P12V_B")
		(layer "B.Cu")
		(hatch none 0.5)
		(connect_pads
			(clearance 0.5)
		)
		(min_thickness 0.25)
		(fill yes
			(thermal_gap 0.5)
			(thermal_bridge_width 0.5)
			(island_removal_mode 0)
		)
		(polygon
			(pts
				(xy 261.875778 -332.486) (xy 261.345172 -333.016606) (xy 261.345172 -336.217006) (xy 261.421372 -336.293206)
				(xy 268.602206 -336.293206) (xy 268.860016 -336.551016) (xy 268.860016 -338.350352) (xy 268.58595 -338.624418)
				(xy 261.559548 -338.624418) (xy 261.345172 -338.838794) (xy 261.345172 -343.337134) (xy 261.441184 -343.433146)
				(xy 268.731746 -343.433146) (xy 268.853158 -343.554558) (xy 268.853158 -345.036394) (xy 268.622526 -345.267026)
				(xy 261.505192 -345.267026) (xy 261.345172 -345.427046) (xy 261.345172 -350.47682) (xy 261.429246 -350.560894)
				(xy 271.192752 -350.560894) (xy 272.203672 -349.549974) (xy 272.203672 -334.052672) (xy 270.637 -332.486)
			)
		)
	)
	(zone
		(layer "B.Cu")
		(hatch none 0.5)
		(connect_pads
			(clearance 0)
		)
		(min_thickness 0.25)
		(keepout
			(tracks not_allowed)
			(vias allowed)
			(pads allowed)
			(copperpour not_allowed)
			(footprints allowed)
		)
		(placement
			(enabled no)
			(sheetname "")
		)
		(fill
			(thermal_gap 0.5)
			(thermal_bridge_width 0.5)
			(island_removal_mode 0)
		)
		(polygon
			(pts
				(arc
					(start 400.675094 -63.799974)
					(mid 393.675108 -56.799988)
					(end 386.675122 -63.799974)
				)
				(arc
					(start 386.675122 -69.799962)
					(mid 393.675108 -76.799948)
					(end 400.675094 -69.799962)
				)
			)
		)
	)
	(zone
		(layer "B.Cu")
		(hatch none 0.5)
		(connect_pads
			(clearance 0)
		)
		(min_thickness 0.25)
		(keepout
			(tracks not_allowed)
			(vias allowed)
			(pads allowed)
			(copperpour not_allowed)
			(footprints allowed)
		)
		(placement
			(enabled no)
			(sheetname "")
		)
		(fill
			(thermal_gap 0.5)
			(thermal_bridge_width 0.5)
			(island_removal_mode 0)
		)
		(polygon
			(pts
				(arc
					(start 129.42062 -244.419374)
					(mid 128.93548 -243.934234)
					(end 128.45034 -244.419374)
				)
				(arc
					(start 128.45034 -245.56212)
					(mid 128.935353 -246.047514)
					(end 129.42062 -245.562374)
				)
				(xy 129.42062 -245.213124)
				(arc
					(start 129.079752 -245.213124)
					(mid 129.031618 -245.233062)
					(end 129.01168 -245.281196)
				)
				(arc
					(start 129.01168 -245.30685)
					(mid 128.93548 -245.829018)
					(end 128.85928 -245.30685)
				)
				(xy 128.85928 -245.2497)
				(arc
					(start 128.862074 -245.246906)
					(mid 128.923932 -245.125376)
					(end 129.045462 -245.063518)
				)
				(xy 129.048256 -245.060724) (xy 129.42062 -245.060724) (xy 129.42062 -244.921024) (xy 129.038604 -244.921024)
				(arc
					(start 129.03581 -244.91823)
					(mid 128.921018 -244.859286)
					(end 128.862074 -244.744494)
				)
				(xy 128.85928 -244.7417)
				(arc
					(start 128.85928 -244.674898)
					(mid 128.93548 -244.15273)
					(end 129.01168 -244.674898)
				)
				(arc
					(start 129.01168 -244.710204)
					(mid 129.028791 -244.751513)
					(end 129.0701 -244.768624)
				)
				(xy 129.42062 -244.768624)
			)
		)
	)
	(zone
		(net "GND")
		(layer "B.Cu")
		(hatch none 0.5)
		(connect_pads
			(clearance 0.5)
		)
		(min_thickness 0.25)
		(fill yes
			(thermal_gap 0.5)
			(thermal_bridge_width 0.5)
			(island_removal_mode 0)
		)
		(polygon
			(pts
				(xy 363.79658 -62.40018) (xy 381.657098 -50.801778)
				(arc
					(start 382.802638 -49.656238)
					(mid 382.811295 -48.671941)
					(end 383.05486 -47.718218)
				)
				(xy 383.05486 -42.874438) (xy 377.472702 -37.29228)
				(arc
					(start 377.472702 -35.929316)
					(mid 377.608389 -32.872997)
					(end 379.826266 -30.76575)
				)
				(arc
					(start 379.826266 -30.76575)
					(mid 380.681018 -27.823909)
					(end 383.339086 -26.300938)
				)
				(xy 383.52095 -26.119074) (xy 383.52095 -25.498552) (xy 382.967992 -24.945594) (xy 381.566674 -24.945594)
				(xy 381.220472 -25.47874) (xy 380.629668 -26.388314) (xy 380.405132 -26.436066)
				(arc
					(start 368.425222 -44.883324)
					(mid 368.594722 -49.066038)
					(end 364.998 -51.207924)
				)
				(xy 364.318042 -51.207924) (xy 360.358182 -57.305702) (xy 360.358182 -60.532264) (xy 362.226098 -62.40018)
			)
		)
	)
	(zone
		(layer "B.Cu")
		(hatch none 0.5)
		(connect_pads
			(clearance 0)
		)
		(min_thickness 0.25)
		(keepout
			(tracks not_allowed)
			(vias allowed)
			(pads allowed)
			(copperpour not_allowed)
			(footprints allowed)
		)
		(placement
			(enabled no)
			(sheetname "")
		)
		(fill
			(thermal_gap 0.5)
			(thermal_bridge_width 0.5)
			(island_removal_mode 0)
		)
		(polygon
			(pts
				(arc
					(start 192.520824 -14.41958)
					(mid 192.035811 -13.934186)
					(end 191.550544 -14.419326)
				)
				(arc
					(start 191.550544 -15.562326)
					(mid 192.035684 -16.047466)
					(end 192.520824 -15.562326)
				)
				(xy 192.520824 -15.213076)
				(arc
					(start 192.179956 -15.213076)
					(mid 192.131822 -15.233014)
					(end 192.111884 -15.281148)
				)
				(arc
					(start 192.111884 -15.306802)
					(mid 192.035684 -15.82897)
					(end 191.959484 -15.306802)
				)
				(xy 191.959484 -15.249652)
				(arc
					(start 191.962278 -15.246858)
					(mid 192.024136 -15.125328)
					(end 192.145666 -15.06347)
				)
				(xy 192.14846 -15.060676) (xy 192.520824 -15.060676) (xy 192.520824 -14.920976) (xy 192.138808 -14.920976)
				(arc
					(start 192.136014 -14.918182)
					(mid 192.021222 -14.859238)
					(end 191.962278 -14.744446)
				)
				(xy 191.959484 -14.741652)
				(arc
					(start 191.959484 -14.67485)
					(mid 192.035684 -14.152682)
					(end 192.111884 -14.67485)
				)
				(arc
					(start 192.111884 -14.710156)
					(mid 192.128995 -14.751465)
					(end 192.170304 -14.768576)
				)
				(xy 192.520824 -14.768576)
			)
		)
	)
	(zone
		(layer "B.Cu")
		(hatch none 0.5)
		(connect_pads
			(clearance 0)
		)
		(min_thickness 0.25)
		(keepout
			(tracks allowed)
			(vias allowed)
			(pads allowed)
			(copperpour allowed)
			(footprints not_allowed)
		)
		(placement
			(enabled no)
			(sheetname "")
		)
		(fill
			(thermal_gap 0.5)
			(thermal_bridge_width 0.5)
			(island_removal_mode 0)
		)
		(polygon
			(pts
				(xy 198.000112 -358.000046) (xy 198.000112 -380.000002) (xy 252.000004 -380.000002) (xy 252.000004 -358.000046)
			)
		)
	)
	(zone
		(layer "B.Cu")
		(hatch none 0.5)
		(connect_pads
			(clearance 0)
		)
		(min_thickness 0.25)
		(keepout
			(tracks not_allowed)
			(vias allowed)
			(pads allowed)
			(copperpour not_allowed)
			(footprints allowed)
		)
		(placement
			(enabled no)
			(sheetname "")
		)
		(fill
			(thermal_gap 0.5)
			(thermal_bridge_width 0.5)
			(island_removal_mode 0)
		)
		(polygon
			(pts
				(arc
					(start 307.200046 -94.000066)
					(mid 300.20006 -87.00008)
					(end 293.200074 -94.000066)
				)
				(arc
					(start 293.200074 -100.000054)
					(mid 300.20006 -107.00004)
					(end 307.200046 -100.000054)
				)
			)
		)
	)
	(zone
		(net "GND")
		(layer "B.Cu")
		(hatch none 0.5)
		(connect_pads
			(clearance 0.5)
		)
		(min_thickness 0.25)
		(fill yes
			(thermal_gap 0.5)
			(thermal_bridge_width 0.5)
			(island_removal_mode 0)
		)
		(polygon
			(pts
				(arc
					(start 269.424404 -241.814604)
					(mid 267.692493 -243.61278)
					(end 265.237976 -244.069362)
				)
				(arc
					(start 265.237976 -244.069362)
					(mid 264.427413 -244.961179)
					(end 263.392158 -245.578122)
				)
				(arc
					(start 263.392158 -245.578122)
					(mid 261.293757 -247.751733)
					(end 258.275836 -247.891808)
				)
				(xy 257.094736 -247.891808) (xy 255.02108 -249.965464) (xy 255.02108 -256.178304) (xy 258.735576 -259.8928)
				(xy 286.05607 -259.8928) (xy 289.378644 -256.570226) (xy 289.378644 -245.500906) (xy 288.989516 -245.111778)
				(xy 287.306258 -245.111778)
				(arc
					(start 285.8135 -246.604536)
					(mid 284.826321 -247.948932)
					(end 283.384498 -248.787412)
				)
				(arc
					(start 283.384498 -248.787412)
					(mid 282.064839 -249.627706)
					(end 280.526236 -249.911108)
				)
				(arc
					(start 280.526236 -249.911108)
					(mid 276.059662 -250.602658)
					(end 273.683222 -246.757952)
				)
				(arc
					(start 273.683222 -246.757952)
					(mid 272.551619 -245.186185)
					(end 272.269966 -243.270024)
				)
				(arc
					(start 271.972532 -242.97259)
					(mid 271.003491 -242.511684)
					(end 270.187674 -241.814604)
				)
			)
		)
	)
	(zone
		(layer "B.Cu")
		(hatch none 0.5)
		(connect_pads
			(clearance 0)
		)
		(min_thickness 0.25)
		(keepout
			(tracks not_allowed)
			(vias allowed)
			(pads allowed)
			(copperpour not_allowed)
			(footprints allowed)
		)
		(placement
			(enabled no)
			(sheetname "")
		)
		(fill
			(thermal_gap 0.5)
			(thermal_bridge_width 0.5)
			(island_removal_mode 0)
		)
		(polygon
			(pts
				(arc
					(start 251.199904 -175.800004)
					(mid 244.199918 -168.800018)
					(end 237.199932 -175.800004)
				)
				(arc
					(start 237.199932 -181.799992)
					(mid 244.199918 -188.799978)
					(end 251.199904 -181.799992)
				)
			)
		)
	)
	(zone
		(net "GND")
		(layer "B.Cu")
		(hatch none 0.5)
		(connect_pads
			(clearance 0.5)
		)
		(min_thickness 0.25)
		(fill yes
			(thermal_gap 0.5)
			(thermal_bridge_width 0.5)
			(island_removal_mode 0)
		)
		(polygon
			(pts
				(xy 102.433882 -248.825766)
				(arc
					(start 99.560634 -251.699014)
					(mid 99.188689 -253.997629)
					(end 97.622614 -255.72085)
				)
				(xy 97.622614 -256.416302)
				(arc
					(start 98.384106 -257.177794)
					(mid 102.063416 -258.684024)
					(end 102.724966 -262.60425)
				)
				(arc
					(start 102.724966 -262.60425)
					(mid 101.844719 -266.776028)
					(end 97.731326 -267.898118)
				)
				(xy 96.353884 -267.898118) (xy 95.495872 -268.75613)
				(arc
					(start 95.495872 -270.975074)
					(mid 95.309738 -272.194768)
					(end 94.768416 -273.303492)
				)
				(arc
					(start 94.768416 -274.943316)
					(mid 95.494999 -276.201554)
					(end 95.781114 -277.626064)
				)
				(arc
					(start 95.781114 -277.626064)
					(mid 96.782399 -278.842624)
					(end 97.249488 -280.34742)
				)
				(arc
					(start 100.89134 -283.989272)
					(mid 105.449398 -287.982381)
					(end 107.14609 -293.799768)
				)
				(xy 107.14609 -303.578768) (xy 111.160814 -307.593492) (xy 143.825976 -307.593492) (xy 148.50364 -302.915828)
				(arc
					(start 148.50364 -293.799768)
					(mid 149.802804 -288.658845)
					(end 153.388314 -284.752288)
				)
				(arc
					(start 153.388314 -283.67482)
					(mid 152.716293 -282.787223)
					(end 152.30856 -281.751278)
				)
				(arc
					(start 152.30856 -281.751278)
					(mid 151.889835 -281.50049)
					(end 151.50084 -281.205686)
				)
				(arc
					(start 151.50084 -281.205686)
					(mid 147.580057 -280.110417)
					(end 146.546824 -276.17293)
				)
				(arc
					(start 146.546824 -274.707096)
					(mid 144.98656 -269.962419)
					(end 149.17801 -267.246354)
				)
				(arc
					(start 150.590504 -267.246354)
					(mid 150.880789 -266.537441)
					(end 151.298148 -265.895074)
				)
				(arc
					(start 151.298148 -265.895074)
					(mid 150.641334 -264.699815)
					(end 150.413974 -263.355074)
				)
				(arc
					(start 150.413974 -260.815074)
					(mid 150.484303 -260.059776)
					(end 150.692866 -259.330444)
				)
				(arc
					(start 150.692866 -259.330444)
					(mid 149.656095 -257.962968)
					(end 149.271482 -256.290572)
				)
				(arc
					(start 149.271482 -256.290572)
					(mid 149.058414 -256.307319)
					(end 148.844762 -256.312924)
				)
				(arc
					(start 146.436588 -256.312924)
					(mid 146.356511 -256.531659)
					(end 146.264122 -256.745486)
				)
				(arc
					(start 146.264122 -256.745486)
					(mid 148.685732 -259.038402)
					(end 148.595334 -262.372094)
				)
				(arc
					(start 148.595334 -262.372094)
					(mid 147.919027 -266.370722)
					(end 144.132046 -267.821664)
				)
				(arc
					(start 142.298166 -267.821664)
					(mid 134.990705 -267.145261)
					(end 139.981432 -261.76478)
				)
				(xy 140.670026 -261.76478) (xy 140.78966 -261.645146) (xy 140.78966 -261.07517) (xy 140.599414 -260.884924)
				(arc
					(start 138.938 -260.884924)
					(mid 135.062383 -258.103677)
					(end 136.45642 -253.54153)
				)
				(xy 136.45642 -252.159262) (xy 135.848344 -251.551186) (xy 135.848344 -249.66168) (xy 135.066532 -248.879868)
				(xy 133.785102 -248.879868)
				(arc
					(start 131.07289 -251.59208)
					(mid 130.71322 -253.683151)
					(end 129.354326 -255.312672)
				)
				(xy 129.354326 -256.112264)
				(arc
					(start 130.3909 -257.148838)
					(mid 133.713063 -258.888704)
					(end 134.220966 -262.60425)
				)
				(arc
					(start 134.220966 -262.60425)
					(mid 133.340168 -266.776612)
					(end 129.225802 -267.89761)
				)
				(xy 128.715516 -267.89761) (xy 127.04572 -269.567406)
				(arc
					(start 127.04572 -270.975074)
					(mid 126.981665 -271.696175)
					(end 126.791466 -272.39468)
				)
				(arc
					(start 126.791466 -275.647404)
					(mid 127.175879 -276.605472)
					(end 127.330962 -277.626064)
				)
				(arc
					(start 127.330962 -277.626064)
					(mid 126.907175 -284.249425)
					(end 120.758458 -281.751278)
				)
				(arc
					(start 120.758458 -281.751278)
					(mid 120.330462 -281.494117)
					(end 119.93372 -281.190954)
				)
				(arc
					(start 119.93372 -281.190954)
					(mid 116.060328 -280.211502)
					(end 114.869722 -276.39772)
				)
				(arc
					(start 114.869722 -274.57654)
					(mid 113.721234 -269.431967)
					(end 118.596664 -267.427964)
				)
				(arc
					(start 118.989602 -267.427964)
					(mid 119.287812 -266.621434)
					(end 119.748046 -265.895074)
				)
				(arc
					(start 119.748046 -265.895074)
					(mid 119.091232 -264.699815)
					(end 118.863872 -263.355074)
				)
				(arc
					(start 118.863872 -260.815074)
					(mid 118.934201 -260.059776)
					(end 119.142764 -259.330444)
				)
				(arc
					(start 119.142764 -259.330444)
					(mid 118.2668 -258.27187)
					(end 117.790722 -256.982976)
				)
				(xy 117.12067 -256.312924) (xy 115.139724 -256.312924) (xy 114.96548 -256.487168) (xy 114.96548 -256.802128)
				(arc
					(start 115.104672 -256.94132)
					(mid 117.167776 -259.321367)
					(end 116.92763 -262.46201)
				)
				(arc
					(start 116.92763 -262.46201)
					(mid 115.98988 -266.628115)
					(end 111.853218 -267.688568)
				)
				(arc
					(start 110.753398 -267.688568)
					(mid 103.383736 -267.18664)
					(end 108.42117 -261.784084)
				)
				(xy 109.016038 -261.784084) (xy 109.179106 -261.621016) (xy 109.179106 -261.045706) (xy 109.018324 -260.884924)
				(arc
					(start 107.315 -260.884924)
					(mid 103.496927 -258.263005)
					(end 104.572816 -253.757938)
				)
				(arc
					(start 104.572816 -249.834908)
					(mid 104.380395 -249.340709)
					(end 104.253538 -248.825766)
				)
			)
		)
	)
	(zone
		(net "GND")
		(layer "B.Cu")
		(hatch none 0.5)
		(connect_pads
			(clearance 0.5)
		)
		(min_thickness 0.25)
		(fill yes
			(thermal_gap 0.5)
			(thermal_bridge_width 0.5)
			(island_removal_mode 0)
		)
		(polygon
			(pts
				(xy 180.732938 -143.96593) (xy 180.448712 -144.250156)
				(arc
					(start 180.448712 -144.939258)
					(mid 180.454743 -146.102241)
					(end 180.133244 -147.219924)
				)
				(arc
					(start 180.133244 -147.219924)
					(mid 180.400348 -148.348374)
					(end 180.34 -149.506432)
				)
				(xy 180.34 -150.633684)
				(arc
					(start 182.37835 -152.672034)
					(mid 184.063558 -154.409839)
					(end 184.471056 -156.795978)
				)
				(xy 184.824624 -157.149546) (xy 185.41111 -157.149546) (xy 185.780426 -156.78023)
				(arc
					(start 185.780426 -154.963114)
					(mid 185.535819 -154.082405)
					(end 185.492898 -153.169366)
				)
				(arc
					(start 184.434988 -152.111456)
					(mid 182.637128 -150.603181)
					(end 181.964076 -148.35505)
				)
				(arc
					(start 181.964076 -145.81505)
					(mid 182.01513 -145.170739)
					(end 182.167022 -144.54251)
				)
				(arc
					(start 182.167022 -144.263364)
					(mid 182.014861 -144.118462)
					(end 181.87035 -143.96593)
				)
			)
		)
	)
	(zone
		(layer "B.Cu")
		(hatch none 0.5)
		(connect_pads
			(clearance 0)
		)
		(min_thickness 0.25)
		(keepout
			(tracks not_allowed)
			(vias allowed)
			(pads allowed)
			(copperpour not_allowed)
			(footprints allowed)
		)
		(placement
			(enabled no)
			(sheetname "")
		)
		(fill
			(thermal_gap 0.5)
			(thermal_bridge_width 0.5)
			(island_removal_mode 0)
		)
		(polygon
			(pts
				(arc
					(start 129.42062 -129.419604)
					(mid 128.935607 -128.93421)
					(end 128.45034 -129.41935)
				)
				(arc
					(start 128.45034 -130.56235)
					(mid 128.93548 -131.04749)
					(end 129.42062 -130.56235)
				)
				(xy 129.42062 -130.2131)
				(arc
					(start 129.079752 -130.2131)
					(mid 129.031618 -130.233038)
					(end 129.01168 -130.281172)
				)
				(arc
					(start 129.01168 -130.306826)
					(mid 128.93548 -130.828994)
					(end 128.85928 -130.306826)
				)
				(xy 128.85928 -130.249676)
				(arc
					(start 128.862074 -130.246882)
					(mid 128.923932 -130.125352)
					(end 129.045462 -130.063494)
				)
				(xy 129.048256 -130.0607) (xy 129.42062 -130.0607) (xy 129.42062 -129.921) (xy 129.038604 -129.921)
				(arc
					(start 129.03581 -129.918206)
					(mid 128.921018 -129.859262)
					(end 128.862074 -129.74447)
				)
				(xy 128.85928 -129.741676)
				(arc
					(start 128.85928 -129.674874)
					(mid 128.93548 -129.152706)
					(end 129.01168 -129.674874)
				)
				(arc
					(start 129.01168 -129.71018)
					(mid 129.028791 -129.751489)
					(end 129.0701 -129.7686)
				)
				(xy 129.42062 -129.7686)
			)
		)
	)
	(zone
		(layer "B.Cu")
		(hatch none 0.5)
		(connect_pads
			(clearance 0)
		)
		(min_thickness 0.25)
		(keepout
			(tracks not_allowed)
			(vias allowed)
			(pads allowed)
			(copperpour not_allowed)
			(footprints allowed)
		)
		(placement
			(enabled no)
			(sheetname "")
		)
		(fill
			(thermal_gap 0.5)
			(thermal_bridge_width 0.5)
			(island_removal_mode 0)
		)
		(polygon
			(pts
				(arc
					(start 66.32067 -14.41958)
					(mid 65.835657 -13.934186)
					(end 65.35039 -14.419326)
				)
				(arc
					(start 65.35039 -15.562326)
					(mid 65.83553 -16.047466)
					(end 66.32067 -15.562326)
				)
				(xy 66.32067 -15.213076)
				(arc
					(start 65.979802 -15.213076)
					(mid 65.931668 -15.233014)
					(end 65.91173 -15.281148)
				)
				(arc
					(start 65.91173 -15.306802)
					(mid 65.83553 -15.82897)
					(end 65.75933 -15.306802)
				)
				(xy 65.75933 -15.249652)
				(arc
					(start 65.762124 -15.246858)
					(mid 65.823982 -15.125328)
					(end 65.945512 -15.06347)
				)
				(xy 65.948306 -15.060676) (xy 66.32067 -15.060676) (xy 66.32067 -14.920976) (xy 65.938654 -14.920976)
				(arc
					(start 65.93586 -14.918182)
					(mid 65.821068 -14.859238)
					(end 65.762124 -14.744446)
				)
				(xy 65.75933 -14.741652)
				(arc
					(start 65.75933 -14.67485)
					(mid 65.83553 -14.152682)
					(end 65.91173 -14.67485)
				)
				(arc
					(start 65.91173 -14.710156)
					(mid 65.928841 -14.751465)
					(end 65.97015 -14.768576)
				)
				(xy 66.32067 -14.768576)
			)
		)
	)
	(zone
		(net "AGND_P5V_B_4")
		(layer "B.Cu")
		(hatch none 0.5)
		(connect_pads
			(clearance 0.5)
		)
		(min_thickness 0.25)
		(fill yes
			(thermal_gap 0.5)
			(thermal_bridge_width 0.5)
			(island_removal_mode 0)
		)
		(polygon
			(pts
				(xy 438.69737 -119.350028) (xy 438.631584 -119.415814) (xy 436.971186 -119.415814) (xy 436.624222 -119.762778)
				(xy 436.615586 -119.762778) (xy 436.615586 -120.701816) (xy 436.691786 -120.778016) (xy 438.876186 -120.778016)
				(xy 438.876186 -120.778778) (xy 439.333386 -120.778778) (xy 439.629296 -120.482868) (xy 439.629296 -119.40794)
				(xy 439.571384 -119.350028)
			)
		)
		(polygon
			(pts
				(xy 439.124598 -119.836692) (xy 438.921398 -119.836692) (xy 438.921398 -120.039892) (xy 439.124598 -120.039892)
			)
		)
	)
	(zone
		(layer "B.Cu")
		(hatch none 0.5)
		(connect_pads
			(clearance 0)
		)
		(min_thickness 0.25)
		(keepout
			(tracks not_allowed)
			(vias allowed)
			(pads allowed)
			(copperpour not_allowed)
			(footprints allowed)
		)
		(placement
			(enabled no)
			(sheetname "")
		)
		(fill
			(thermal_gap 0.5)
			(thermal_bridge_width 0.5)
			(island_removal_mode 0)
		)
		(polygon
			(pts
				(arc
					(start 279.236678 -140.54582)
					(mid 278.688038 -141.09446)
					(end 279.236678 -141.6431)
				)
				(arc
					(start 280.636726 -141.6431)
					(mid 281.185366 -141.09446)
					(end 280.636726 -140.54582)
				)
				(arc
					(start 280.161492 -140.54582)
					(mid 280.171517 -140.603555)
					(end 280.176986 -140.661898)
				)
				(xy 280.178002 -140.663168)
				(arc
					(start 280.178002 -140.90269)
					(mid 280.199753 -140.963728)
					(end 280.255218 -140.997178)
				)
				(arc
					(start 280.255218 -140.997178)
					(mid 281.03044 -141.095507)
					(end 280.25471 -141.18971)
				)
				(xy 280.235152 -141.18971)
				(arc
					(start 280.23185 -141.186408)
					(mid 280.071647 -141.105565)
					(end 279.990804 -140.945362)
				)
				(xy 279.987502 -140.94206)
				(arc
					(start 279.987502 -140.702538)
					(mid 279.981904 -140.623383)
					(end 279.96515 -140.54582)
				)
				(arc
					(start 279.858216 -140.54582)
					(mid 279.874899 -140.602639)
					(end 279.884124 -140.661136)
				)
				(xy 279.885902 -140.663168) (xy 279.885902 -140.94206)
				(arc
					(start 279.8826 -140.945362)
					(mid 279.801757 -141.105565)
					(end 279.641554 -141.186408)
				)
				(xy 279.638252 -141.18971)
				(arc
					(start 279.618694 -141.18971)
					(mid 278.842968 -141.095507)
					(end 279.618186 -140.997178)
				)
				(arc
					(start 279.618186 -140.997178)
					(mid 279.673589 -140.963678)
					(end 279.695402 -140.90269)
				)
				(arc
					(start 279.695402 -140.702538)
					(mid 279.682438 -140.620143)
					(end 279.644602 -140.54582)
				)
			)
		)
	)
	(zone
		(layer "B.Cu")
		(hatch none 0.5)
		(connect_pads
			(clearance 0)
		)
		(min_thickness 0.25)
		(keepout
			(tracks not_allowed)
			(vias allowed)
			(pads allowed)
			(copperpour not_allowed)
			(footprints allowed)
		)
		(placement
			(enabled no)
			(sheetname "")
		)
		(fill
			(thermal_gap 0.5)
			(thermal_bridge_width 0.5)
			(island_removal_mode 0)
		)
		(polygon
			(pts
				(arc
					(start 477.637602 -244.312694)
					(mid 477.152462 -243.827554)
					(end 476.667322 -244.312694)
				)
				(xy 476.667322 -244.661944)
				(arc
					(start 476.985584 -244.661944)
					(mid 477.049703 -244.635385)
					(end 477.076262 -244.571266)
				)
				(arc
					(start 477.076262 -244.568218)
					(mid 477.152462 -244.04605)
					(end 477.228662 -244.568218)
				)
				(xy 477.228662 -244.602762)
				(arc
					(start 477.226376 -244.605302)
					(mid 477.161599 -244.73907)
					(end 477.03105 -244.810026)
				)
				(xy 477.026732 -244.814344) (xy 476.667322 -244.814344) (xy 476.667322 -244.954044) (xy 477.01708 -244.954044)
				(arc
					(start 477.01962 -244.95633)
					(mid 477.157542 -245.025164)
					(end 477.226376 -245.163086)
				)
				(xy 477.228662 -245.165626)
				(arc
					(start 477.228662 -245.20017)
					(mid 477.152462 -245.722338)
					(end 477.076262 -245.20017)
				)
				(arc
					(start 477.076262 -245.197122)
					(mid 477.049703 -245.133003)
					(end 476.985584 -245.106444)
				)
				(xy 476.667322 -245.106444)
				(arc
					(start 476.667322 -245.45544)
					(mid 477.152335 -245.940834)
					(end 477.637602 -245.455694)
				)
			)
		)
	)
	(zone
		(net "GND")
		(layer "B.Cu")
		(hatch none 0.5)
		(connect_pads
			(clearance 0.5)
		)
		(min_thickness 0.25)
		(fill yes
			(thermal_gap 0.5)
			(thermal_bridge_width 0.5)
			(island_removal_mode 0)
		)
		(polygon
			(pts
				(xy 39.1922 -214.7062) (xy 38.547802 -215.350598) (xy 38.547802 -217.5256) (xy 39.030402 -218.0082)
				(xy 43.119802 -218.0082) (xy 43.373802 -217.7542) (xy 43.373802 -215.382602) (xy 42.6974 -214.7062)
			)
		)
	)
	(zone
		(layer "B.Cu")
		(hatch none 0.5)
		(connect_pads
			(clearance 0)
		)
		(min_thickness 0.25)
		(keepout
			(tracks not_allowed)
			(vias allowed)
			(pads allowed)
			(copperpour not_allowed)
			(footprints allowed)
		)
		(placement
			(enabled no)
			(sheetname "")
		)
		(fill
			(thermal_gap 0.5)
			(thermal_bridge_width 0.5)
			(island_removal_mode 0)
		)
		(polygon
			(pts
				(arc
					(start 34.770822 -14.41958)
					(mid 34.285809 -13.934186)
					(end 33.800542 -14.419326)
				)
				(arc
					(start 33.800542 -15.562326)
					(mid 34.285682 -16.047466)
					(end 34.770822 -15.562326)
				)
				(xy 34.770822 -15.213076)
				(arc
					(start 34.429954 -15.213076)
					(mid 34.38182 -15.233014)
					(end 34.361882 -15.281148)
				)
				(arc
					(start 34.361882 -15.306802)
					(mid 34.285682 -15.82897)
					(end 34.209482 -15.306802)
				)
				(xy 34.209482 -15.249652)
				(arc
					(start 34.212276 -15.246858)
					(mid 34.274134 -15.125328)
					(end 34.395664 -15.06347)
				)
				(xy 34.398458 -15.060676) (xy 34.770822 -15.060676) (xy 34.770822 -14.920976) (xy 34.388806 -14.920976)
				(arc
					(start 34.386012 -14.918182)
					(mid 34.27122 -14.859238)
					(end 34.212276 -14.744446)
				)
				(xy 34.209482 -14.741652)
				(arc
					(start 34.209482 -14.67485)
					(mid 34.285682 -14.152682)
					(end 34.361882 -14.67485)
				)
				(arc
					(start 34.361882 -14.710156)
					(mid 34.378993 -14.751465)
					(end 34.420302 -14.768576)
				)
				(xy 34.770822 -14.768576)
			)
		)
	)
	(zone
		(layer "B.Cu")
		(hatch none 0.5)
		(connect_pads
			(clearance 0)
		)
		(min_thickness 0.25)
		(keepout
			(tracks not_allowed)
			(vias allowed)
			(pads allowed)
			(copperpour not_allowed)
			(footprints allowed)
		)
		(placement
			(enabled no)
			(sheetname "")
		)
		(fill
			(thermal_gap 0.5)
			(thermal_bridge_width 0.5)
			(island_removal_mode 0)
		)
		(polygon
			(pts
				(arc
					(start 97.870772 -14.41958)
					(mid 97.385759 -13.934186)
					(end 96.900492 -14.419326)
				)
				(arc
					(start 96.900492 -15.562326)
					(mid 97.385632 -16.047466)
					(end 97.870772 -15.562326)
				)
				(xy 97.870772 -15.213076)
				(arc
					(start 97.529904 -15.213076)
					(mid 97.48177 -15.233014)
					(end 97.461832 -15.281148)
				)
				(arc
					(start 97.461832 -15.306802)
					(mid 97.385632 -15.82897)
					(end 97.309432 -15.306802)
				)
				(xy 97.309432 -15.249652)
				(arc
					(start 97.312226 -15.246858)
					(mid 97.374084 -15.125328)
					(end 97.495614 -15.06347)
				)
				(xy 97.498408 -15.060676) (xy 97.870772 -15.060676) (xy 97.870772 -14.920976) (xy 97.488756 -14.920976)
				(arc
					(start 97.485962 -14.918182)
					(mid 97.37117 -14.859238)
					(end 97.312226 -14.744446)
				)
				(xy 97.309432 -14.741652)
				(arc
					(start 97.309432 -14.67485)
					(mid 97.385632 -14.152682)
					(end 97.461832 -14.67485)
				)
				(arc
					(start 97.461832 -14.710156)
					(mid 97.478943 -14.751465)
					(end 97.520252 -14.768576)
				)
				(xy 97.870772 -14.768576)
			)
		)
	)
	(zone
		(net "P12V_B")
		(layer "B.Cu")
		(hatch none 0.5)
		(connect_pads
			(clearance 0.5)
		)
		(min_thickness 0.25)
		(fill yes
			(thermal_gap 0.5)
			(thermal_bridge_width 0.5)
			(island_removal_mode 0)
		)
		(polygon
			(pts
				(xy 256.667 -289.56) (xy 256.413 -289.814) (xy 256.413 -292.862) (xy 257.175 -293.624) (xy 259.715 -293.624)
				(xy 261.239 -292.1) (xy 261.239 -291.084) (xy 260.858 -290.703) (xy 260.35 -290.703) (xy 259.842 -291.211)
				(xy 258.953 -291.211) (xy 258.572 -290.83) (xy 258.572 -290.195) (xy 257.937 -289.56)
			)
		)
	)
	(zone
		(layer "B.Cu")
		(hatch none 0.5)
		(connect_pads
			(clearance 0)
		)
		(min_thickness 0.25)
		(keepout
			(tracks not_allowed)
			(vias allowed)
			(pads allowed)
			(copperpour not_allowed)
			(footprints allowed)
		)
		(placement
			(enabled no)
			(sheetname "")
		)
		(fill
			(thermal_gap 0.5)
			(thermal_bridge_width 0.5)
			(island_removal_mode 0)
		)
		(polygon
			(pts
				(arc
					(start 463.674968 -63.799974)
					(mid 456.674982 -56.799988)
					(end 449.674996 -63.799974)
				)
				(arc
					(start 449.674996 -69.799962)
					(mid 456.674982 -76.799948)
					(end 463.674968 -69.799962)
				)
			)
		)
	)
	(zone
		(layer "B.Cu")
		(hatch none 0.5)
		(connect_pads
			(clearance 0)
		)
		(min_thickness 0.25)
		(keepout
			(tracks not_allowed)
			(vias allowed)
			(pads allowed)
			(copperpour not_allowed)
			(footprints allowed)
		)
		(placement
			(enabled no)
			(sheetname "")
		)
		(fill
			(thermal_gap 0.5)
			(thermal_bridge_width 0.5)
			(island_removal_mode 0)
		)
		(polygon
			(pts
				(arc
					(start 278.23668 -214.745824)
					(mid 277.68804 -215.294464)
					(end 278.23668 -215.843104)
				)
				(arc
					(start 279.636728 -215.843104)
					(mid 280.185368 -215.294464)
					(end 279.636728 -214.745824)
				)
				(arc
					(start 279.141936 -214.745824)
					(mid 279.152757 -214.80783)
					(end 279.158192 -214.870538)
				)
				(xy 279.158954 -214.8713)
				(arc
					(start 279.158954 -215.080596)
					(mid 279.184566 -215.160653)
					(end 279.251918 -215.210898)
				)
				(arc
					(start 279.251918 -215.210898)
					(mid 280.030466 -215.300167)
					(end 279.249632 -215.366854)
				)
				(arc
					(start 279.249632 -215.366854)
					(mid 279.086753 -215.280862)
					(end 279.008586 -215.114124)
				)
				(xy 279.006554 -215.112092)
				(arc
					(start 279.006554 -214.902796)
					(mid 279.001028 -214.82356)
					(end 278.98471 -214.745824)
				)
				(arc
					(start 278.837898 -214.745824)
					(mid 278.856274 -214.806917)
					(end 278.865584 -214.87003)
				)
				(xy 278.866854 -214.8713) (xy 278.866854 -215.112092)
				(arc
					(start 278.864822 -215.114124)
					(mid 278.786577 -215.280787)
					(end 278.623776 -215.366854)
				)
				(arc
					(start 278.623776 -215.366854)
					(mid 277.842915 -215.300168)
					(end 278.62149 -215.210898)
				)
				(arc
					(start 278.62149 -215.210898)
					(mid 278.688775 -215.160605)
					(end 278.714454 -215.080596)
				)
				(arc
					(start 278.714454 -214.902796)
					(mid 278.702457 -214.820867)
					(end 278.667464 -214.745824)
				)
			)
		)
	)
	(zone
		(layer "B.Cu")
		(hatch none 0.5)
		(connect_pads
			(clearance 0)
		)
		(min_thickness 0.25)
		(keepout
			(tracks not_allowed)
			(vias allowed)
			(pads allowed)
			(copperpour not_allowed)
			(footprints allowed)
		)
		(placement
			(enabled no)
			(sheetname "")
		)
		(fill
			(thermal_gap 0.5)
			(thermal_bridge_width 0.5)
			(island_removal_mode 0)
		)
		(polygon
			(pts
				(arc
					(start 134.999984 -339.39988)
					(mid 138.999976 -335.399888)
					(end 134.999984 -331.399896)
				)
				(arc
					(start 129.919984 -331.399896)
					(mid 125.919992 -335.399888)
					(end 129.919984 -339.39988)
				)
			)
		)
	)
	(zone
		(layer "B.Cu")
		(hatch none 0.5)
		(connect_pads
			(clearance 0)
		)
		(min_thickness 0.25)
		(keepout
			(tracks not_allowed)
			(vias allowed)
			(pads allowed)
			(copperpour not_allowed)
			(footprints allowed)
		)
		(placement
			(enabled no)
			(sheetname "")
		)
		(fill
			(thermal_gap 0.5)
			(thermal_bridge_width 0.5)
			(island_removal_mode 0)
		)
		(polygon
			(pts
				(arc
					(start 399.64995 -23.999952)
					(mid 404.400004 -28.750006)
					(end 409.150058 -23.999952)
				)
				(arc
					(start 409.150058 -23.999952)
					(mid 404.400004 -19.249898)
					(end 399.64995 -23.999952)
				)
			)
		)
	)
	(zone
		(layer "B.Cu")
		(hatch none 0.5)
		(connect_pads
			(clearance 0)
		)
		(min_thickness 0.25)
		(keepout
			(tracks not_allowed)
			(vias allowed)
			(pads allowed)
			(copperpour not_allowed)
			(footprints allowed)
		)
		(placement
			(enabled no)
			(sheetname "")
		)
		(fill
			(thermal_gap 0.5)
			(thermal_bridge_width 0.5)
			(island_removal_mode 0)
		)
		(polygon
			(pts
				(arc
					(start 279.236678 -194.945762)
					(mid 278.688038 -195.494402)
					(end 279.236678 -196.043042)
				)
				(arc
					(start 280.636726 -196.043042)
					(mid 281.185366 -195.494402)
					(end 280.636726 -194.945762)
				)
				(arc
					(start 280.141934 -194.945762)
					(mid 280.152755 -195.007768)
					(end 280.15819 -195.070476)
				)
				(xy 280.158952 -195.071238)
				(arc
					(start 280.158952 -195.280534)
					(mid 280.184564 -195.360591)
					(end 280.251916 -195.410836)
				)
				(arc
					(start 280.251916 -195.410836)
					(mid 281.030464 -195.500105)
					(end 280.24963 -195.566792)
				)
				(arc
					(start 280.24963 -195.566792)
					(mid 280.086751 -195.4808)
					(end 280.008584 -195.314062)
				)
				(xy 280.006552 -195.31203)
				(arc
					(start 280.006552 -195.102734)
					(mid 280.001026 -195.023498)
					(end 279.984708 -194.945762)
				)
				(arc
					(start 279.837896 -194.945762)
					(mid 279.856272 -195.006855)
					(end 279.865582 -195.069968)
				)
				(xy 279.866852 -195.071238) (xy 279.866852 -195.31203)
				(arc
					(start 279.86482 -195.314062)
					(mid 279.786575 -195.480725)
					(end 279.623774 -195.566792)
				)
				(arc
					(start 279.623774 -195.566792)
					(mid 278.842913 -195.500106)
					(end 279.621488 -195.410836)
				)
				(arc
					(start 279.621488 -195.410836)
					(mid 279.688773 -195.360543)
					(end 279.714452 -195.280534)
				)
				(arc
					(start 279.714452 -195.102734)
					(mid 279.702455 -195.020805)
					(end 279.667462 -194.945762)
				)
			)
		)
	)
	(zone
		(layer "B.Cu")
		(hatch none 0.5)
		(connect_pads
			(clearance 0)
		)
		(min_thickness 0.25)
		(keepout
			(tracks not_allowed)
			(vias allowed)
			(pads allowed)
			(copperpour not_allowed)
			(footprints allowed)
		)
		(placement
			(enabled no)
			(sheetname "")
		)
		(fill
			(thermal_gap 0.5)
			(thermal_bridge_width 0.5)
			(island_removal_mode 0)
		)
		(polygon
			(pts
				(arc
					(start 97.870772 -129.419604)
					(mid 97.385759 -128.93421)
					(end 96.900492 -129.41935)
				)
				(arc
					(start 96.900492 -130.56235)
					(mid 97.385632 -131.04749)
					(end 97.870772 -130.56235)
				)
				(xy 97.870772 -130.2131)
				(arc
					(start 97.529904 -130.2131)
					(mid 97.48177 -130.233038)
					(end 97.461832 -130.281172)
				)
				(arc
					(start 97.461832 -130.306826)
					(mid 97.385632 -130.828994)
					(end 97.309432 -130.306826)
				)
				(xy 97.309432 -130.249676)
				(arc
					(start 97.312226 -130.246882)
					(mid 97.374084 -130.125352)
					(end 97.495614 -130.063494)
				)
				(xy 97.498408 -130.0607) (xy 97.870772 -130.0607) (xy 97.870772 -129.921) (xy 97.488756 -129.921)
				(arc
					(start 97.485962 -129.918206)
					(mid 97.37117 -129.859262)
					(end 97.312226 -129.74447)
				)
				(xy 97.309432 -129.741676)
				(arc
					(start 97.309432 -129.674874)
					(mid 97.385632 -129.152706)
					(end 97.461832 -129.674874)
				)
				(arc
					(start 97.461832 -129.71018)
					(mid 97.478943 -129.751489)
					(end 97.520252 -129.7686)
				)
				(xy 97.870772 -129.7686)
			)
		)
	)
	(zone
		(net "GND")
		(layer "B.Cu")
		(hatch none 0.5)
		(connect_pads
			(clearance 0.5)
		)
		(min_thickness 0.25)
		(fill yes
			(thermal_gap 0.5)
			(thermal_bridge_width 0.5)
			(island_removal_mode 0)
		)
		(polygon
			(pts
				(xy 172.566076 -82.56778) (xy 169.74312 -79.744824)
				(arc
					(start 163.577778 -79.744824)
					(mid 160.265462 -80.574653)
					(end 156.859478 -80.331056)
				)
				(xy 156.027882 -80.331056) (xy 155.717748 -80.64119) (xy 155.717748 -81.381854) (xy 161.946336 -90.973402)
				(arc
					(start 164.08527 -90.973402)
					(mid 168.134505 -90.896385)
					(end 170.26509 -94.34068)
				)
				(xy 170.946318 -95.021908) (xy 173.096682 -95.021908) (xy 174.291244 -93.827346) (xy 174.291244 -90.684096)
			)
		)
	)
	(zone
		(layer "B.Cu")
		(hatch none 0.5)
		(connect_pads
			(clearance 0)
		)
		(min_thickness 0.25)
		(keepout
			(tracks allowed)
			(vias allowed)
			(pads allowed)
			(copperpour allowed)
			(footprints not_allowed)
		)
		(placement
			(enabled no)
			(sheetname "")
		)
		(fill
			(thermal_gap 0.5)
			(thermal_bridge_width 0.5)
			(island_removal_mode 0)
		)
		(polygon
			(pts
				(arc
					(start 129.919984 -331.399896)
					(mid 125.919992 -335.399888)
					(end 129.919984 -339.39988)
				)
				(arc
					(start 134.999984 -339.39988)
					(mid 138.999976 -335.399888)
					(end 134.999984 -331.399896)
				)
			)
		)
	)
	(zone
		(layer "B.Cu")
		(hatch none 0.5)
		(connect_pads
			(clearance 0)
		)
		(min_thickness 0.25)
		(keepout
			(tracks not_allowed)
			(vias allowed)
			(pads allowed)
			(copperpour not_allowed)
			(footprints allowed)
		)
		(placement
			(enabled no)
			(sheetname "")
		)
		(fill
			(thermal_gap 0.5)
			(thermal_bridge_width 0.5)
			(island_removal_mode 0)
		)
		(polygon
			(pts
				(arc
					(start 278.23668 -200.345802)
					(mid 277.68804 -200.894442)
					(end 278.23668 -201.443082)
				)
				(arc
					(start 279.636728 -201.443082)
					(mid 280.185368 -200.894442)
					(end 279.636728 -200.345802)
				)
				(xy 279.160224 -200.345802) (xy 279.158954 -200.36536)
				(arc
					(start 279.158954 -200.74636)
					(mid 279.180008 -200.797188)
					(end 279.230836 -200.818242)
				)
				(arc
					(start 279.250394 -200.818242)
					(mid 280.030505 -200.894442)
					(end 279.250394 -200.970642)
				)
				(xy 279.19934 -200.970642)
				(arc
					(start 279.196546 -200.968102)
					(mid 279.072177 -200.905019)
					(end 279.009094 -200.78065)
				)
				(xy 279.006554 -200.777856) (xy 279.006554 -200.345802) (xy 278.867362 -200.345802) (xy 278.866854 -200.36536)
				(xy 278.866854 -200.777856)
				(arc
					(start 278.864314 -200.78065)
					(mid 278.801231 -200.905019)
					(end 278.676862 -200.968102)
				)
				(xy 278.674068 -200.970642)
				(arc
					(start 278.623014 -200.970642)
					(mid 277.842903 -200.894442)
					(end 278.623014 -200.818242)
				)
				(arc
					(start 278.642572 -200.818242)
					(mid 278.6934 -200.797188)
					(end 278.714454 -200.74636)
				)
				(xy 278.714454 -200.345802)
			)
		)
	)
	(zone
		(layer "B.Cu")
		(hatch none 0.5)
		(connect_pads
			(clearance 0)
		)
		(min_thickness 0.25)
		(keepout
			(tracks not_allowed)
			(vias allowed)
			(pads allowed)
			(copperpour not_allowed)
			(footprints allowed)
		)
		(placement
			(enabled no)
			(sheetname "")
		)
		(fill
			(thermal_gap 0.5)
			(thermal_bridge_width 0.5)
			(island_removal_mode 0)
		)
		(polygon
			(pts
				(arc
					(start 278.23668 -138.745722)
					(mid 277.68804 -139.294362)
					(end 278.23668 -139.843002)
				)
				(arc
					(start 279.636728 -139.843002)
					(mid 280.185368 -139.294362)
					(end 279.636728 -138.745722)
				)
				(arc
					(start 279.161494 -138.745722)
					(mid 279.171519 -138.803457)
					(end 279.176988 -138.8618)
				)
				(xy 279.178004 -138.86307)
				(arc
					(start 279.178004 -139.102592)
					(mid 279.199755 -139.16363)
					(end 279.25522 -139.19708)
				)
				(arc
					(start 279.25522 -139.19708)
					(mid 280.030442 -139.295409)
					(end 279.254712 -139.389612)
				)
				(xy 279.235154 -139.389612)
				(arc
					(start 279.231852 -139.38631)
					(mid 279.071649 -139.305467)
					(end 278.990806 -139.145264)
				)
				(xy 278.987504 -139.141962)
				(arc
					(start 278.987504 -138.90244)
					(mid 278.981906 -138.823285)
					(end 278.965152 -138.745722)
				)
				(arc
					(start 278.858218 -138.745722)
					(mid 278.874901 -138.802541)
					(end 278.884126 -138.861038)
				)
				(xy 278.885904 -138.86307) (xy 278.885904 -139.141962)
				(arc
					(start 278.882602 -139.145264)
					(mid 278.801759 -139.305467)
					(end 278.641556 -139.38631)
				)
				(xy 278.638254 -139.389612)
				(arc
					(start 278.618696 -139.389612)
					(mid 277.84297 -139.295409)
					(end 278.618188 -139.19708)
				)
				(arc
					(start 278.618188 -139.19708)
					(mid 278.673591 -139.16358)
					(end 278.695404 -139.102592)
				)
				(arc
					(start 278.695404 -138.90244)
					(mid 278.68244 -138.820045)
					(end 278.644604 -138.745722)
				)
			)
		)
	)
	(zone
		(layer "B.Cu")
		(hatch none 0.5)
		(connect_pads
			(clearance 0)
		)
		(min_thickness 0.25)
		(keepout
			(tracks not_allowed)
			(vias allowed)
			(pads allowed)
			(copperpour not_allowed)
			(footprints allowed)
		)
		(placement
			(enabled no)
			(sheetname "")
		)
		(fill
			(thermal_gap 0.5)
			(thermal_bridge_width 0.5)
			(island_removal_mode 0)
		)
		(polygon
			(pts
				(arc
					(start 350.764856 -13.14196)
					(mid 350.279462 -13.626973)
					(end 350.764602 -14.11224)
				)
				(xy 351.113852 -14.11224)
				(arc
					(start 351.113852 -13.801852)
					(mid 351.086671 -13.733891)
					(end 351.020126 -13.7033)
				)
				(arc
					(start 351.020126 -13.7033)
					(mid 350.497958 -13.6271)
					(end 351.020126 -13.5509)
				)
				(xy 351.046796 -13.5509)
				(arc
					(start 351.049082 -13.553186)
					(mid 351.192749 -13.624403)
					(end 351.263966 -13.76807)
				)
				(xy 351.266252 -13.770356) (xy 351.266252 -14.11224) (xy 351.405952 -14.11224) (xy 351.405952 -13.770356)
				(arc
					(start 351.408238 -13.76807)
					(mid 351.479455 -13.624403)
					(end 351.623122 -13.553186)
				)
				(xy 351.625408 -13.5509)
				(arc
					(start 351.652078 -13.5509)
					(mid 352.174246 -13.6271)
					(end 351.652078 -13.7033)
				)
				(arc
					(start 351.652078 -13.7033)
					(mid 351.585448 -13.733809)
					(end 351.558352 -13.801852)
				)
				(xy 351.558352 -14.11224)
				(arc
					(start 351.907602 -14.11224)
					(mid 352.392742 -13.6271)
					(end 351.907602 -13.14196)
				)
			)
		)
	)
	(zone
		(layer "B.Cu")
		(hatch none 0.5)
		(connect_pads
			(clearance 0)
		)
		(min_thickness 0.25)
		(keepout
			(tracks allowed)
			(vias allowed)
			(pads allowed)
			(copperpour allowed)
			(footprints not_allowed)
		)
		(placement
			(enabled no)
			(sheetname "")
		)
		(fill
			(thermal_gap 0.5)
			(thermal_bridge_width 0.5)
			(island_removal_mode 0)
		)
		(polygon
			(pts
				(arc
					(start 196.799962 -94.000066)
					(mid 189.799976 -87.00008)
					(end 182.79999 -94.000066)
				)
				(arc
					(start 182.79999 -100.000054)
					(mid 189.799976 -107.00004)
					(end 196.799962 -100.000054)
				)
			)
		)
	)
	(zone
		(layer "B.Cu")
		(hatch none 0.5)
		(connect_pads
			(clearance 0)
		)
		(min_thickness 0.25)
		(keepout
			(tracks allowed)
			(vias allowed)
			(pads allowed)
			(copperpour allowed)
			(footprints allowed)
		)
		(placement
			(enabled no)
			(sheetname "")
		)
		(fill
			(thermal_gap 0.5)
			(thermal_bridge_width 0.5)
			(island_removal_mode 0)
		)
		(polygon
			(pts
				(xy 256.7686 -281.9146) (xy 256.7686 -283.2354) (xy 255.5494 -283.2354) (xy 255.5494 -281.9146)
			)
		)
	)
	(zone
		(layer "B.Cu")
		(hatch none 0.5)
		(connect_pads
			(clearance 0)
		)
		(min_thickness 0.25)
		(keepout
			(tracks not_allowed)
			(vias allowed)
			(pads allowed)
			(copperpour not_allowed)
			(footprints allowed)
		)
		(placement
			(enabled no)
			(sheetname "")
		)
		(fill
			(thermal_gap 0.5)
			(thermal_bridge_width 0.5)
			(island_removal_mode 0)
		)
		(polygon
			(pts
				(arc
					(start 221.348808 -77.600302)
					(mid 220.800295 -77.051408)
					(end 220.251528 -77.600048)
				)
				(arc
					(start 220.251528 -78.999842)
					(mid 220.800168 -79.548482)
					(end 221.348808 -78.999842)
				)
				(arc
					(start 221.348808 -78.580234)
					(mid 221.285733 -78.551117)
					(end 221.216982 -78.541118)
				)
				(arc
					(start 220.988382 -78.541118)
					(mid 220.928496 -78.562899)
					(end 220.896688 -78.61808)
				)
				(arc
					(start 220.896688 -78.61808)
					(mid 220.800022 -79.393554)
					(end 220.704918 -78.617826)
				)
				(xy 220.704918 -78.594712)
				(arc
					(start 220.70822 -78.59141)
					(mid 220.787993 -78.433693)
					(end 220.94571 -78.35392)
				)
				(xy 220.949012 -78.350618) (xy 221.256352 -78.350618)
				(arc
					(start 221.258384 -78.35265)
					(mid 221.304092 -78.359503)
					(end 221.348808 -78.371192)
				)
				(arc
					(start 221.348808 -78.265528)
					(mid 221.283411 -78.253147)
					(end 221.216982 -78.249018)
				)
				(xy 220.949012 -78.249018)
				(arc
					(start 220.94571 -78.245716)
					(mid 220.787993 -78.165943)
					(end 220.70822 -78.008226)
				)
				(xy 220.704918 -78.004924)
				(arc
					(start 220.704918 -77.982064)
					(mid 220.799898 -77.206275)
					(end 220.896942 -77.98181)
				)
				(arc
					(start 220.896942 -77.98181)
					(mid 220.928734 -78.036741)
					(end 220.988382 -78.058518)
				)
				(xy 221.256352 -78.058518)
				(arc
					(start 221.257622 -78.059534)
					(mid 221.303392 -78.063679)
					(end 221.348808 -78.07071)
				)
			)
		)
	)
	(zone
		(layer "B.Cu")
		(hatch none 0.5)
		(connect_pads
			(clearance 0)
		)
		(min_thickness 0.25)
		(keepout
			(tracks allowed)
			(vias allowed)
			(pads allowed)
			(copperpour allowed)
			(footprints not_allowed)
		)
		(placement
			(enabled no)
			(sheetname "")
		)
		(fill
			(thermal_gap 0.5)
			(thermal_bridge_width 0.5)
			(island_removal_mode 0)
		)
		(polygon
			(pts
				(arc
					(start 491.450122 -0.999998)
					(mid 491.157229 -0.292893)
					(end 490.450124 0)
				)
				(arc
					(start 311.999884 0)
					(mid 311.292779 -0.292893)
					(end 310.999886 -0.999998)
				)
				(xy 310.999886 -39.99992) (xy 491.450122 -39.99992)
			)
		)
	)
	(zone
		(layer "B.Cu")
		(hatch none 0.5)
		(connect_pads
			(clearance 0)
		)
		(min_thickness 0.25)
		(keepout
			(tracks not_allowed)
			(vias allowed)
			(pads allowed)
			(copperpour not_allowed)
			(footprints allowed)
		)
		(placement
			(enabled no)
			(sheetname "")
		)
		(fill
			(thermal_gap 0.5)
			(thermal_bridge_width 0.5)
			(island_removal_mode 0)
		)
		(polygon
			(pts
				(arc
					(start 279.236678 -205.745842)
					(mid 278.688038 -206.294482)
					(end 279.236678 -206.843122)
				)
				(arc
					(start 280.636726 -206.843122)
					(mid 281.185366 -206.294482)
					(end 280.636726 -205.745842)
				)
				(xy 280.160222 -205.745842) (xy 280.158952 -205.7654)
				(arc
					(start 280.158952 -206.1464)
					(mid 280.180006 -206.197228)
					(end 280.230834 -206.218282)
				)
				(arc
					(start 280.250392 -206.218282)
					(mid 281.030503 -206.294482)
					(end 280.250392 -206.370682)
				)
				(xy 280.199338 -206.370682)
				(arc
					(start 280.196544 -206.368142)
					(mid 280.072175 -206.305059)
					(end 280.009092 -206.18069)
				)
				(xy 280.006552 -206.177896) (xy 280.006552 -205.745842) (xy 279.86736 -205.745842) (xy 279.866852 -205.7654)
				(xy 279.866852 -206.177896)
				(arc
					(start 279.864312 -206.18069)
					(mid 279.801229 -206.305059)
					(end 279.67686 -206.368142)
				)
				(xy 279.674066 -206.370682)
				(arc
					(start 279.623012 -206.370682)
					(mid 278.842901 -206.294482)
					(end 279.623012 -206.218282)
				)
				(arc
					(start 279.64257 -206.218282)
					(mid 279.693398 -206.197228)
					(end 279.714452 -206.1464)
				)
				(xy 279.714452 -205.745842)
			)
		)
	)
	(zone
		(net "GND")
		(layer "B.Cu")
		(hatch none 0.5)
		(connect_pads
			(clearance 0.5)
		)
		(min_thickness 0.25)
		(fill yes
			(thermal_gap 0.5)
			(thermal_bridge_width 0.5)
			(island_removal_mode 0)
		)
		(polygon
			(pts
				(xy 479.618802 -228.60635) (xy 479.364802 -228.86035) (xy 479.364802 -230.63835) (xy 479.745802 -231.01935)
				(xy 484.952802 -231.01935) (xy 485.206802 -230.76535) (xy 485.206802 -228.73335) (xy 485.079802 -228.60635)
			)
		)
	)
	(zone
		(net "GND")
		(layer "B.Cu")
		(hatch none 0.5)
		(connect_pads
			(clearance 0.5)
		)
		(min_thickness 0.25)
		(fill yes
			(thermal_gap 0.5)
			(thermal_bridge_width 0.5)
			(island_removal_mode 0)
		)
		(polygon
			(pts
				(xy 445.208152 -223.393) (xy 445.074802 -223.52635) (xy 445.074802 -225.30435) (xy 447.614802 -227.84435)
				(xy 450.662802 -227.84435) (xy 450.789802 -227.71735) (xy 450.789802 -226.32035) (xy 451.297802 -225.812096)
				(xy 451.297802 -224.66935) (xy 451.805802 -224.16135) (xy 451.805802 -223.52635) (xy 451.678802 -223.39935)
				(xy 450.916802 -223.39935) (xy 450.910452 -223.393)
			)
		)
		(polygon
			(pts
				(xy 450.510402 -225.76155) (xy 450.307202 -225.76155) (xy 450.307202 -225.96475) (xy 450.510402 -225.96475)
			)
		)
		(polygon
			(pts
				(xy 450.510402 -224.89795) (xy 450.307202 -224.89795) (xy 450.307202 -225.10115) (xy 450.510402 -225.10115)
			)
		)
		(polygon
			(pts
				(xy 451.221602 -223.93275) (xy 451.018402 -223.93275) (xy 451.018402 -224.13595) (xy 451.221602 -224.13595)
			)
		)
	)
	(zone
		(layer "B.Cu")
		(hatch none 0.5)
		(connect_pads
			(clearance 0)
		)
		(min_thickness 0.25)
		(keepout
			(tracks not_allowed)
			(vias allowed)
			(pads allowed)
			(copperpour not_allowed)
			(footprints allowed)
		)
		(placement
			(enabled no)
			(sheetname "")
		)
		(fill
			(thermal_gap 0.5)
			(thermal_bridge_width 0.5)
			(island_removal_mode 0)
		)
		(polygon
			(pts
				(arc
					(start 66.32067 -129.419604)
					(mid 65.835657 -128.93421)
					(end 65.35039 -129.41935)
				)
				(arc
					(start 65.35039 -130.56235)
					(mid 65.83553 -131.04749)
					(end 66.32067 -130.56235)
				)
				(xy 66.32067 -130.2131)
				(arc
					(start 65.979802 -130.2131)
					(mid 65.931668 -130.233038)
					(end 65.91173 -130.281172)
				)
				(arc
					(start 65.91173 -130.306826)
					(mid 65.83553 -130.828994)
					(end 65.75933 -130.306826)
				)
				(xy 65.75933 -130.249676)
				(arc
					(start 65.762124 -130.246882)
					(mid 65.823982 -130.125352)
					(end 65.945512 -130.063494)
				)
				(xy 65.948306 -130.0607) (xy 66.32067 -130.0607) (xy 66.32067 -129.921) (xy 65.938654 -129.921)
				(arc
					(start 65.93586 -129.918206)
					(mid 65.821068 -129.859262)
					(end 65.762124 -129.74447)
				)
				(xy 65.75933 -129.741676)
				(arc
					(start 65.75933 -129.674874)
					(mid 65.83553 -129.152706)
					(end 65.91173 -129.674874)
				)
				(arc
					(start 65.91173 -129.71018)
					(mid 65.928841 -129.751489)
					(end 65.97015 -129.7686)
				)
				(xy 66.32067 -129.7686)
			)
		)
	)
	(zone
		(layer "B.Cu")
		(hatch none 0.5)
		(connect_pads
			(clearance 0)
		)
		(min_thickness 0.25)
		(keepout
			(tracks not_allowed)
			(vias allowed)
			(pads allowed)
			(copperpour not_allowed)
			(footprints allowed)
		)
		(placement
			(enabled no)
			(sheetname "")
		)
		(fill
			(thermal_gap 0.5)
			(thermal_bridge_width 0.5)
			(island_removal_mode 0)
		)
		(polygon
			(pts
				(arc
					(start 279.236678 -198.545704)
					(mid 278.688038 -199.094344)
					(end 279.236678 -199.642984)
				)
				(arc
					(start 280.636726 -199.642984)
					(mid 281.185366 -199.094344)
					(end 280.636726 -198.545704)
				)
				(xy 280.160222 -198.545704) (xy 280.158952 -198.565262)
				(arc
					(start 280.158952 -198.946262)
					(mid 280.180006 -198.99709)
					(end 280.230834 -199.018144)
				)
				(arc
					(start 280.250392 -199.018144)
					(mid 281.030503 -199.094344)
					(end 280.250392 -199.170544)
				)
				(xy 280.199338 -199.170544)
				(arc
					(start 280.196544 -199.168004)
					(mid 280.072175 -199.104921)
					(end 280.009092 -198.980552)
				)
				(xy 280.006552 -198.977758) (xy 280.006552 -198.545704) (xy 279.86736 -198.545704) (xy 279.866852 -198.565262)
				(xy 279.866852 -198.977758)
				(arc
					(start 279.864312 -198.980552)
					(mid 279.801229 -199.104921)
					(end 279.67686 -199.168004)
				)
				(xy 279.674066 -199.170544)
				(arc
					(start 279.623012 -199.170544)
					(mid 278.842901 -199.094344)
					(end 279.623012 -199.018144)
				)
				(arc
					(start 279.64257 -199.018144)
					(mid 279.693398 -198.99709)
					(end 279.714452 -198.946262)
				)
				(xy 279.714452 -198.545704)
			)
		)
	)
	(zone
		(layer "B.Cu")
		(hatch none 0.5)
		(connect_pads
			(clearance 0)
		)
		(min_thickness 0.25)
		(keepout
			(tracks not_allowed)
			(vias allowed)
			(pads allowed)
			(copperpour not_allowed)
			(footprints allowed)
		)
		(placement
			(enabled no)
			(sheetname "")
		)
		(fill
			(thermal_gap 0.5)
			(thermal_bridge_width 0.5)
			(island_removal_mode 0)
		)
		(polygon
			(pts
				(arc
					(start 160.970722 -244.419374)
					(mid 160.485582 -243.934234)
					(end 160.000442 -244.419374)
				)
				(arc
					(start 160.000442 -245.56212)
					(mid 160.485455 -246.047514)
					(end 160.970722 -245.562374)
				)
				(xy 160.970722 -245.213124)
				(arc
					(start 160.629854 -245.213124)
					(mid 160.58172 -245.233062)
					(end 160.561782 -245.281196)
				)
				(arc
					(start 160.561782 -245.30685)
					(mid 160.485582 -245.829018)
					(end 160.409382 -245.30685)
				)
				(xy 160.409382 -245.2497)
				(arc
					(start 160.412176 -245.246906)
					(mid 160.474034 -245.125376)
					(end 160.595564 -245.063518)
				)
				(xy 160.598358 -245.060724) (xy 160.970722 -245.060724) (xy 160.970722 -244.921024) (xy 160.588706 -244.921024)
				(arc
					(start 160.585912 -244.91823)
					(mid 160.47112 -244.859286)
					(end 160.412176 -244.744494)
				)
				(xy 160.409382 -244.7417)
				(arc
					(start 160.409382 -244.674898)
					(mid 160.485582 -244.15273)
					(end 160.561782 -244.674898)
				)
				(arc
					(start 160.561782 -244.710204)
					(mid 160.578893 -244.751513)
					(end 160.620202 -244.768624)
				)
				(xy 160.970722 -244.768624)
			)
		)
	)
	(zone
		(layer "B.Cu")
		(hatch none 0.5)
		(connect_pads
			(clearance 0)
		)
		(min_thickness 0.25)
		(keepout
			(tracks allowed)
			(vias allowed)
			(pads allowed)
			(copperpour allowed)
			(footprints not_allowed)
		)
		(placement
			(enabled no)
			(sheetname "")
		)
		(fill
			(thermal_gap 0.5)
			(thermal_bridge_width 0.5)
			(island_removal_mode 0)
		)
		(polygon
			(pts
				(arc
					(start 199.00011 -0.999998)
					(mid 198.707217 -0.292893)
					(end 198.000112 0)
				)
				(arc
					(start 0.999998 0)
					(mid 0.292893 -0.292893)
					(end 0 -0.999998)
				)
				(xy 0 -39.99992) (xy 199.00011 -39.99992)
			)
		)
	)
	(zone
		(net "GND")
		(layer "B.Cu")
		(hatch none 0.5)
		(connect_pads
			(clearance 0.5)
		)
		(min_thickness 0.25)
		(fill yes
			(thermal_gap 0.5)
			(thermal_bridge_width 0.5)
			(island_removal_mode 0)
		)
		(polygon
			(pts
				(xy 39.00805 -231.67975) (xy 38.674802 -232.012998) (xy 38.674802 -235.245402) (xy 39.02075 -235.59135)
				(xy 43.02125 -235.59135) (xy 43.348402 -235.264198) (xy 43.348402 -232.070402) (xy 42.95775 -231.67975)
			)
		)
	)
	(zone
		(layer "B.Cu")
		(hatch none 0.5)
		(connect_pads
			(clearance 0)
		)
		(min_thickness 0.25)
		(keepout
			(tracks allowed)
			(vias allowed)
			(pads allowed)
			(copperpour allowed)
			(footprints allowed)
		)
		(placement
			(enabled no)
			(sheetname "")
		)
		(fill
			(thermal_gap 0.5)
			(thermal_bridge_width 0.5)
			(island_removal_mode 0)
		)
		(polygon
			(pts
				(xy 33.956244 -113.36401) (xy 33.956244 -111.213138) (xy 42.121582 -111.213138) (xy 42.121582 -113.36401)
			)
		)
	)
	(zone
		(net "MB3_P12V_IN_R")
		(layer "B.Cu")
		(hatch none 0.5)
		(connect_pads
			(clearance 0.5)
		)
		(min_thickness 0.25)
		(fill yes
			(thermal_gap 0.5)
			(thermal_bridge_width 0.5)
			(island_removal_mode 0)
		)
		(polygon
			(pts
				(xy 249.7836 -329.8952) (xy 249.4788 -330.2) (xy 249.4788 -330.9366) (xy 249.1994 -331.216) (xy 249.1994 -344.0176)
				(xy 249.203972 -344.0176) (xy 250.677172 -345.4908) (xy 250.677172 -353.915218) (xy 251.149104 -354.38715)
				(xy 258.237228 -354.38715) (xy 260.024372 -352.600006) (xy 260.024372 -330.610972) (xy 259.3086 -329.8952)
			)
		)
	)
	(zone
		(layer "B.Cu")
		(hatch none 0.5)
		(connect_pads
			(clearance 0)
		)
		(min_thickness 0.25)
		(keepout
			(tracks allowed)
			(vias allowed)
			(pads allowed)
			(copperpour allowed)
			(footprints allowed)
		)
		(placement
			(enabled no)
			(sheetname "")
		)
		(fill
			(thermal_gap 0.5)
			(thermal_bridge_width 0.5)
			(island_removal_mode 0)
		)
		(polygon
			(pts
				(xy 254.4826 -280.0096) (xy 255.2446 -280.0096) (xy 255.2446 -281.2288) (xy 254.4826 -281.2288)
			)
		)
	)
	(zone
		(layer "B.Cu")
		(hatch none 0.5)
		(connect_pads
			(clearance 0)
		)
		(min_thickness 0.25)
		(keepout
			(tracks not_allowed)
			(vias allowed)
			(pads allowed)
			(copperpour not_allowed)
			(footprints allowed)
		)
		(placement
			(enabled no)
			(sheetname "")
		)
		(fill
			(thermal_gap 0.5)
			(thermal_bridge_width 0.5)
			(island_removal_mode 0)
		)
		(polygon
			(pts
				(arc
					(start 278.23668 -211.145882)
					(mid 277.68804 -211.694522)
					(end 278.23668 -212.243162)
				)
				(arc
					(start 279.636728 -212.243162)
					(mid 280.185368 -211.694522)
					(end 279.636728 -211.145882)
				)
				(arc
					(start 279.141936 -211.145882)
					(mid 279.152757 -211.207888)
					(end 279.158192 -211.270596)
				)
				(xy 279.158954 -211.271358)
				(arc
					(start 279.158954 -211.480654)
					(mid 279.184566 -211.560711)
					(end 279.251918 -211.610956)
				)
				(arc
					(start 279.251918 -211.610956)
					(mid 280.030466 -211.700225)
					(end 279.249632 -211.766912)
				)
				(arc
					(start 279.249632 -211.766912)
					(mid 279.086753 -211.68092)
					(end 279.008586 -211.514182)
				)
				(xy 279.006554 -211.51215)
				(arc
					(start 279.006554 -211.302854)
					(mid 279.001028 -211.223618)
					(end 278.98471 -211.145882)
				)
				(arc
					(start 278.837898 -211.145882)
					(mid 278.856274 -211.206975)
					(end 278.865584 -211.270088)
				)
				(xy 278.866854 -211.271358) (xy 278.866854 -211.51215)
				(arc
					(start 278.864822 -211.514182)
					(mid 278.786577 -211.680845)
					(end 278.623776 -211.766912)
				)
				(arc
					(start 278.623776 -211.766912)
					(mid 277.842915 -211.700226)
					(end 278.62149 -211.610956)
				)
				(arc
					(start 278.62149 -211.610956)
					(mid 278.688775 -211.560663)
					(end 278.714454 -211.480654)
				)
				(arc
					(start 278.714454 -211.302854)
					(mid 278.702457 -211.220925)
					(end 278.667464 -211.145882)
				)
			)
		)
	)
	(zone
		(layer "B.Cu")
		(hatch none 0.5)
		(connect_pads
			(clearance 0)
		)
		(min_thickness 0.25)
		(keepout
			(tracks not_allowed)
			(vias allowed)
			(pads allowed)
			(copperpour not_allowed)
			(footprints allowed)
		)
		(placement
			(enabled no)
			(sheetname "")
		)
		(fill
			(thermal_gap 0.5)
			(thermal_bridge_width 0.5)
			(island_removal_mode 0)
		)
		(polygon
			(pts
				(arc
					(start 40.32504 -293.800022)
					(mid 33.325054 -286.800036)
					(end 26.325068 -293.800022)
				)
				(arc
					(start 26.325068 -299.80001)
					(mid 33.325054 -306.799996)
					(end 40.32504 -299.80001)
				)
			)
		)
	)
	(zone
		(layer "B.Cu")
		(hatch none 0.5)
		(connect_pads
			(clearance 0)
		)
		(min_thickness 0.25)
		(keepout
			(tracks allowed)
			(vias allowed)
			(pads allowed)
			(copperpour allowed)
			(footprints not_allowed)
		)
		(placement
			(enabled no)
			(sheetname "")
		)
		(fill
			(thermal_gap 0.5)
			(thermal_bridge_width 0.5)
			(island_removal_mode 0)
		)
		(polygon
			(pts
				(arc
					(start 134.999984 -339.39988)
					(mid 138.999976 -335.399888)
					(end 134.999984 -331.399896)
				)
				(arc
					(start 129.919984 -331.399896)
					(mid 125.919992 -335.399888)
					(end 129.919984 -339.39988)
				)
			)
		)
	)
	(zone
		(net "GND")
		(layer "B.Cu")
		(hatch none 0.5)
		(connect_pads
			(clearance 0.5)
		)
		(min_thickness 0.25)
		(fill yes
			(thermal_gap 0.5)
			(thermal_bridge_width 0.5)
			(island_removal_mode 0)
		)
		(polygon
			(pts
				(xy 184.7977 -304.343308) (xy 171.720256 -317.420752) (xy 52.01158 -317.420752) (xy 41.311576 -328.120756)
				(xy 41.311576 -344.125804) (xy 42.776648 -345.590876)
				(arc
					(start 43.18 -345.590876)
					(mid 46.126602 -346.811398)
					(end 47.347124 -349.758)
				)
				(arc
					(start 47.347124 -351.282)
					(mid 47.321266 -351.745507)
					(end 47.244 -352.203258)
				)
				(xy 47.244 -353.533202) (xy 49.36109 -355.650292)
				(arc
					(start 53.148738 -355.650292)
					(mid 53.439838 -355.658237)
					(end 53.729636 -355.686868)
				)
				(xy 53.817266 -355.599492) (xy 63.708534 -355.599492) (xy 66.883534 -358.774492)
				(arc
					(start 69.846698 -358.774492)
					(mid 71.0438 -358.596539)
					(end 72.240902 -358.774492)
				)
				(xy 87.990934 -358.774492) (xy 87.991442 -358.775) (xy 89.35593 -358.775) (xy 90.454988 -357.675942)
				(xy 90.454988 -355.950012) (xy 92.968826 -353.436174) (xy 99.316286 -353.436174) (xy 100.012246 -352.740214)
				(xy 100.012246 -351.415858) (xy 99.370642 -350.774254) (xy 71.700644 -350.774254) (xy 68.960746 -348.034356)
				(xy 68.960746 -342.69299) (xy 66.91376 -340.646004)
				(arc
					(start 63.945262 -340.646004)
					(mid 57.276669 -334.546463)
					(end 65.513458 -330.827634)
				)
				(arc
					(start 65.513458 -330.827634)
					(mid 67.207459 -330.355733)
					(end 68.960746 -330.491084)
				)
				(xy 68.960746 -330.399644) (xy 71.700644 -327.659746) (xy 102.577138 -327.659746) (xy 102.647242 -327.589642)
				(arc
					(start 128.644396 -327.589642)
					(mid 130.410001 -328.011017)
					(end 131.795266 -329.184)
				)
				(arc
					(start 133.124702 -329.184)
					(mid 134.510003 -328.011088)
					(end 136.275572 -327.589642)
				)
				(xy 146.589242 -327.589642) (xy 150.773638 -323.405246) (xy 158.852362 -323.405246) (xy 160.757362 -325.310246)
				(xy 187.804552 -325.310246) (xy 189.978792 -323.136006) (xy 189.978792 -305.921918) (xy 188.400182 -304.343308)
			)
		)
	)
	(zone
		(layer "B.Cu")
		(hatch none 0.5)
		(connect_pads
			(clearance 0)
		)
		(min_thickness 0.25)
		(keepout
			(tracks allowed)
			(vias allowed)
			(pads allowed)
			(copperpour allowed)
			(footprints allowed)
		)
		(placement
			(enabled no)
			(sheetname "")
		)
		(fill
			(thermal_gap 0.5)
			(thermal_bridge_width 0.5)
			(island_removal_mode 0)
		)
		(polygon
			(pts
				(xy 19.318224 -221.364048) (xy 21.469096 -221.364048) (xy 21.469096 -226.137724) (xy 19.318224 -226.137724)
			)
		)
	)
	(zone
		(layer "B.Cu")
		(hatch none 0.5)
		(connect_pads
			(clearance 0)
		)
		(min_thickness 0.25)
		(keepout
			(tracks not_allowed)
			(vias allowed)
			(pads allowed)
			(copperpour not_allowed)
			(footprints allowed)
		)
		(placement
			(enabled no)
			(sheetname "")
		)
		(fill
			(thermal_gap 0.5)
			(thermal_bridge_width 0.5)
			(island_removal_mode 0)
		)
		(polygon
			(pts
				(arc
					(start 279.236678 -144.145762)
					(mid 278.688038 -144.694402)
					(end 279.236678 -145.243042)
				)
				(arc
					(start 280.636726 -145.243042)
					(mid 281.185366 -144.694402)
					(end 280.636726 -144.145762)
				)
				(arc
					(start 280.108406 -144.145762)
					(mid 280.160444 -144.320835)
					(end 280.178002 -144.502632)
				)
				(arc
					(start 280.178002 -144.502632)
					(mid 280.199753 -144.56367)
					(end 280.255218 -144.59712)
				)
				(arc
					(start 280.255218 -144.59712)
					(mid 281.03044 -144.695449)
					(end 280.25471 -144.789652)
				)
				(xy 280.235152 -144.789652)
				(arc
					(start 280.23185 -144.78635)
					(mid 280.056939 -144.689884)
					(end 279.987502 -144.502632)
				)
				(arc
					(start 279.987502 -144.502632)
					(mid 279.96488 -144.318711)
					(end 279.898348 -144.145762)
				)
				(arc
					(start 279.780492 -144.145762)
					(mid 279.859 -144.316579)
					(end 279.885902 -144.502632)
				)
				(arc
					(start 279.885902 -144.502632)
					(mid 279.816385 -144.689815)
					(end 279.641554 -144.78635)
				)
				(xy 279.638252 -144.789652)
				(arc
					(start 279.618694 -144.789652)
					(mid 278.842968 -144.695449)
					(end 279.618186 -144.59712)
				)
				(arc
					(start 279.618186 -144.59712)
					(mid 279.673589 -144.56362)
					(end 279.695402 -144.502632)
				)
				(arc
					(start 279.695402 -144.502632)
					(mid 279.651911 -144.305867)
					(end 279.52954 -144.145762)
				)
			)
		)
	)
	(zone
		(layer "B.Cu")
		(hatch none 0.5)
		(connect_pads
			(clearance 0)
		)
		(min_thickness 0.25)
		(keepout
			(tracks not_allowed)
			(vias allowed)
			(pads allowed)
			(copperpour not_allowed)
			(footprints allowed)
		)
		(placement
			(enabled no)
			(sheetname "")
		)
		(fill
			(thermal_gap 0.5)
			(thermal_bridge_width 0.5)
			(island_removal_mode 0)
		)
		(polygon
			(pts
				(arc
					(start 279.236678 -212.945726)
					(mid 278.688038 -213.494366)
					(end 279.236678 -214.043006)
				)
				(arc
					(start 280.636726 -214.043006)
					(mid 281.185366 -213.494366)
					(end 280.636726 -212.945726)
				)
				(arc
					(start 280.141934 -212.945726)
					(mid 280.152755 -213.007732)
					(end 280.15819 -213.07044)
				)
				(xy 280.158952 -213.071202)
				(arc
					(start 280.158952 -213.280498)
					(mid 280.184564 -213.360555)
					(end 280.251916 -213.4108)
				)
				(arc
					(start 280.251916 -213.4108)
					(mid 281.030464 -213.500069)
					(end 280.24963 -213.566756)
				)
				(arc
					(start 280.24963 -213.566756)
					(mid 280.086751 -213.480764)
					(end 280.008584 -213.314026)
				)
				(xy 280.006552 -213.311994)
				(arc
					(start 280.006552 -213.102698)
					(mid 280.001026 -213.023462)
					(end 279.984708 -212.945726)
				)
				(arc
					(start 279.837896 -212.945726)
					(mid 279.856272 -213.006819)
					(end 279.865582 -213.069932)
				)
				(xy 279.866852 -213.071202) (xy 279.866852 -213.311994)
				(arc
					(start 279.86482 -213.314026)
					(mid 279.786575 -213.480689)
					(end 279.623774 -213.566756)
				)
				(arc
					(start 279.623774 -213.566756)
					(mid 278.842913 -213.50007)
					(end 279.621488 -213.4108)
				)
				(arc
					(start 279.621488 -213.4108)
					(mid 279.688773 -213.360507)
					(end 279.714452 -213.280498)
				)
				(arc
					(start 279.714452 -213.102698)
					(mid 279.702455 -213.020769)
					(end 279.667462 -212.945726)
				)
			)
		)
	)
	(zone
		(net "GND")
		(layer "B.Cu")
		(hatch none 0.5)
		(connect_pads
			(clearance 0.5)
		)
		(min_thickness 0.25)
		(fill yes
			(thermal_gap 0.5)
			(thermal_bridge_width 0.5)
			(island_removal_mode 0)
		)
		(polygon
			(pts
				(xy 139.087352 -70.5358) (xy 131.739132 -35.963606) (xy 130.55981 -34.784284) (xy 127.573278 -34.784284)
				(xy 126.802388 -35.555174)
				(arc
					(start 126.802388 -37.045392)
					(mid 126.984414 -37.72964)
					(end 127.04572 -38.435026)
				)
				(arc
					(start 127.04572 -40.975026)
					(mid 127.001391 -41.57538)
					(end 126.869444 -42.16273)
				)
				(arc
					(start 126.869444 -45.797978)
					(mid 127.197364 -46.687466)
					(end 127.330962 -47.626016)
				)
				(arc
					(start 127.330962 -47.626016)
					(mid 128.652847 -51.952463)
					(end 125.179328 -54.850792)
				)
				(xy 124.578364 -55.451756) (xy 124.578364 -56.342534) (xy 145.208244 -88.11006) (xy 152.878028 -93.091254)
				(xy 153.279856 -93.091254) (xy 153.410412 -92.960698) (xy 153.410412 -92.592144) (xy 145.087594 -79.775304)
				(xy 144.877028 -79.7306) (xy 144.295876 -78.836266) (xy 144.295876 -78.836012) (xy 142.338806 -75.82281)
				(xy 142.338806 -75.822556) (xy 141.176756 -74.03338) (xy 141.221714 -73.822306)
			)
		)
	)
	(zone
		(net "GND")
		(layer "B.Cu")
		(hatch none 0.5)
		(connect_pads
			(clearance 0.5)
		)
		(min_thickness 0.25)
		(fill yes
			(thermal_gap 0.5)
			(thermal_bridge_width 0.5)
			(island_removal_mode 0)
		)
		(polygon
			(pts
				(arc
					(start 366.268 -147.981924)
					(mid 362.209988 -144.408874)
					(end 365.24057 -139.93114)
				)
				(xy 366.368076 -138.803634)
				(arc
					(start 366.368076 -137.033)
					(mid 366.488266 -136.048656)
					(end 366.841786 -135.122158)
				)
				(xy 366.841786 -134.909306) (xy 366.694974 -134.762494)
				(arc
					(start 366.20196 -134.762494)
					(mid 366.042631 -135.01619)
					(end 365.865156 -135.25754)
				)
				(arc
					(start 365.865156 -135.25754)
					(mid 364.734852 -138.533171)
					(end 361.496356 -139.765786)
				)
				(xy 360.15295 -141.109192)
				(arc
					(start 360.15295 -141.23035)
					(mid 360.1309 -141.654271)
					(end 360.065066 -142.07363)
				)
				(arc
					(start 360.065066 -142.889986)
					(mid 360.975709 -144.228298)
					(end 361.29595 -145.81505)
				)
				(arc
					(start 361.29595 -148.35505)
					(mid 361.292231 -148.527925)
					(end 361.281218 -148.70049)
				)
				(arc
					(start 362.163868 -149.58314)
					(mid 362.734861 -149.599711)
					(end 363.297978 -149.695662)
				)
				(arc
					(start 363.297978 -149.695662)
					(mid 365.118131 -149.200925)
					(end 366.966754 -149.57552)
				)
				(xy 368.925856 -149.57552) (xy 369.311428 -149.189948) (xy 369.311428 -148.255736)
				(arc
					(start 369.03152 -147.975828)
					(mid 368.919929 -147.9804)
					(end 368.808254 -147.981924)
				)
			)
		)
	)
	(zone
		(layer "B.Cu")
		(hatch none 0.5)
		(connect_pads
			(clearance 0)
		)
		(min_thickness 0.25)
		(keepout
			(tracks not_allowed)
			(vias allowed)
			(pads allowed)
			(copperpour not_allowed)
			(footprints allowed)
		)
		(placement
			(enabled no)
			(sheetname "")
		)
		(fill
			(thermal_gap 0.5)
			(thermal_bridge_width 0.5)
			(island_removal_mode 0)
		)
		(polygon
			(pts
				(arc
					(start 411.174946 -66.799968)
					(mid 425.174918 -80.79994)
					(end 439.17489 -66.799968)
				)
				(arc
					(start 439.17489 -66.799968)
					(mid 425.174918 -52.799996)
					(end 411.174946 -66.799968)
				)
			)
		)
	)
	(zone
		(net "GND")
		(layer "B.Cu")
		(hatch none 0.5)
		(connect_pads
			(clearance 0.5)
		)
		(min_thickness 0.25)
		(fill yes
			(thermal_gap 0.5)
			(thermal_bridge_width 0.5)
			(island_removal_mode 0)
		)
		(polygon
			(pts
				(arc
					(start 460.67345 -249.927872)
					(mid 460.590571 -250.046854)
					(end 460.503524 -250.162822)
				)
				(arc
					(start 460.503524 -250.7488)
					(mid 459.115056 -253.82002)
					(end 455.892154 -254.80645)
				)
				(xy 454.802748 -255.895856)
				(arc
					(start 454.802748 -256.23012)
					(mid 454.732419 -256.985418)
					(end 454.523856 -257.71475)
				)
				(arc
					(start 454.523856 -257.71475)
					(mid 455.57333 -259.109655)
					(end 455.945748 -260.815074)
				)
				(xy 455.945748 -263.031478) (xy 457.138786 -264.224516)
				(arc
					(start 459.010004 -264.224516)
					(mid 460.163041 -264.144457)
					(end 461.292448 -264.390124)
				)
				(arc
					(start 463.733896 -264.390124)
					(mid 463.93357 -263.899691)
					(end 464.194906 -263.439148)
				)
				(xy 464.194906 -263.140952)
				(arc
					(start 463.938366 -262.884412)
					(mid 463.681197 -262.908816)
					(end 463.423 -262.916924)
				)
				(arc
					(start 460.883 -262.916924)
					(mid 456.807838 -259.184766)
					(end 460.168244 -254.798068)
				)
				(xy 460.983076 -253.983236)
				(arc
					(start 460.983076 -251.967492)
					(mid 461.044715 -251.260247)
					(end 461.227678 -250.574302)
				)
				(xy 461.227678 -250.177808) (xy 460.977742 -249.927872)
			)
		)
	)
	(zone
		(net "GND")
		(layer "B.Cu")
		(hatch none 0.5)
		(connect_pads
			(clearance 0.5)
		)
		(min_thickness 0.25)
		(fill yes
			(thermal_gap 0.5)
			(thermal_bridge_width 0.5)
			(island_removal_mode 0)
		)
		(polygon
			(pts
				(xy 73.279 -331.47) (xy 72.771 -331.978) (xy 72.771 -346.456) (xy 73.279 -346.964) (xy 101.219 -346.964)
				(xy 101.916992 -346.266008) (xy 101.916992 -332.421992) (xy 100.965 -331.47)
			)
		)
	)
	(zone
		(net "P5V_B_1")
		(layer "B.Cu")
		(hatch none 0.5)
		(connect_pads
			(clearance 0.5)
		)
		(min_thickness 0.25)
		(fill yes
			(thermal_gap 0.5)
			(thermal_bridge_width 0.5)
			(island_removal_mode 0)
		)
		(polygon
			(pts
				(xy 33.957006 -220.22435) (xy 33.467802 -220.713554) (xy 33.467802 -227.33635) (xy 34.356802 -228.22535)
				(xy 49.24425 -228.22535) (xy 49.7078 -227.7618) (xy 50.822352 -227.7618) (xy 51.628802 -226.95535)
				(xy 51.628802 -221.62135) (xy 50.231802 -220.22435)
			)
		)
	)
	(zone
		(layer "B.Cu")
		(hatch none 0.5)
		(connect_pads
			(clearance 0)
		)
		(min_thickness 0.25)
		(keepout
			(tracks not_allowed)
			(vias allowed)
			(pads allowed)
			(copperpour not_allowed)
			(footprints allowed)
		)
		(placement
			(enabled no)
			(sheetname "")
		)
		(fill
			(thermal_gap 0.5)
			(thermal_bridge_width 0.5)
			(island_removal_mode 0)
		)
		(polygon
			(pts
				(arc
					(start 279.236678 -133.345682)
					(mid 278.688038 -133.894322)
					(end 279.236678 -134.442962)
				)
				(arc
					(start 280.636726 -134.442962)
					(mid 281.185366 -133.894322)
					(end 280.636726 -133.345682)
				)
				(arc
					(start 280.161492 -133.345682)
					(mid 280.171517 -133.403417)
					(end 280.176986 -133.46176)
				)
				(xy 280.178002 -133.46303)
				(arc
					(start 280.178002 -133.702552)
					(mid 280.199753 -133.76359)
					(end 280.255218 -133.79704)
				)
				(arc
					(start 280.255218 -133.79704)
					(mid 281.03044 -133.895369)
					(end 280.25471 -133.989572)
				)
				(xy 280.235152 -133.989572)
				(arc
					(start 280.23185 -133.98627)
					(mid 280.071647 -133.905427)
					(end 279.990804 -133.745224)
				)
				(xy 279.987502 -133.741922)
				(arc
					(start 279.987502 -133.5024)
					(mid 279.981904 -133.423245)
					(end 279.96515 -133.345682)
				)
				(arc
					(start 279.858216 -133.345682)
					(mid 279.874899 -133.402501)
					(end 279.884124 -133.460998)
				)
				(xy 279.885902 -133.46303) (xy 279.885902 -133.741922)
				(arc
					(start 279.8826 -133.745224)
					(mid 279.801757 -133.905427)
					(end 279.641554 -133.98627)
				)
				(xy 279.638252 -133.989572)
				(arc
					(start 279.618694 -133.989572)
					(mid 278.842968 -133.895369)
					(end 279.618186 -133.79704)
				)
				(arc
					(start 279.618186 -133.79704)
					(mid 279.673589 -133.76354)
					(end 279.695402 -133.702552)
				)
				(arc
					(start 279.695402 -133.5024)
					(mid 279.682438 -133.420005)
					(end 279.644602 -133.345682)
				)
			)
		)
	)
	(zone
		(net "GND")
		(layer "B.Cu")
		(hatch none 0.5)
		(connect_pads
			(clearance 0.5)
		)
		(min_thickness 0.25)
		(fill yes
			(thermal_gap 0.5)
			(thermal_bridge_width 0.5)
			(island_removal_mode 0)
		)
		(polygon
			(pts
				(xy 233.910124 -360.22915) (xy 233.497628 -360.641646) (xy 228.47808 -360.641646) (xy 227.719128 -361.400598)
				(arc
					(start 225.36023 -361.400598)
					(mid 223.024339 -362.425362)
					(end 220.5355 -361.866688)
				)
				(arc
					(start 220.5355 -361.866688)
					(mid 218.423076 -362.444226)
					(end 216.315544 -361.849162)
				)
				(arc
					(start 216.315544 -361.849162)
					(mid 214.155805 -362.568023)
					(end 211.946236 -362.02112)
				)
				(xy 211.840318 -362.127292) (xy 204.8891 -362.127292) (xy 203.220828 -363.795564) (xy 203.220828 -367.704878)
				(xy 204.907642 -369.391692) (xy 234.639866 -369.391692)
				(arc
					(start 235.729526 -368.302032)
					(mid 235.991715 -367.323802)
					(end 236.486192 -366.439958)
				)
				(arc
					(start 236.486192 -364.89386)
					(mid 236.051088 -363.265102)
					(end 236.309916 -361.599226)
				)
				(xy 236.309916 -360.97845) (xy 235.560616 -360.22915)
			)
		)
	)
	(zone
		(net "P12V_B_3_VIN_U33")
		(layer "B.Cu")
		(hatch none 0.5)
		(connect_pads
			(clearance 0.5)
		)
		(min_thickness 0.25)
		(fill yes
			(thermal_gap 0.5)
			(thermal_bridge_width 0.5)
			(island_removal_mode 0)
		)
		(polygon
			(pts
				(xy 445.328802 -219.20835) (xy 444.947802 -219.58935) (xy 444.947802 -222.51035) (xy 445.068452 -222.631)
				(xy 450.596 -222.631) (xy 451.104 -223.139) (xy 451.926452 -223.139) (xy 452.186802 -223.39935)
				(xy 452.186802 -224.41535) (xy 452.440802 -224.66935) (xy 453.075802 -224.66935) (xy 453.456802 -225.05035)
				(xy 455.361802 -225.05035) (xy 455.361802 -222.00235) (xy 452.567802 -219.20835)
			)
		)
		(polygon
			(pts
				(xy 451.831202 -222.40875) (xy 451.628002 -222.40875) (xy 451.628002 -222.61195) (xy 451.831202 -222.61195)
			)
		)
		(polygon
			(pts
				(xy 451.221602 -222.40875) (xy 451.018402 -222.40875) (xy 451.018402 -222.61195) (xy 451.221602 -222.61195)
			)
		)
		(polygon
			(pts
				(xy 446.459102 -220.69425) (xy 446.255902 -220.69425) (xy 446.255902 -220.89745) (xy 446.459102 -220.89745)
			)
		)
		(polygon
			(pts
				(xy 445.316102 -220.69425) (xy 445.112902 -220.69425) (xy 445.112902 -220.89745) (xy 445.316102 -220.89745)
			)
		)
	)
	(zone
		(layer "B.Cu")
		(hatch none 0.5)
		(connect_pads
			(clearance 0)
		)
		(min_thickness 0.25)
		(keepout
			(tracks not_allowed)
			(vias allowed)
			(pads allowed)
			(copperpour not_allowed)
			(footprints allowed)
		)
		(placement
			(enabled no)
			(sheetname "")
		)
		(fill
			(thermal_gap 0.5)
			(thermal_bridge_width 0.5)
			(island_removal_mode 0)
		)
		(polygon
			(pts
				(arc
					(start 166.325042 -178.799998)
					(mid 159.325056 -171.800012)
					(end 152.32507 -178.799998)
				)
				(arc
					(start 152.32507 -184.799986)
					(mid 159.325056 -191.799972)
					(end 166.325042 -184.799986)
				)
			)
		)
	)
	(zone
		(net "P12V_B")
		(layer "B.Cu")
		(hatch none 0.5)
		(connect_pads
			(clearance 0.5)
		)
		(min_thickness 0.25)
		(fill yes
			(thermal_gap 0.5)
			(thermal_bridge_width 0.5)
			(island_removal_mode 0)
		)
		(polygon
			(pts
				(xy 440.883802 -218.95435) (xy 440.629802 -219.20835) (xy 440.629802 -222.12935) (xy 440.883802 -222.38335)
				(xy 444.185802 -222.38335) (xy 444.439802 -222.12935) (xy 444.439802 -219.20835) (xy 444.185802 -218.95435)
			)
		)
		(polygon
			(pts
				(xy 443.474602 -221.26575) (xy 443.271402 -221.26575) (xy 443.271402 -221.46895) (xy 443.474602 -221.46895)
			)
		)
		(polygon
			(pts
				(xy 443.385702 -220.69425) (xy 443.182502 -220.69425) (xy 443.182502 -220.89745) (xy 443.385702 -220.89745)
			)
		)
		(polygon
			(pts
				(xy 443.385702 -219.29725) (xy 443.182502 -219.29725) (xy 443.182502 -219.50045) (xy 443.385702 -219.50045)
			)
		)
	)
	(zone
		(net "AGND_P5V_B_2")
		(layer "B.Cu")
		(hatch none 0.5)
		(connect_pads
			(clearance 0.5)
		)
		(min_thickness 0.25)
		(fill yes
			(thermal_gap 0.5)
			(thermal_bridge_width 0.5)
			(island_removal_mode 0)
		)
		(polygon
			(pts
				(xy 45.10786 -118.547642) (xy 44.760896 -118.894606) (xy 44.75226 -118.894606) (xy 44.75226 -119.833644)
				(xy 44.82846 -119.909844) (xy 47.01286 -119.909844) (xy 47.01286 -119.910606) (xy 47.47006 -119.910606)
				(xy 47.76597 -119.614696) (xy 47.76597 -118.701312) (xy 47.6123 -118.547642)
			)
		)
		(polygon
			(pts
				(xy 47.261272 -118.96852) (xy 47.058072 -118.96852) (xy 47.058072 -119.17172) (xy 47.261272 -119.17172)
			)
		)
	)
	(zone
		(layer "B.Cu")
		(hatch none 0.5)
		(connect_pads
			(clearance 0)
		)
		(min_thickness 0.25)
		(keepout
			(tracks not_allowed)
			(vias allowed)
			(pads allowed)
			(copperpour not_allowed)
			(footprints allowed)
		)
		(placement
			(enabled no)
			(sheetname "")
		)
		(fill
			(thermal_gap 0.5)
			(thermal_bridge_width 0.5)
			(island_removal_mode 0)
		)
		(polygon
			(pts
				(arc
					(start 278.23668 -131.545838)
					(mid 277.68804 -132.094478)
					(end 278.23668 -132.643118)
				)
				(arc
					(start 279.636728 -132.643118)
					(mid 280.185368 -132.094478)
					(end 279.636728 -131.545838)
				)
				(xy 279.178004 -131.545838)
				(arc
					(start 279.178004 -131.902708)
					(mid 279.199755 -131.963746)
					(end 279.25522 -131.997196)
				)
				(arc
					(start 279.25522 -131.997196)
					(mid 280.030442 -132.095525)
					(end 279.254712 -132.189728)
				)
				(xy 279.235154 -132.189728)
				(arc
					(start 279.231852 -132.186426)
					(mid 279.071649 -132.105583)
					(end 278.990806 -131.94538)
				)
				(xy 278.987504 -131.942078) (xy 278.987504 -131.545838) (xy 278.885904 -131.545838) (xy 278.885904 -131.942078)
				(arc
					(start 278.882602 -131.94538)
					(mid 278.801759 -132.105583)
					(end 278.641556 -132.186426)
				)
				(xy 278.638254 -132.189728)
				(arc
					(start 278.618696 -132.189728)
					(mid 277.84297 -132.095525)
					(end 278.618188 -131.997196)
				)
				(arc
					(start 278.618188 -131.997196)
					(mid 278.673591 -131.963696)
					(end 278.695404 -131.902708)
				)
				(xy 278.695404 -131.545838)
			)
		)
	)
	(zone
		(layer "B.Cu")
		(hatch none 0.5)
		(connect_pads
			(clearance 0)
		)
		(min_thickness 0.25)
		(keepout
			(tracks not_allowed)
			(vias allowed)
			(pads allowed)
			(copperpour not_allowed)
			(footprints allowed)
		)
		(placement
			(enabled no)
			(sheetname "")
		)
		(fill
			(thermal_gap 0.5)
			(thermal_bridge_width 0.5)
			(island_removal_mode 0)
		)
		(polygon
			(pts
				(arc
					(start 279.236678 -230.945944)
					(mid 278.688038 -231.494584)
					(end 279.236678 -232.043224)
				)
				(arc
					(start 280.636726 -232.043224)
					(mid 281.185366 -231.494584)
					(end 280.636726 -230.945944)
				)
				(arc
					(start 280.141934 -230.945944)
					(mid 280.152755 -231.00795)
					(end 280.15819 -231.070658)
				)
				(xy 280.158952 -231.07142)
				(arc
					(start 280.158952 -231.280716)
					(mid 280.184564 -231.360773)
					(end 280.251916 -231.411018)
				)
				(arc
					(start 280.251916 -231.411018)
					(mid 281.030464 -231.500287)
					(end 280.24963 -231.566974)
				)
				(arc
					(start 280.24963 -231.566974)
					(mid 280.086751 -231.480982)
					(end 280.008584 -231.314244)
				)
				(xy 280.006552 -231.312212)
				(arc
					(start 280.006552 -231.102916)
					(mid 280.001026 -231.02368)
					(end 279.984708 -230.945944)
				)
				(arc
					(start 279.837896 -230.945944)
					(mid 279.856272 -231.007037)
					(end 279.865582 -231.07015)
				)
				(xy 279.866852 -231.07142) (xy 279.866852 -231.312212)
				(arc
					(start 279.86482 -231.314244)
					(mid 279.786575 -231.480907)
					(end 279.623774 -231.566974)
				)
				(arc
					(start 279.623774 -231.566974)
					(mid 278.842913 -231.500288)
					(end 279.621488 -231.411018)
				)
				(arc
					(start 279.621488 -231.411018)
					(mid 279.688773 -231.360725)
					(end 279.714452 -231.280716)
				)
				(arc
					(start 279.714452 -231.102916)
					(mid 279.702455 -231.020987)
					(end 279.667462 -230.945944)
				)
			)
		)
	)
	(zone
		(net "GND")
		(layer "B.Cu")
		(hatch none 0.5)
		(connect_pads
			(clearance 0.5)
		)
		(min_thickness 0.25)
		(fill yes
			(thermal_gap 0.5)
			(thermal_bridge_width 0.5)
			(island_removal_mode 0)
		)
		(polygon
			(pts
				(xy 94.547182 -357.246428) (xy 94.265242 -357.528368) (xy 94.265242 -365.559848) (xy 94.554548 -365.849154)
				(xy 100.44684 -365.849154) (xy 100.8126 -365.483394) (xy 100.8126 -359.1306) (xy 98.928428 -357.246428)
			)
		)
	)
	(zone
		(net "P5V_B_3_LL")
		(layer "B.Cu")
		(hatch none 0.5)
		(connect_pads
			(clearance 0.5)
		)
		(min_thickness 0.25)
		(fill yes
			(thermal_gap 0.5)
			(thermal_bridge_width 0.5)
			(island_removal_mode 0)
		)
		(polygon
			(pts
				(xy 462.066386 -219.234766) (xy 459.044802 -222.25635) (xy 459.044802 -224.92335) (xy 459.216252 -225.0948)
				(xy 464.797902 -225.0948) (xy 465.267802 -224.6249) (xy 465.267802 -220.60535) (xy 465.25688 -220.594428)
				(xy 465.25688 -219.664788) (xy 464.826858 -219.234766)
			)
		)
	)
	(zone
		(net "P5V_B_4")
		(layer "B.Cu")
		(hatch none 0.5)
		(connect_pads
			(clearance 0.5)
		)
		(min_thickness 0.25)
		(fill yes
			(thermal_gap 0.5)
			(thermal_bridge_width 0.5)
			(island_removal_mode 0)
		)
		(polygon
			(pts
				(xy 450.66839 -109.907578) (xy 450.179186 -110.396782) (xy 450.179186 -117.019578) (xy 451.068186 -117.908578)
				(xy 465.769198 -117.908578) (xy 466.183472 -117.494304) (xy 466.1916 -117.494304) (xy 466.261704 -117.4242)
				(xy 466.791802 -117.4242) (xy 467.6648 -116.551202) (xy 467.6648 -110.5154) (xy 467.056978 -109.907578)
			)
		)
	)
	(zone
		(layer "B.Cu")
		(hatch none 0.5)
		(connect_pads
			(clearance 0)
		)
		(min_thickness 0.25)
		(keepout
			(tracks not_allowed)
			(vias allowed)
			(pads allowed)
			(copperpour not_allowed)
			(footprints allowed)
		)
		(placement
			(enabled no)
			(sheetname "")
		)
		(fill
			(thermal_gap 0.5)
			(thermal_bridge_width 0.5)
			(island_removal_mode 0)
		)
		(polygon
			(pts
				(arc
					(start 279.236678 -176.945798)
					(mid 278.688038 -177.494438)
					(end 279.236678 -178.043078)
				)
				(arc
					(start 280.636726 -178.043078)
					(mid 281.185366 -177.494438)
					(end 280.636726 -176.945798)
				)
				(arc
					(start 280.174954 -176.945798)
					(mid 280.162991 -176.98514)
					(end 280.158952 -177.026062)
				)
				(arc
					(start 280.158952 -177.305462)
					(mid 280.184926 -177.377461)
					(end 280.2509 -177.416206)
				)
				(arc
					(start 280.2509 -177.416206)
					(mid 281.030452 -177.495987)
					(end 280.250392 -177.570638)
				)
				(xy 280.240232 -177.570638)
				(arc
					(start 280.237946 -177.568606)
					(mid 280.08413 -177.49306)
					(end 280.008584 -177.339244)
				)
				(xy 280.006552 -177.336958) (xy 280.006552 -176.994566)
				(arc
					(start 280.008076 -176.993042)
					(mid 280.011101 -176.969293)
					(end 280.015696 -176.945798)
				)
				(arc
					(start 279.873202 -176.945798)
					(mid 279.868417 -176.985802)
					(end 279.866852 -177.026062)
				)
				(xy 279.866852 -177.336958)
				(arc
					(start 279.86482 -177.339244)
					(mid 279.789274 -177.49306)
					(end 279.635458 -177.568606)
				)
				(xy 279.633172 -177.570638)
				(arc
					(start 279.623012 -177.570638)
					(mid 278.842952 -177.495987)
					(end 279.622504 -177.416206)
				)
				(arc
					(start 279.622504 -177.416206)
					(mid 279.688409 -177.377403)
					(end 279.714452 -177.305462)
				)
				(xy 279.714452 -176.994566) (xy 279.715214 -176.993804) (xy 279.719278 -176.945798)
			)
		)
	)
	(zone
		(layer "B.Cu")
		(hatch none 0.5)
		(connect_pads
			(clearance 0)
		)
		(min_thickness 0.25)
		(keepout
			(tracks not_allowed)
			(vias allowed)
			(pads allowed)
			(copperpour not_allowed)
			(footprints allowed)
		)
		(placement
			(enabled no)
			(sheetname "")
		)
		(fill
			(thermal_gap 0.5)
			(thermal_bridge_width 0.5)
			(island_removal_mode 0)
		)
		(polygon
			(pts
				(arc
					(start 279.236678 -209.345784)
					(mid 278.688038 -209.894424)
					(end 279.236678 -210.443064)
				)
				(arc
					(start 280.636726 -210.443064)
					(mid 281.185366 -209.894424)
					(end 280.636726 -209.345784)
				)
				(arc
					(start 280.141934 -209.345784)
					(mid 280.152755 -209.40779)
					(end 280.15819 -209.470498)
				)
				(xy 280.158952 -209.47126)
				(arc
					(start 280.158952 -209.680556)
					(mid 280.184564 -209.760613)
					(end 280.251916 -209.810858)
				)
				(arc
					(start 280.251916 -209.810858)
					(mid 281.030464 -209.900127)
					(end 280.24963 -209.966814)
				)
				(arc
					(start 280.24963 -209.966814)
					(mid 280.086751 -209.880822)
					(end 280.008584 -209.714084)
				)
				(xy 280.006552 -209.712052)
				(arc
					(start 280.006552 -209.502756)
					(mid 280.001026 -209.42352)
					(end 279.984708 -209.345784)
				)
				(arc
					(start 279.837896 -209.345784)
					(mid 279.856272 -209.406877)
					(end 279.865582 -209.46999)
				)
				(xy 279.866852 -209.47126) (xy 279.866852 -209.712052)
				(arc
					(start 279.86482 -209.714084)
					(mid 279.786575 -209.880747)
					(end 279.623774 -209.966814)
				)
				(arc
					(start 279.623774 -209.966814)
					(mid 278.842913 -209.900128)
					(end 279.621488 -209.810858)
				)
				(arc
					(start 279.621488 -209.810858)
					(mid 279.688773 -209.760565)
					(end 279.714452 -209.680556)
				)
				(arc
					(start 279.714452 -209.502756)
					(mid 279.702455 -209.420827)
					(end 279.667462 -209.345784)
				)
			)
		)
	)
	(zone
		(net "GND")
		(layer "B.Cu")
		(hatch none 0.5)
		(connect_pads
			(clearance 0.5)
		)
		(min_thickness 0.25)
		(fill yes
			(thermal_gap 0.5)
			(thermal_bridge_width 0.5)
			(island_removal_mode 0)
		)
		(polygon
			(pts
				(xy 64.040258 -103.622856) (xy 63.39586 -104.267254) (xy 63.39586 -106.442256) (xy 63.87846 -106.924856)
				(xy 67.96786 -106.924856) (xy 68.22186 -106.670856) (xy 68.22186 -104.299258) (xy 67.545458 -103.622856)
			)
		)
	)
	(zone
		(net "GND")
		(layer "B.Cu")
		(hatch none 0.5)
		(connect_pads
			(clearance 0.5)
		)
		(min_thickness 0.25)
		(fill yes
			(thermal_gap 0.5)
			(thermal_bridge_width 0.5)
			(island_removal_mode 0)
		)
		(polygon
			(pts
				(xy 474.56725 -231.83215) (xy 474.234002 -232.165398) (xy 474.234002 -235.397802) (xy 474.57995 -235.74375)
				(xy 478.58045 -235.74375) (xy 478.907602 -235.416598) (xy 478.907602 -232.222802) (xy 478.51695 -231.83215)
			)
		)
	)
	(zone
		(layer "B.Cu")
		(hatch none 0.5)
		(connect_pads
			(clearance 0)
		)
		(min_thickness 0.25)
		(keepout
			(tracks not_allowed)
			(vias allowed)
			(pads allowed)
			(copperpour not_allowed)
			(footprints allowed)
		)
		(placement
			(enabled no)
			(sheetname "")
		)
		(fill
			(thermal_gap 0.5)
			(thermal_bridge_width 0.5)
			(island_removal_mode 0)
		)
		(polygon
			(pts
				(arc
					(start 337.674966 -178.799998)
					(mid 330.67498 -171.800012)
					(end 323.674994 -178.799998)
				)
				(arc
					(start 323.674994 -184.799986)
					(mid 330.67498 -191.799972)
					(end 337.674966 -184.799986)
				)
			)
		)
	)
	(zone
		(net "GND")
		(layer "B.Cu")
		(hatch none 0.5)
		(connect_pads
			(clearance 0.5)
		)
		(min_thickness 0.25)
		(fill yes
			(thermal_gap 0.5)
			(thermal_bridge_width 0.5)
			(island_removal_mode 0)
		)
		(polygon
			(pts
				(xy 44.940474 -110.64875) (xy 44.761658 -110.827566) (xy 44.761658 -116.532406) (xy 45.029882 -116.80063)
				(xy 45.029882 -117.648228) (xy 45.51426 -118.132606) (xy 46.368462 -118.132606) (xy 46.37786 -118.142004)
				(xy 48.063658 -116.456206) (xy 48.063658 -110.83036) (xy 47.882048 -110.64875)
			)
		)
	)
	(zone
		(layer "B.Cu")
		(hatch none 0.5)
		(connect_pads
			(clearance 0)
		)
		(min_thickness 0.25)
		(keepout
			(tracks not_allowed)
			(vias allowed)
			(pads allowed)
			(copperpour not_allowed)
			(footprints allowed)
		)
		(placement
			(enabled no)
			(sheetname "")
		)
		(fill
			(thermal_gap 0.5)
			(thermal_bridge_width 0.5)
			(island_removal_mode 0)
		)
		(polygon
			(pts
				(arc
					(start 278.23668 -203.945744)
					(mid 277.68804 -204.494384)
					(end 278.23668 -205.043024)
				)
				(arc
					(start 279.636728 -205.043024)
					(mid 280.185368 -204.494384)
					(end 279.636728 -203.945744)
				)
				(xy 279.160224 -203.945744) (xy 279.158954 -203.965302)
				(arc
					(start 279.158954 -204.346302)
					(mid 279.180008 -204.39713)
					(end 279.230836 -204.418184)
				)
				(arc
					(start 279.250394 -204.418184)
					(mid 280.030505 -204.494384)
					(end 279.250394 -204.570584)
				)
				(xy 279.19934 -204.570584)
				(arc
					(start 279.196546 -204.568044)
					(mid 279.072177 -204.504961)
					(end 279.009094 -204.380592)
				)
				(xy 279.006554 -204.377798) (xy 279.006554 -203.945744) (xy 278.867362 -203.945744) (xy 278.866854 -203.965302)
				(xy 278.866854 -204.377798)
				(arc
					(start 278.864314 -204.380592)
					(mid 278.801231 -204.504961)
					(end 278.676862 -204.568044)
				)
				(xy 278.674068 -204.570584)
				(arc
					(start 278.623014 -204.570584)
					(mid 277.842903 -204.494384)
					(end 278.623014 -204.418184)
				)
				(arc
					(start 278.642572 -204.418184)
					(mid 278.6934 -204.39713)
					(end 278.714454 -204.346302)
				)
				(xy 278.714454 -203.945744)
			)
		)
	)
	(zone
		(net "P12V_B")
		(layer "B.Cu")
		(hatch none 0.5)
		(connect_pads
			(clearance 0.5)
		)
		(min_thickness 0.25)
		(fill yes
			(thermal_gap 0.5)
			(thermal_bridge_width 0.5)
			(island_removal_mode 0)
		)
		(polygon
			(pts
				(xy 421.985186 -108.637578) (xy 421.731186 -108.891578) (xy 421.731186 -111.812578) (xy 421.985186 -112.066578)
				(xy 425.287186 -112.066578) (xy 425.541186 -111.812578) (xy 425.541186 -108.891578) (xy 425.287186 -108.637578)
			)
		)
		(polygon
			(pts
				(xy 424.575986 -110.948978) (xy 424.372786 -110.948978) (xy 424.372786 -111.152178) (xy 424.575986 -111.152178)
			)
		)
		(polygon
			(pts
				(xy 424.487086 -110.377478) (xy 424.283886 -110.377478) (xy 424.283886 -110.580678) (xy 424.487086 -110.580678)
			)
		)
		(polygon
			(pts
				(xy 424.487086 -108.980478) (xy 424.283886 -108.980478) (xy 424.283886 -109.183678) (xy 424.487086 -109.183678)
			)
		)
	)
	(zone
		(net "GND")
		(layer "B.Cu")
		(hatch none 0.5)
		(connect_pads
			(clearance 0.5)
		)
		(min_thickness 0.25)
		(fill yes
			(thermal_gap 0.5)
			(thermal_bridge_width 0.5)
			(island_removal_mode 0)
		)
		(polygon
			(pts
				(xy 34.513266 -112.141) (xy 34.31286 -112.341406) (xy 34.31286 -114.119406) (xy 36.85286 -116.659406)
				(xy 39.90086 -116.659406) (xy 40.02786 -116.532406) (xy 40.02786 -115.135406) (xy 40.53586 -114.627152)
				(xy 40.53586 -113.484406) (xy 41.04386 -112.976406) (xy 41.04386 -112.341406) (xy 40.91686 -112.214406)
				(xy 40.15486 -112.214406) (xy 40.081454 -112.141)
			)
		)
		(polygon
			(pts
				(xy 39.74846 -114.576606) (xy 39.54526 -114.576606) (xy 39.54526 -114.779806) (xy 39.74846 -114.779806)
			)
		)
		(polygon
			(pts
				(xy 39.74846 -113.713006) (xy 39.54526 -113.713006) (xy 39.54526 -113.916206) (xy 39.74846 -113.916206)
			)
		)
		(polygon
			(pts
				(xy 40.45966 -112.747806) (xy 40.25646 -112.747806) (xy 40.25646 -112.951006) (xy 40.45966 -112.951006)
			)
		)
	)
	(zone
		(net "GND")
		(layer "B.Cu")
		(hatch none 0.5)
		(connect_pads
			(clearance 0.5)
		)
		(min_thickness 0.25)
		(fill yes
			(thermal_gap 0.5)
			(thermal_bridge_width 0.5)
			(island_removal_mode 0)
		)
		(polygon
			(pts
				(xy 63.856108 -120.596406) (xy 63.52286 -120.929654) (xy 63.52286 -124.162058) (xy 63.868808 -124.508006)
				(xy 67.869308 -124.508006) (xy 68.19646 -124.180854) (xy 68.19646 -120.987058) (xy 67.805808 -120.596406)
			)
		)
	)
	(zone
		(layer "B.Cu")
		(hatch none 0.5)
		(connect_pads
			(clearance 0)
		)
		(min_thickness 0.25)
		(keepout
			(tracks not_allowed)
			(vias allowed)
			(pads allowed)
			(copperpour not_allowed)
			(footprints allowed)
		)
		(placement
			(enabled no)
			(sheetname "")
		)
		(fill
			(thermal_gap 0.5)
			(thermal_bridge_width 0.5)
			(island_removal_mode 0)
		)
		(polygon
			(pts
				(xy 160.6042 -358.2162) (xy 160.6042 -329.1078) (xy 166.387018 -329.1078) (xy 166.387018 -358.2162)
			)
		)
	)
	(zone
		(layer "B.Cu")
		(hatch none 0.5)
		(connect_pads
			(clearance 0)
		)
		(min_thickness 0.25)
		(keepout
			(tracks not_allowed)
			(vias allowed)
			(pads allowed)
			(copperpour not_allowed)
			(footprints allowed)
		)
		(placement
			(enabled no)
			(sheetname "")
		)
		(fill
			(thermal_gap 0.5)
			(thermal_bridge_width 0.5)
			(island_removal_mode 0)
		)
		(polygon
			(pts
				(arc
					(start 279.236678 -227.345748)
					(mid 278.688038 -227.894388)
					(end 279.236678 -228.443028)
				)
				(arc
					(start 279.725628 -228.443028)
					(mid 279.718916 -228.398117)
					(end 279.715214 -228.352858)
				)
				(xy 279.714452 -228.352096)
				(arc
					(start 279.714452 -228.092)
					(mid 279.688662 -228.017185)
					(end 279.62225 -227.974144)
				)
				(arc
					(start 279.62225 -227.974144)
					(mid 278.842948 -227.89257)
					(end 279.623012 -227.818188)
				)
				(xy 279.624536 -227.818188)
				(arc
					(start 279.626568 -227.82022)
					(mid 279.786674 -227.898366)
					(end 279.86482 -228.058472)
				)
				(xy 279.866852 -228.060504)
				(arc
					(start 279.866852 -228.3206)
					(mid 279.87041 -228.382226)
					(end 279.881076 -228.443028)
				)
				(arc
					(start 280.02611 -228.443028)
					(mid 280.014347 -228.398859)
					(end 280.007822 -228.35362)
				)
				(xy 280.006552 -228.352096) (xy 280.006552 -228.060504)
				(arc
					(start 280.008584 -228.058472)
					(mid 280.08673 -227.898366)
					(end 280.246836 -227.82022)
				)
				(xy 280.248868 -227.818188)
				(arc
					(start 280.250392 -227.818188)
					(mid 281.030499 -227.89257)
					(end 280.251154 -227.974144)
				)
				(arc
					(start 280.251154 -227.974144)
					(mid 280.184735 -228.017178)
					(end 280.158952 -228.092)
				)
				(arc
					(start 280.158952 -228.3206)
					(mid 280.167552 -228.384102)
					(end 280.192734 -228.443028)
				)
				(arc
					(start 280.636726 -228.443028)
					(mid 281.185366 -227.894388)
					(end 280.636726 -227.345748)
				)
			)
		)
	)
	(zone
		(layer "B.Cu")
		(hatch none 0.5)
		(connect_pads
			(clearance 0)
		)
		(min_thickness 0.25)
		(keepout
			(tracks not_allowed)
			(vias allowed)
			(pads allowed)
			(copperpour not_allowed)
			(footprints allowed)
		)
		(placement
			(enabled no)
			(sheetname "")
		)
		(fill
			(thermal_gap 0.5)
			(thermal_bridge_width 0.5)
			(island_removal_mode 0)
		)
		(polygon
			(pts
				(arc
					(start 217.748612 -77.600302)
					(mid 217.200099 -77.051408)
					(end 216.651332 -77.600048)
				)
				(arc
					(start 216.651332 -78.999842)
					(mid 217.199972 -79.548482)
					(end 217.748612 -78.999842)
				)
				(arc
					(start 217.748612 -78.580234)
					(mid 217.685537 -78.551117)
					(end 217.616786 -78.541118)
				)
				(arc
					(start 217.388186 -78.541118)
					(mid 217.3283 -78.562899)
					(end 217.296492 -78.61808)
				)
				(arc
					(start 217.296492 -78.61808)
					(mid 217.199826 -79.393554)
					(end 217.104722 -78.617826)
				)
				(xy 217.104722 -78.594712)
				(arc
					(start 217.108024 -78.59141)
					(mid 217.187797 -78.433693)
					(end 217.345514 -78.35392)
				)
				(xy 217.348816 -78.350618) (xy 217.656156 -78.350618)
				(arc
					(start 217.658188 -78.35265)
					(mid 217.703896 -78.359503)
					(end 217.748612 -78.371192)
				)
				(arc
					(start 217.748612 -78.265528)
					(mid 217.683215 -78.253147)
					(end 217.616786 -78.249018)
				)
				(xy 217.348816 -78.249018)
				(arc
					(start 217.345514 -78.245716)
					(mid 217.187797 -78.165943)
					(end 217.108024 -78.008226)
				)
				(xy 217.104722 -78.004924)
				(arc
					(start 217.104722 -77.982064)
					(mid 217.199702 -77.206275)
					(end 217.296746 -77.98181)
				)
				(arc
					(start 217.296746 -77.98181)
					(mid 217.328538 -78.036741)
					(end 217.388186 -78.058518)
				)
				(xy 217.656156 -78.058518)
				(arc
					(start 217.657426 -78.059534)
					(mid 217.703196 -78.063679)
					(end 217.748612 -78.07071)
				)
			)
		)
	)
	(zone
		(layer "B.Cu")
		(hatch none 0.5)
		(connect_pads
			(clearance 0)
		)
		(min_thickness 0.25)
		(keepout
			(tracks not_allowed)
			(vias allowed)
			(pads allowed)
			(copperpour not_allowed)
			(footprints allowed)
		)
		(placement
			(enabled no)
			(sheetname "")
		)
		(fill
			(thermal_gap 0.5)
			(thermal_bridge_width 0.5)
			(island_removal_mode 0)
		)
		(polygon
			(pts
				(arc
					(start 446.0875 -244.312694)
					(mid 445.60236 -243.827554)
					(end 445.11722 -244.312694)
				)
				(xy 445.11722 -244.663722)
				(arc
					(start 445.472058 -244.663722)
					(mid 445.510314 -244.647876)
					(end 445.52616 -244.60962)
				)
				(arc
					(start 445.52616 -244.568218)
					(mid 445.60236 -244.04605)
					(end 445.67856 -244.568218)
				)
				(xy 445.67856 -244.641116)
				(arc
					(start 445.675766 -244.644164)
					(mid 445.618158 -244.75572)
					(end 445.506602 -244.813328)
				)
				(xy 445.503554 -244.816122) (xy 445.11722 -244.816122) (xy 445.11722 -244.955822) (xy 445.497458 -244.955822)
				(arc
					(start 445.500252 -244.958616)
					(mid 445.616284 -245.018098)
					(end 445.675766 -245.13413)
				)
				(xy 445.67856 -245.136924)
				(arc
					(start 445.67856 -245.20017)
					(mid 445.60236 -245.722338)
					(end 445.52616 -245.20017)
				)
				(arc
					(start 445.52616 -245.16842)
					(mid 445.508528 -245.125854)
					(end 445.465962 -245.108222)
				)
				(xy 445.11722 -245.108222)
				(arc
					(start 445.11722 -245.45544)
					(mid 445.602233 -245.940834)
					(end 446.0875 -245.455694)
				)
			)
		)
	)
	(zone
		(net "P5V_B_4_LL_R")
		(layer "B.Cu")
		(hatch none 0.5)
		(connect_pads
			(clearance 0.5)
		)
		(min_thickness 0.25)
		(fill yes
			(thermal_gap 0.5)
			(thermal_bridge_width 0.5)
			(island_removal_mode 0)
		)
		(polygon
			(pts
				(xy 447.366136 -118.918228) (xy 447.131186 -119.153178) (xy 447.131186 -119.852186) (xy 448.114674 -120.835674)
				(xy 448.114674 -122.067066) (xy 448.401186 -122.353578) (xy 449.137024 -122.353578) (xy 449.502784 -121.987818)
				(xy 449.502784 -119.096028) (xy 449.324984 -118.918228)
			)
		)
		(polygon
			(pts
				(xy 448.882008 -120.798082) (xy 448.678808 -120.798082) (xy 448.678808 -121.001282) (xy 448.882008 -121.001282)
			)
		)
		(polygon
			(pts
				(xy 448.882008 -120.188482) (xy 448.678808 -120.188482) (xy 448.678808 -120.391682) (xy 448.882008 -120.391682)
			)
		)
		(polygon
			(pts
				(xy 448.674998 -119.818404) (xy 448.471798 -119.818404) (xy 448.471798 -120.021604) (xy 448.674998 -120.021604)
			)
		)
		(polygon
			(pts
				(xy 448.013328 -119.394224) (xy 447.810128 -119.394224) (xy 447.810128 -119.597424) (xy 448.013328 -119.597424)
			)
		)
		(polygon
			(pts
				(xy 447.454528 -119.394224) (xy 447.251328 -119.394224) (xy 447.251328 -119.597424) (xy 447.454528 -119.597424)
			)
		)
	)
	(zone
		(net "GND")
		(layer "B.Cu")
		(hatch none 0.5)
		(connect_pads
			(clearance 0.5)
		)
		(min_thickness 0.25)
		(fill yes
			(thermal_gap 0.5)
			(thermal_bridge_width 0.5)
			(island_removal_mode 0)
		)
		(polygon
			(pts
				(xy 343.810336 -181.129686) (xy 351.69602 -176.008792) (xy 353.031044 -174.673768)
				(arc
					(start 353.031044 -164.668454)
					(mid 352.620668 -162.587259)
					(end 353.212908 -160.550352)
				)
				(arc
					(start 353.212908 -156.868622)
					(mid 353.138891 -156.424558)
					(end 353.114102 -155.97505)
				)
				(arc
					(start 353.114102 -153.43505)
					(mid 353.121167 -153.194987)
					(end 353.142296 -152.955752)
				)
				(xy 353.142296 -151.87676)
				(arc
					(start 350.871282 -149.605746)
					(mid 347.445269 -145.253387)
					(end 351.498154 -141.478)
				)
				(xy 351.971102 -141.005052) (xy 351.971102 -139.498832) (xy 351.497138 -139.024868) (xy 350.40443 -139.024868)
				(xy 337.43646 -158.993586)
				(arc
					(start 337.43646 -162.26155)
					(mid 337.048083 -165.380633)
					(end 334.561434 -167.303196)
				)
				(xy 334.124554 -167.740076) (xy 334.124554 -168.228518)
				(arc
					(start 334.619346 -168.72331)
					(mid 339.613109 -172.700202)
					(end 341.496142 -178.799998)
				)
				(xy 341.496142 -180.063394) (xy 342.562434 -181.129686)
			)
		)
	)
	(zone
		(net "GND")
		(layer "B.Cu")
		(hatch none 0.5)
		(connect_pads
			(clearance 0.5)
		)
		(min_thickness 0.25)
		(fill yes
			(thermal_gap 0.5)
			(thermal_bridge_width 0.5)
			(island_removal_mode 0)
		)
		(polygon
			(pts
				(xy 105.383076 -135.621522) (xy 101.107494 -134.713726) (xy 100.348796 -134.713726) (xy 99.674426 -135.388096)
				(arc
					(start 99.674426 -135.40105)
					(mid 99.281414 -137.144937)
					(end 98.178366 -138.551666)
				)
				(xy 98.178366 -139.592304) (xy 98.451924 -139.865862) (xy 100.026216 -140.20038)
				(arc
					(start 103.52151 -140.20038)
					(mid 104.419397 -138.842033)
					(end 105.776014 -137.941558)
				)
				(xy 106.245406 -137.472166) (xy 106.245406 -136.483852)
			)
		)
	)
	(zone
		(layer "B.Cu")
		(hatch none 0.5)
		(connect_pads
			(clearance 0)
		)
		(min_thickness 0.25)
		(keepout
			(tracks not_allowed)
			(vias allowed)
			(pads allowed)
			(copperpour not_allowed)
			(footprints allowed)
		)
		(placement
			(enabled no)
			(sheetname "")
		)
		(fill
			(thermal_gap 0.5)
			(thermal_bridge_width 0.5)
			(island_removal_mode 0)
		)
		(polygon
			(pts
				(arc
					(start 166.325042 -293.800022)
					(mid 159.325056 -286.800036)
					(end 152.32507 -293.800022)
				)
				(arc
					(start 152.32507 -299.80001)
					(mid 159.325056 -306.799996)
					(end 166.325042 -299.80001)
				)
			)
		)
	)
	(zone
		(net "AGND_P5V_B_3")
		(layer "B.Cu")
		(hatch none 0.5)
		(connect_pads
			(clearance 0.5)
		)
		(min_thickness 0.25)
		(fill yes
			(thermal_gap 0.5)
			(thermal_bridge_width 0.5)
			(island_removal_mode 0)
		)
		(polygon
			(pts
				(xy 455.869802 -229.732586) (xy 455.522838 -230.07955) (xy 455.514202 -230.07955) (xy 455.514202 -231.018588)
				(xy 455.590402 -231.094788) (xy 457.774802 -231.094788) (xy 457.774802 -231.09555) (xy 458.232002 -231.09555)
				(xy 458.527912 -230.79964) (xy 458.527912 -229.886256) (xy 458.374242 -229.732586)
			)
		)
		(polygon
			(pts
				(xy 458.023214 -230.153464) (xy 457.820014 -230.153464) (xy 457.820014 -230.356664) (xy 458.023214 -230.356664)
			)
		)
	)
	(zone
		(net "GND")
		(layer "B.Cu")
		(hatch none 0.5)
		(connect_pads
			(clearance 0.5)
		)
		(min_thickness 0.25)
		(fill yes
			(thermal_gap 0.5)
			(thermal_bridge_width 0.5)
			(island_removal_mode 0)
		)
		(polygon
			(pts
				(xy 318.455294 -188.221112) (xy 317.485014 -189.71514) (xy 317.485014 -190.737998) (xy 318.082422 -191.335406)
				(xy 318.25692 -191.335406) (xy 320.082672 -190.947294) (xy 320.408808 -190.621158) (xy 320.408808 -188.72073)
				(xy 319.90919 -188.221112)
			)
		)
	)
	(zone
		(net "GND")
		(layer "B.Cu")
		(hatch none 0.5)
		(connect_pads
			(clearance 0.5)
		)
		(min_thickness 0.25)
		(fill yes
			(thermal_gap 0.5)
			(thermal_bridge_width 0.5)
			(island_removal_mode 0)
		)
		(polygon
			(pts
				(xy 38.652958 -126.403608) (xy 48.682656 -127.937514)
				(arc
					(start 52.926996 -127.937514)
					(mid 53.898631 -127.400763)
					(end 54.978808 -127.145034)
				)
				(xy 55.297324 -126.826518) (xy 55.297324 -125.718824) (xy 55.063898 -125.485398)
				(arc
					(start 53.321966 -125.485398)
					(mid 49.809677 -126.210181)
					(end 47.07636 -123.8885)
				)
				(arc
					(start 47.07636 -123.8885)
					(mid 46.810157 -123.817876)
					(end 46.54931 -123.729496)
				)
				(arc
					(start 46.54931 -123.729496)
					(mid 45.972523 -123.76564)
					(end 45.396404 -123.720098)
				)
				(xy 43.250104 -123.720098) (xy 42.655236 -123.12523) (xy 41.524936 -123.12523) (xy 41.524936 -122.727212)
				(xy 40.469312 -121.671588) (xy 40.181276 -121.671588)
				(arc
					(start 40.179752 -121.670064)
					(mid 40.073363 -121.674253)
					(end 39.9669 -121.675652)
				)
				(xy 39.053008 -121.675652) (xy 37.993066 -122.735594) (xy 37.993066 -125.743716)
			)
		)
	)
	(zone
		(net "GND")
		(layer "B.Cu")
		(hatch none 0.5)
		(connect_pads
			(clearance 0.5)
		)
		(min_thickness 0.25)
		(fill yes
			(thermal_gap 0.5)
			(thermal_bridge_width 0.5)
			(island_removal_mode 0)
		)
		(polygon
			(pts
				(xy 44.008802 -228.60635) (xy 43.754802 -228.86035) (xy 43.754802 -230.63835) (xy 44.135802 -231.01935)
				(xy 49.342802 -231.01935) (xy 49.596802 -230.76535) (xy 49.596802 -228.73335) (xy 49.469802 -228.60635)
			)
		)
	)
	(zone
		(layer "B.Cu")
		(hatch none 0.5)
		(connect_pads
			(clearance 0)
		)
		(min_thickness 0.25)
		(keepout
			(tracks not_allowed)
			(vias allowed)
			(pads allowed)
			(copperpour not_allowed)
			(footprints allowed)
		)
		(placement
			(enabled no)
			(sheetname "")
		)
		(fill
			(thermal_gap 0.5)
			(thermal_bridge_width 0.5)
			(island_removal_mode 0)
		)
		(polygon
			(pts
				(arc
					(start 382.97739 -244.302534)
					(mid 382.49225 -243.817394)
					(end 382.00711 -244.302534)
				)
				(xy 382.00711 -244.651784)
				(arc
					(start 382.284224 -244.651784)
					(mid 382.363525 -244.625328)
					(end 382.41097 -244.556534)
				)
				(arc
					(start 382.41097 -244.556534)
					(mid 382.495852 -244.035951)
					(end 382.565656 -244.55882)
				)
				(arc
					(start 382.565656 -244.55882)
					(mid 382.487186 -244.718756)
					(end 382.328928 -244.800628)
				)
				(xy 382.325372 -244.804184) (xy 382.00711 -244.804184) (xy 382.00711 -244.943884) (xy 382.31572 -244.943884)
				(arc
					(start 382.317752 -244.945916)
					(mid 382.483255 -245.025269)
					(end 382.565656 -245.189248)
				)
				(arc
					(start 382.565656 -245.189248)
					(mid 382.495853 -245.712168)
					(end 382.41097 -245.191534)
				)
				(arc
					(start 382.41097 -245.191534)
					(mid 382.36347 -245.122813)
					(end 382.284224 -245.096284)
				)
				(xy 382.00711 -245.096284)
				(arc
					(start 382.00711 -245.44528)
					(mid 382.492123 -245.930674)
					(end 382.97739 -245.445534)
				)
			)
		)
	)
	(zone
		(layer "B.Cu")
		(hatch none 0.5)
		(connect_pads
			(clearance 0)
		)
		(min_thickness 0.25)
		(keepout
			(tracks not_allowed)
			(vias allowed)
			(pads allowed)
			(copperpour not_allowed)
			(footprints allowed)
		)
		(placement
			(enabled no)
			(sheetname "")
		)
		(fill
			(thermal_gap 0.5)
			(thermal_bridge_width 0.5)
			(island_removal_mode 0)
		)
		(polygon
			(pts
				(arc
					(start 223.148652 -76.399898)
					(mid 222.600012 -75.851258)
					(end 222.051372 -76.399898)
				)
				(arc
					(start 222.051372 -77.799692)
					(mid 222.599885 -78.348586)
					(end 223.148652 -77.799946)
				)
				(arc
					(start 223.148652 -77.38364)
					(mid 223.086063 -77.352088)
					(end 223.016826 -77.341222)
				)
				(arc
					(start 222.788226 -77.341222)
					(mid 222.72834 -77.363003)
					(end 222.696532 -77.418184)
				)
				(arc
					(start 222.696532 -77.418184)
					(mid 222.599866 -78.193658)
					(end 222.504762 -77.41793)
				)
				(xy 222.504762 -77.394816)
				(arc
					(start 222.508064 -77.391514)
					(mid 222.587837 -77.233797)
					(end 222.745554 -77.154024)
				)
				(xy 222.748856 -77.150722) (xy 223.056196 -77.150722)
				(arc
					(start 223.058228 -77.152754)
					(mid 223.103975 -77.1599)
					(end 223.148652 -77.172058)
				)
				(arc
					(start 223.148652 -77.06614)
					(mid 223.083287 -77.053384)
					(end 223.016826 -77.049122)
				)
				(xy 222.748856 -77.049122)
				(arc
					(start 222.745554 -77.04582)
					(mid 222.587837 -76.966047)
					(end 222.508064 -76.80833)
				)
				(xy 222.504762 -76.805028)
				(arc
					(start 222.504762 -76.781914)
					(mid 222.599866 -76.006125)
					(end 222.696532 -76.78166)
				)
				(arc
					(start 222.696532 -76.78166)
					(mid 222.7284 -76.836769)
					(end 222.788226 -76.858622)
				)
				(xy 223.056196 -76.858622)
				(arc
					(start 223.057466 -76.859892)
					(mid 223.103241 -76.863995)
					(end 223.148652 -76.871068)
				)
			)
		)
	)
	(zone
		(layer "B.Cu")
		(hatch none 0.5)
		(connect_pads
			(clearance 0)
		)
		(min_thickness 0.25)
		(keepout
			(tracks not_allowed)
			(vias allowed)
			(pads allowed)
			(copperpour not_allowed)
			(footprints allowed)
		)
		(placement
			(enabled no)
			(sheetname "")
		)
		(fill
			(thermal_gap 0.5)
			(thermal_bridge_width 0.5)
			(island_removal_mode 0)
		)
		(polygon
			(pts
				(arc
					(start 113.82502 -181.799992)
					(mid 127.824992 -195.799964)
					(end 141.824964 -181.799992)
				)
				(arc
					(start 141.824964 -181.799992)
					(mid 127.824992 -167.80002)
					(end 113.82502 -181.799992)
				)
			)
		)
	)
	(zone
		(net "P12V_B")
		(layer "B.Cu")
		(hatch none 0.5)
		(connect_pads
			(clearance 0.5)
		)
		(min_thickness 0.25)
		(fill yes
			(thermal_gap 0.5)
			(thermal_bridge_width 0.5)
			(island_removal_mode 0)
		)
		(polygon
			(pts
				(xy 5.273802 -218.95435) (xy 5.019802 -219.20835) (xy 5.019802 -222.12935) (xy 5.273802 -222.38335)
				(xy 8.575802 -222.38335) (xy 8.829802 -222.12935) (xy 8.829802 -219.20835) (xy 8.575802 -218.95435)
			)
		)
		(polygon
			(pts
				(xy 7.864602 -221.26575) (xy 7.661402 -221.26575) (xy 7.661402 -221.46895) (xy 7.864602 -221.46895)
			)
		)
		(polygon
			(pts
				(xy 7.775702 -220.69425) (xy 7.572502 -220.69425) (xy 7.572502 -220.89745) (xy 7.775702 -220.89745)
			)
		)
		(polygon
			(pts
				(xy 7.775702 -219.29725) (xy 7.572502 -219.29725) (xy 7.572502 -219.50045) (xy 7.775702 -219.50045)
			)
		)
	)
	(zone
		(net "AGND_P5V_B_1")
		(layer "B.Cu")
		(hatch none 0.5)
		(connect_pads
			(clearance 0.5)
		)
		(min_thickness 0.25)
		(fill yes
			(thermal_gap 0.5)
			(thermal_bridge_width 0.5)
			(island_removal_mode 0)
		)
		(polygon
			(pts
				(xy 20.259802 -229.732586) (xy 19.912838 -230.07955) (xy 19.904202 -230.07955) (xy 19.904202 -231.018588)
				(xy 19.980402 -231.094788) (xy 22.164802 -231.094788) (xy 22.164802 -231.09555) (xy 22.622002 -231.09555)
				(xy 22.917912 -230.79964) (xy 22.917912 -229.886256) (xy 22.764242 -229.732586)
			)
		)
		(polygon
			(pts
				(xy 22.413214 -230.153464) (xy 22.210014 -230.153464) (xy 22.210014 -230.356664) (xy 22.413214 -230.356664)
			)
		)
	)
	(zone
		(layer "B.Cu")
		(hatch none 0.5)
		(connect_pads
			(clearance 0)
		)
		(min_thickness 0.25)
		(keepout
			(tracks not_allowed)
			(vias allowed)
			(pads allowed)
			(copperpour not_allowed)
			(footprints allowed)
		)
		(placement
			(enabled no)
			(sheetname "")
		)
		(fill
			(thermal_gap 0.5)
			(thermal_bridge_width 0.5)
			(island_removal_mode 0)
		)
		(polygon
			(pts
				(arc
					(start 278.23668 -236.34573)
					(mid 277.68804 -236.89437)
					(end 278.23668 -237.44301)
				)
				(arc
					(start 279.636728 -237.44301)
					(mid 280.185368 -236.89437)
					(end 279.636728 -236.34573)
				)
				(arc
					(start 279.141936 -236.34573)
					(mid 279.152757 -236.407736)
					(end 279.158192 -236.470444)
				)
				(xy 279.158954 -236.471206)
				(arc
					(start 279.158954 -236.680502)
					(mid 279.184566 -236.760559)
					(end 279.251918 -236.810804)
				)
				(arc
					(start 279.251918 -236.810804)
					(mid 280.030466 -236.900073)
					(end 279.249632 -236.96676)
				)
				(arc
					(start 279.249632 -236.96676)
					(mid 279.086753 -236.880768)
					(end 279.008586 -236.71403)
				)
				(xy 279.006554 -236.711998)
				(arc
					(start 279.006554 -236.502702)
					(mid 279.001028 -236.423466)
					(end 278.98471 -236.34573)
				)
				(arc
					(start 278.837898 -236.34573)
					(mid 278.856274 -236.406823)
					(end 278.865584 -236.469936)
				)
				(xy 278.866854 -236.471206) (xy 278.866854 -236.711998)
				(arc
					(start 278.864822 -236.71403)
					(mid 278.786577 -236.880693)
					(end 278.623776 -236.96676)
				)
				(arc
					(start 278.623776 -236.96676)
					(mid 277.842915 -236.900074)
					(end 278.62149 -236.810804)
				)
				(arc
					(start 278.62149 -236.810804)
					(mid 278.688775 -236.760511)
					(end 278.714454 -236.680502)
				)
				(arc
					(start 278.714454 -236.502702)
					(mid 278.702457 -236.420773)
					(end 278.667464 -236.34573)
				)
			)
		)
	)
	(zone
		(layer "B.Cu")
		(hatch none 0.5)
		(connect_pads
			(clearance 0)
		)
		(min_thickness 0.25)
		(keepout
			(tracks allowed)
			(vias allowed)
			(pads allowed)
			(copperpour allowed)
			(footprints allowed)
		)
		(placement
			(enabled no)
			(sheetname "")
		)
		(fill
			(thermal_gap 0.5)
			(thermal_bridge_width 0.5)
			(island_removal_mode 0)
		)
		(polygon
			(pts
				(xy 43.886374 -110.312708) (xy 46.037246 -110.312708) (xy 46.037246 -115.086384) (xy 43.886374 -115.086384)
			)
		)
	)
	(zone
		(layer "B.Cu")
		(hatch none 0.5)
		(connect_pads
			(clearance 0)
		)
		(min_thickness 0.25)
		(keepout
			(tracks not_allowed)
			(vias allowed)
			(pads allowed)
			(copperpour not_allowed)
			(footprints allowed)
		)
		(placement
			(enabled no)
			(sheetname "")
		)
		(fill
			(thermal_gap 0.5)
			(thermal_bridge_width 0.5)
			(island_removal_mode 0)
		)
		(polygon
			(pts
				(arc
					(start 279.236678 -216.545922)
					(mid 278.688038 -217.094562)
					(end 279.236678 -217.643202)
				)
				(arc
					(start 280.636726 -217.643202)
					(mid 281.185366 -217.094562)
					(end 280.636726 -216.545922)
				)
				(arc
					(start 280.141934 -216.545922)
					(mid 280.152755 -216.607928)
					(end 280.15819 -216.670636)
				)
				(xy 280.158952 -216.671398)
				(arc
					(start 280.158952 -216.880694)
					(mid 280.184564 -216.960751)
					(end 280.251916 -217.010996)
				)
				(arc
					(start 280.251916 -217.010996)
					(mid 281.030464 -217.100265)
					(end 280.24963 -217.166952)
				)
				(arc
					(start 280.24963 -217.166952)
					(mid 280.086751 -217.08096)
					(end 280.008584 -216.914222)
				)
				(xy 280.006552 -216.91219)
				(arc
					(start 280.006552 -216.702894)
					(mid 280.001026 -216.623658)
					(end 279.984708 -216.545922)
				)
				(arc
					(start 279.837896 -216.545922)
					(mid 279.856272 -216.607015)
					(end 279.865582 -216.670128)
				)
				(xy 279.866852 -216.671398) (xy 279.866852 -216.91219)
				(arc
					(start 279.86482 -216.914222)
					(mid 279.786575 -217.080885)
					(end 279.623774 -217.166952)
				)
				(arc
					(start 279.623774 -217.166952)
					(mid 278.842913 -217.100266)
					(end 279.621488 -217.010996)
				)
				(arc
					(start 279.621488 -217.010996)
					(mid 279.688773 -216.960703)
					(end 279.714452 -216.880694)
				)
				(arc
					(start 279.714452 -216.702894)
					(mid 279.702455 -216.620965)
					(end 279.667462 -216.545922)
				)
			)
		)
	)
	(zone
		(net "GND")
		(layer "B.Cu")
		(hatch none 0.5)
		(connect_pads
			(clearance 0.5)
		)
		(min_thickness 0.25)
		(fill yes
			(thermal_gap 0.5)
			(thermal_bridge_width 0.5)
			(island_removal_mode 0)
		)
		(polygon
			(pts
				(arc
					(start 288.905696 -167.177212)
					(mid 289.840467 -167.061511)
					(end 290.776914 -167.162734)
				)
				(xy 295.266364 -160.249616) (xy 295.266364 -158.072582) (xy 294.549576 -157.355794) (xy 292.833806 -157.355794)
				(arc
					(start 292.192456 -157.997144)
					(mid 290.780357 -160.325932)
					(end 288.219134 -161.2519)
				)
				(arc
					(start 288.219134 -161.2519)
					(mid 285.666202 -162.075456)
					(end 283.152088 -161.14014)
				)
				(arc
					(start 283.152088 -161.14014)
					(mid 279.474294 -159.824473)
					(end 278.577548 -156.022802)
				)
				(xy 278.577548 -155.283916) (xy 277.37943 -154.085798) (xy 270.675354 -154.085798) (xy 269.216632 -155.54452)
				(xy 269.216632 -155.805124) (xy 269.260066 -155.848558) (xy 269.260066 -157.454346) (xy 276.871938 -165.066218)
				(arc
					(start 279.796748 -165.066218)
					(mid 281.462529 -163.646651)
					(end 283.621734 -163.289234)
				)
				(arc
					(start 283.621734 -163.289234)
					(mid 286.413036 -163.977821)
					(end 288.061654 -166.33317)
				)
			)
		)
	)
	(zone
		(net "GND")
		(layer "B.Cu")
		(hatch none 0.5)
		(connect_pads
			(clearance 0.5)
		)
		(min_thickness 0.25)
		(fill yes
			(thermal_gap 0.5)
			(thermal_bridge_width 0.5)
			(island_removal_mode 0)
		)
		(polygon
			(pts
				(xy 301.102014 -136.983216) (xy 304.227992 -122.263662)
				(arc
					(start 304.227992 -118.837964)
					(mid 301.486495 -117.01982)
					(end 300.970442 -113.770918)
				)
				(arc
					(start 300.970442 -113.770918)
					(mid 300.995156 -113.032547)
					(end 301.152306 -112.310672)
				)
				(xy 301.152306 -111.561372)
				(arc
					(start 300.404276 -110.813342)
					(mid 294.987753 -109.477349)
					(end 290.956492 -105.62082)
				)
				(xy 290.140644 -105.62082)
				(arc
					(start 289.814508 -105.946956)
					(mid 289.829905 -106.152949)
					(end 289.835082 -106.359452)
				)
				(arc
					(start 289.835082 -109.618526)
					(mid 291.297324 -110.474883)
					(end 292.286944 -111.850424)
				)
				(arc
					(start 295.377108 -114.940588)
					(mid 298.337598 -116.832126)
					(end 298.738798 -120.32234)
				)
				(arc
					(start 299.805598 -121.38914)
					(mid 300.393437 -121.730513)
					(end 300.9138 -122.167904)
				)
				(arc
					(start 300.985174 -122.239532)
					(mid 302.3261 -128.163016)
					(end 296.296334 -128.88976)
				)
				(xy 295.823894 -128.88976) (xy 294.268652 -130.445002) (xy 294.268652 -134.486904) (xy 295.887648 -136.1059)
				(xy 297.699176 -136.1059) (xy 298.576492 -136.983216)
			)
		)
	)
	(zone
		(layer "B.Cu")
		(hatch none 0.5)
		(connect_pads
			(clearance 0)
		)
		(min_thickness 0.25)
		(keepout
			(tracks allowed)
			(vias allowed)
			(pads allowed)
			(copperpour allowed)
			(footprints allowed)
		)
		(placement
			(enabled no)
			(sheetname "")
		)
		(fill
			(thermal_gap 0.5)
			(thermal_bridge_width 0.5)
			(island_removal_mode 0)
		)
		(polygon
			(pts
				(xy 23.4696 -225.2726) (xy 25.273 -225.2726) (xy 25.273 -227.2538) (xy 23.4696 -227.2538)
			)
		)
	)
	(zone
		(layer "B.Cu")
		(hatch none 0.5)
		(connect_pads
			(clearance 0)
		)
		(min_thickness 0.25)
		(keepout
			(tracks not_allowed)
			(vias allowed)
			(pads allowed)
			(copperpour not_allowed)
			(footprints allowed)
		)
		(placement
			(enabled no)
			(sheetname "")
		)
		(fill
			(thermal_gap 0.5)
			(thermal_bridge_width 0.5)
			(island_removal_mode 0)
		)
		(polygon
			(pts
				(arc
					(start 129.42062 -14.41958)
					(mid 128.935607 -13.934186)
					(end 128.45034 -14.419326)
				)
				(arc
					(start 128.45034 -15.562326)
					(mid 128.93548 -16.047466)
					(end 129.42062 -15.562326)
				)
				(xy 129.42062 -15.213076)
				(arc
					(start 129.079752 -15.213076)
					(mid 129.031618 -15.233014)
					(end 129.01168 -15.281148)
				)
				(arc
					(start 129.01168 -15.306802)
					(mid 128.93548 -15.82897)
					(end 128.85928 -15.306802)
				)
				(xy 128.85928 -15.249652)
				(arc
					(start 128.862074 -15.246858)
					(mid 128.923932 -15.125328)
					(end 129.045462 -15.06347)
				)
				(xy 129.048256 -15.060676) (xy 129.42062 -15.060676) (xy 129.42062 -14.920976) (xy 129.038604 -14.920976)
				(arc
					(start 129.03581 -14.918182)
					(mid 128.921018 -14.859238)
					(end 128.862074 -14.744446)
				)
				(xy 128.85928 -14.741652)
				(arc
					(start 128.85928 -14.67485)
					(mid 128.93548 -14.152682)
					(end 129.01168 -14.67485)
				)
				(arc
					(start 129.01168 -14.710156)
					(mid 129.028791 -14.751465)
					(end 129.0701 -14.768576)
				)
				(xy 129.42062 -14.768576)
			)
		)
	)
	(zone
		(net "P12V_B_4_VIN_U34")
		(layer "B.Cu")
		(hatch none 0.5)
		(connect_pads
			(clearance 0.5)
		)
		(min_thickness 0.25)
		(fill yes
			(thermal_gap 0.5)
			(thermal_bridge_width 0.5)
			(island_removal_mode 0)
		)
		(polygon
			(pts
				(xy 426.430186 -108.891578) (xy 426.049186 -109.272578) (xy 426.049186 -112.193578) (xy 426.250608 -112.395)
				(xy 431.838608 -112.395) (xy 432.272186 -112.828578) (xy 433.034186 -112.828578) (xy 433.288186 -113.082578)
				(xy 433.288186 -114.098578) (xy 433.542186 -114.352578) (xy 434.177186 -114.352578) (xy 434.558186 -114.733578)
				(xy 436.463186 -114.733578) (xy 436.463186 -111.685578) (xy 433.669186 -108.891578)
			)
		)
		(polygon
			(pts
				(xy 432.932586 -112.091978) (xy 432.729386 -112.091978) (xy 432.729386 -112.295178) (xy 432.932586 -112.295178)
			)
		)
		(polygon
			(pts
				(xy 432.322986 -112.091978) (xy 432.119786 -112.091978) (xy 432.119786 -112.295178) (xy 432.322986 -112.295178)
			)
		)
		(polygon
			(pts
				(xy 427.560486 -110.377478) (xy 427.357286 -110.377478) (xy 427.357286 -110.580678) (xy 427.560486 -110.580678)
			)
		)
		(polygon
			(pts
				(xy 426.417486 -110.377478) (xy 426.214286 -110.377478) (xy 426.214286 -110.580678) (xy 426.417486 -110.580678)
			)
		)
	)
	(zone
		(net "GND")
		(layer "B.Cu")
		(hatch none 0.5)
		(connect_pads
			(clearance 0.5)
		)
		(min_thickness 0.25)
		(fill yes
			(thermal_gap 0.5)
			(thermal_bridge_width 0.5)
			(island_removal_mode 0)
		)
		(polygon
			(pts
				(xy 71.54545 -22.328632) (xy 70.17639 -21.439886) (xy 68.31457 -21.439886)
				(arc
					(start 67.82689 -21.927566)
					(mid 67.312576 -22.838601)
					(end 66.582798 -23.588218)
				)
				(xy 66.582798 -24.310086) (xy 66.894202 -24.62149) (xy 70.07987 -25.2984)
				(arc
					(start 70.793356 -25.2984)
					(mid 71.115349 -24.653774)
					(end 71.54545 -24.075644)
				)
			)
		)
	)
	(zone
		(net "MB0_12V_CTRL_GATE1")
		(layer "B.Cu")
		(hatch none 0.5)
		(connect_pads
			(clearance 0.5)
		)
		(min_thickness 0.25)
		(fill yes
			(thermal_gap 0.5)
			(thermal_bridge_width 0.5)
			(island_removal_mode 0)
		)
		(polygon
			(pts
				(xy 205.232254 -327.406) (xy 204.863954 -327.774554) (xy 204.863954 -331.857604) (xy 204.940154 -331.933804)
				(xy 206.438754 -331.933804) (xy 206.565754 -331.806804) (xy 206.565754 -327.723754) (xy 206.248 -327.406)
			)
		)
	)
	(zone
		(layer "B.Cu")
		(hatch none 0.5)
		(connect_pads
			(clearance 0)
		)
		(min_thickness 0.25)
		(keepout
			(tracks not_allowed)
			(vias allowed)
			(pads allowed)
			(copperpour not_allowed)
			(footprints allowed)
		)
		(placement
			(enabled no)
			(sheetname "")
		)
		(fill
			(thermal_gap 0.5)
			(thermal_bridge_width 0.5)
			(island_removal_mode 0)
		)
		(polygon
			(pts
				(arc
					(start 278.23668 -196.74586)
					(mid 277.68804 -197.2945)
					(end 278.23668 -197.84314)
				)
				(arc
					(start 279.636728 -197.84314)
					(mid 280.185368 -197.2945)
					(end 279.636728 -196.74586)
				)
				(xy 279.160224 -196.74586) (xy 279.158954 -196.765418)
				(arc
					(start 279.158954 -197.146418)
					(mid 279.180008 -197.197246)
					(end 279.230836 -197.2183)
				)
				(arc
					(start 279.250394 -197.2183)
					(mid 280.030505 -197.2945)
					(end 279.250394 -197.3707)
				)
				(xy 279.19934 -197.3707)
				(arc
					(start 279.196546 -197.36816)
					(mid 279.072177 -197.305077)
					(end 279.009094 -197.180708)
				)
				(xy 279.006554 -197.177914) (xy 279.006554 -196.74586) (xy 278.867362 -196.74586) (xy 278.866854 -196.765418)
				(xy 278.866854 -197.177914)
				(arc
					(start 278.864314 -197.180708)
					(mid 278.801231 -197.305077)
					(end 278.676862 -197.36816)
				)
				(xy 278.674068 -197.3707)
				(arc
					(start 278.623014 -197.3707)
					(mid 277.842903 -197.2945)
					(end 278.623014 -197.2183)
				)
				(arc
					(start 278.642572 -197.2183)
					(mid 278.6934 -197.197246)
					(end 278.714454 -197.146418)
				)
				(xy 278.714454 -196.74586)
			)
		)
	)
	(zone
		(net "GND")
		(layer "B.Cu")
		(hatch none 0.5)
		(connect_pads
			(clearance 0.5)
		)
		(min_thickness 0.25)
		(fill yes
			(thermal_gap 0.5)
			(thermal_bridge_width 0.5)
			(island_removal_mode 0)
		)
		(polygon
			(pts
				(xy 334.863186 -108.922058) (xy 330.095352 -116.263928) (xy 330.095352 -122.097038)
				(arc
					(start 331.357224 -123.35891)
					(mid 331.729024 -123.307351)
					(end 332.103984 -123.290076)
				)
				(arc
					(start 333.248 -123.290076)
					(mid 334.616377 -123.525717)
					(end 335.827116 -124.205492)
				)
				(arc
					(start 335.827116 -124.205492)
					(mid 336.500199 -124.120046)
					(end 337.178142 -124.147072)
				)
				(xy 337.619848 -123.705366) (xy 337.619848 -109.58576) (xy 336.956146 -108.922058)
			)
		)
	)
	(zone
		(layer "B.Cu")
		(hatch none 0.5)
		(connect_pads
			(clearance 0)
		)
		(min_thickness 0.25)
		(keepout
			(tracks allowed)
			(vias allowed)
			(pads allowed)
			(copperpour allowed)
			(footprints not_allowed)
		)
		(placement
			(enabled no)
			(sheetname "")
		)
		(fill
			(thermal_gap 0.5)
			(thermal_bridge_width 0.5)
			(island_removal_mode 0)
		)
		(polygon
			(pts
				(arc
					(start 167.824912 -181.799992)
					(mid 127.824992 -141.800072)
					(end 87.825072 -181.799992)
				)
				(arc
					(start 87.825072 -181.799992)
					(mid 127.824992 -221.799912)
					(end 167.824912 -181.799992)
				)
			)
		)
	)
	(zone
		(layer "B.Cu")
		(hatch none 0.5)
		(connect_pads
			(clearance 0)
		)
		(min_thickness 0.25)
		(keepout
			(tracks not_allowed)
			(vias allowed)
			(pads allowed)
			(copperpour not_allowed)
			(footprints allowed)
		)
		(placement
			(enabled no)
			(sheetname "")
		)
		(fill
			(thermal_gap 0.5)
			(thermal_bridge_width 0.5)
			(island_removal_mode 0)
		)
		(polygon
			(pts
				(arc
					(start 279.236678 -136.943338)
					(mid 278.685498 -137.494518)
					(end 279.236678 -138.045698)
				)
				(arc
					(start 280.636726 -138.045698)
					(mid 281.187906 -137.494518)
					(end 280.636726 -136.943338)
				)
				(arc
					(start 280.160984 -136.943338)
					(mid 280.171363 -137.002326)
					(end 280.176986 -137.061956)
				)
				(xy 280.178002 -137.063226)
				(arc
					(start 280.178002 -137.302748)
					(mid 280.199753 -137.363786)
					(end 280.255218 -137.397236)
				)
				(arc
					(start 280.255218 -137.397236)
					(mid 281.03044 -137.495565)
					(end 280.25471 -137.589768)
				)
				(xy 280.235152 -137.589768)
				(arc
					(start 280.23185 -137.586466)
					(mid 280.071647 -137.505623)
					(end 279.990804 -137.34542)
				)
				(xy 279.987502 -137.342118)
				(arc
					(start 279.987502 -137.102596)
					(mid 279.981715 -137.022129)
					(end 279.964388 -136.943338)
				)
				(arc
					(start 279.8572 -136.943338)
					(mid 279.874567 -137.001373)
					(end 279.884124 -137.061194)
				)
				(xy 279.885902 -137.063226) (xy 279.885902 -137.342118)
				(arc
					(start 279.8826 -137.34542)
					(mid 279.801757 -137.505623)
					(end 279.641554 -137.586466)
				)
				(xy 279.638252 -137.589768)
				(arc
					(start 279.618694 -137.589768)
					(mid 278.842968 -137.495565)
					(end 279.618186 -137.397236)
				)
				(arc
					(start 279.618186 -137.397236)
					(mid 279.673589 -137.363736)
					(end 279.695402 -137.302748)
				)
				(arc
					(start 279.695402 -137.102596)
					(mid 279.681849 -137.0187)
					(end 279.64257 -136.943338)
				)
				(xy 279.236932 -136.943338)
			)
		)
	)
	(zone
		(net "GATE_FAN1")
		(layer "B.Cu")
		(hatch none 0.5)
		(connect_pads
			(clearance 0.5)
		)
		(min_thickness 0.25)
		(fill yes
			(thermal_gap 0.5)
			(thermal_bridge_width 0.5)
			(island_removal_mode 0)
		)
		(polygon
			(pts
				(xy 126.625858 -362.323888) (xy 126.44501 -362.504736) (xy 126.44501 -363.898434) (xy 126.745746 -364.19917)
				(xy 127.837946 -364.19917) (xy 128.422146 -364.78337) (xy 131.546346 -364.78337) (xy 131.622546 -364.70717)
				(xy 131.622546 -362.54817) (xy 131.398264 -362.323888)
			)
		)
		(polygon
			(pts
				(xy 130.644646 -364.12297) (xy 130.441446 -364.12297) (xy 130.441446 -364.32617) (xy 130.644646 -364.32617)
			)
		)
		(polygon
			(pts
				(xy 130.085846 -364.12297) (xy 129.882646 -364.12297) (xy 129.882646 -364.32617) (xy 130.085846 -364.32617)
			)
		)
		(polygon
			(pts
				(xy 131.114292 -364.114334) (xy 130.911092 -364.114334) (xy 130.911092 -364.317534) (xy 131.114292 -364.317534)
			)
		)
	)
	(zone
		(net "GND")
		(layer "B.Cu")
		(hatch none 0.5)
		(connect_pads
			(clearance 0.5)
		)
		(min_thickness 0.25)
		(fill yes
			(thermal_gap 0.5)
			(thermal_bridge_width 0.5)
			(island_removal_mode 0)
		)
		(polygon
			(pts
				(arc
					(start 363.297978 -34.633662)
					(mid 364.509115 -34.204838)
					(end 365.793528 -34.172906)
				)
				(xy 366.388142 -33.25749) (xy 366.388142 -33.113726)
				(arc
					(start 366.193578 -32.919162)
					(mid 362.935852 -31.202132)
					(end 362.378244 -27.562048)
				)
				(xy 362.378244 -24.369776) (xy 361.932982 -23.924514) (xy 360.640884 -23.924514) (xy 360.15295 -24.412448)
				(arc
					(start 360.15295 -26.230072)
					(mid 360.141886 -26.530732)
					(end 360.108754 -26.829766)
				)
				(arc
					(start 360.108754 -27.933396)
					(mid 360.987504 -29.256729)
					(end 361.29595 -30.815026)
				)
				(arc
					(start 361.29595 -33.355026)
					(mid 361.294799 -33.451319)
					(end 361.291378 -33.547558)
				)
				(arc
					(start 362.262166 -34.518346)
					(mid 362.783761 -34.54287)
					(end 363.297978 -34.633662)
				)
			)
		)
	)
	(zone
		(net "GND")
		(layer "B.Cu")
		(hatch none 0.5)
		(connect_pads
			(clearance 0.5)
		)
		(min_thickness 0.25)
		(fill yes
			(thermal_gap 0.5)
			(thermal_bridge_width 0.5)
			(island_removal_mode 0)
		)
		(polygon
			(pts
				(xy 118.049294 -36.087304) (xy 119.07012 -35.066478)
				(arc
					(start 119.07012 -34.637472)
					(mid 118.915789 -34.004486)
					(end 118.863872 -33.355026)
				)
				(arc
					(start 118.863872 -30.815026)
					(mid 118.934201 -30.059728)
					(end 119.142764 -29.330396)
				)
				(arc
					(start 119.142764 -29.330396)
					(mid 118.600442 -28.764536)
					(end 118.17604 -28.105608)
				)
				(xy 117.343428 -28.105608) (xy 116.518182 -28.930854)
				(arc
					(start 116.518182 -31.45155)
					(mid 117.216032 -33.279207)
					(end 116.985288 -35.221926)
				)
				(xy 116.985288 -35.577018) (xy 117.495574 -36.087304)
			)
		)
	)
	(zone
		(layer "B.Cu")
		(hatch none 0.5)
		(connect_pads
			(clearance 0)
		)
		(min_thickness 0.25)
		(keepout
			(tracks not_allowed)
			(vias allowed)
			(pads allowed)
			(copperpour not_allowed)
			(footprints allowed)
		)
		(placement
			(enabled no)
			(sheetname "")
		)
		(fill
			(thermal_gap 0.5)
			(thermal_bridge_width 0.5)
			(island_removal_mode 0)
		)
		(polygon
			(pts
				(arc
					(start 400.675094 -178.799998)
					(mid 393.675108 -171.800012)
					(end 386.675122 -178.799998)
				)
				(arc
					(start 386.675122 -184.799986)
					(mid 393.675108 -191.799972)
					(end 400.675094 -184.799986)
				)
			)
		)
	)
	(zone
		(net "GND")
		(layer "B.Cu")
		(hatch none 0.5)
		(connect_pads
			(clearance 0.5)
		)
		(min_thickness 0.25)
		(fill yes
			(thermal_gap 0.5)
			(thermal_bridge_width 0.5)
			(island_removal_mode 0)
		)
		(polygon
			(pts
				(arc
					(start 394.920978 -149.695662)
					(mid 396.335758 -149.234435)
					(end 397.821912 -149.309836)
				)
				(xy 399.189702 -148.421852) (xy 399.189702 -148.14931) (xy 399.022316 -147.981924)
				(arc
					(start 397.891 -147.981924)
					(mid 393.862919 -144.605296)
					(end 396.484348 -140.049504)
				)
				(xy 397.991076 -138.542776)
				(arc
					(start 397.991076 -137.033)
					(mid 398.090324 -136.137383)
					(end 398.383252 -135.285226)
				)
				(xy 398.383252 -135.24611) (xy 398.144238 -135.007096)
				(arc
					(start 397.671798 -135.007096)
					(mid 397.542357 -135.187523)
					(end 397.40332 -135.360664)
				)
				(arc
					(start 397.40332 -135.360664)
					(mid 396.292493 -138.699654)
					(end 392.999468 -139.94003)
				)
				(arc
					(start 391.702798 -141.2367)
					(mid 391.679725 -141.664018)
					(end 391.61212 -142.086584)
				)
				(arc
					(start 391.61212 -142.887192)
					(mid 392.524777 -144.226474)
					(end 392.845798 -145.81505)
				)
				(arc
					(start 392.845798 -148.355304)
					(mid 392.842485 -148.519394)
					(end 392.83259 -148.683218)
				)
				(arc
					(start 393.735052 -149.58568)
					(mid 394.332038 -149.597286)
					(end 394.920978 -149.695662)
				)
			)
		)
	)
	(zone
		(layer "B.Cu")
		(hatch none 0.5)
		(connect_pads
			(clearance 0)
		)
		(min_thickness 0.25)
		(keepout
			(tracks allowed)
			(vias allowed)
			(pads allowed)
			(copperpour allowed)
			(footprints allowed)
		)
		(placement
			(enabled no)
			(sheetname "")
		)
		(fill
			(thermal_gap 0.5)
			(thermal_bridge_width 0.5)
			(island_removal_mode 0)
		)
		(polygon
			(pts
				(xy 42.3418 -114.1984) (xy 44.1198 -114.1984) (xy 44.1198 -115.7732) (xy 42.3418 -115.7732)
			)
		)
	)
	(zone
		(layer "B.Cu")
		(hatch none 0.5)
		(connect_pads
			(clearance 0)
		)
		(min_thickness 0.25)
		(keepout
			(tracks not_allowed)
			(vias allowed)
			(pads allowed)
			(copperpour not_allowed)
			(footprints allowed)
		)
		(placement
			(enabled no)
			(sheetname "")
		)
		(fill
			(thermal_gap 0.5)
			(thermal_bridge_width 0.5)
			(island_removal_mode 0)
		)
		(polygon
			(pts
				(arc
					(start 351.427542 -244.317774)
					(mid 350.942402 -243.832634)
					(end 350.457262 -244.317774)
				)
				(xy 350.457262 -244.667024)
				(arc
					(start 350.788224 -244.667024)
					(mid 350.843363 -244.644185)
					(end 350.866202 -244.589046)
				)
				(arc
					(start 350.866202 -244.573298)
					(mid 350.942402 -244.05113)
					(end 351.018602 -244.573298)
				)
				(xy 351.018602 -244.620542)
				(arc
					(start 351.016062 -244.623082)
					(mid 350.951118 -244.75194)
					(end 350.82226 -244.816884)
				)
				(xy 350.81972 -244.819424) (xy 350.457262 -244.819424) (xy 350.457262 -244.959124) (xy 350.81972 -244.959124)
				(arc
					(start 350.82226 -244.961664)
					(mid 350.951118 -245.026608)
					(end 351.016062 -245.155466)
				)
				(xy 351.018602 -245.158006)
				(arc
					(start 351.018602 -245.20525)
					(mid 350.942402 -245.727418)
					(end 350.866202 -245.20525)
				)
				(arc
					(start 350.866202 -245.189502)
					(mid 350.843363 -245.134363)
					(end 350.788224 -245.111524)
				)
				(xy 350.457262 -245.111524)
				(arc
					(start 350.457262 -245.46052)
					(mid 350.942275 -245.945914)
					(end 351.427542 -245.460774)
				)
			)
		)
	)
	(zone
		(layer "B.Cu")
		(hatch none 0.5)
		(connect_pads
			(clearance 0)
		)
		(min_thickness 0.25)
		(keepout
			(tracks allowed)
			(vias allowed)
			(pads allowed)
			(copperpour allowed)
			(footprints not_allowed)
		)
		(placement
			(enabled no)
			(sheetname "")
		)
		(fill
			(thermal_gap 0.5)
			(thermal_bridge_width 0.5)
			(island_removal_mode 0)
		)
		(polygon
			(pts
				(arc
					(start 87.825072 -181.799992)
					(mid 127.824992 -221.799912)
					(end 167.824912 -181.799992)
				)
				(arc
					(start 167.824912 -181.799992)
					(mid 127.824992 -141.800072)
					(end 87.825072 -181.799992)
				)
			)
		)
	)
	(zone
		(net "MB3_CM_GATE")
		(layer "B.Cu")
		(hatch none 0.5)
		(connect_pads
			(clearance 0.5)
		)
		(min_thickness 0.25)
		(fill yes
			(thermal_gap 0.5)
			(thermal_bridge_width 0.5)
			(island_removal_mode 0)
		)
		(polygon
			(pts
				(xy 250.6726 -367.8936) (xy 250.0376 -368.5286) (xy 250.0376 -369.8494) (xy 250.1646 -369.9764)
				(xy 251.0282 -369.9764) (xy 251.5616 -369.443) (xy 252.603 -369.443) (xy 252.73 -369.316) (xy 252.73 -368.0206)
				(xy 252.603 -367.8936)
			)
		)
	)
	(zone
		(net "P12V_B_1_VIN_U31")
		(layer "B.Cu")
		(hatch none 0.5)
		(connect_pads
			(clearance 0.5)
		)
		(min_thickness 0.25)
		(fill yes
			(thermal_gap 0.5)
			(thermal_bridge_width 0.5)
			(island_removal_mode 0)
		)
		(polygon
			(pts
				(xy 9.718802 -219.20835) (xy 9.337802 -219.58935) (xy 9.337802 -222.51035) (xy 9.591802 -222.76435)
				(xy 15.179802 -222.76435) (xy 15.560802 -223.14535) (xy 16.322802 -223.14535) (xy 16.576802 -223.39935)
				(xy 16.576802 -224.41535) (xy 16.830802 -224.66935) (xy 17.465802 -224.66935) (xy 17.846802 -225.05035)
				(xy 19.751802 -225.05035) (xy 19.751802 -222.00235) (xy 16.957802 -219.20835)
			)
		)
		(polygon
			(pts
				(xy 16.221202 -222.40875) (xy 16.018002 -222.40875) (xy 16.018002 -222.61195) (xy 16.221202 -222.61195)
			)
		)
		(polygon
			(pts
				(xy 15.611602 -222.40875) (xy 15.408402 -222.40875) (xy 15.408402 -222.61195) (xy 15.611602 -222.61195)
			)
		)
		(polygon
			(pts
				(xy 10.849102 -220.69425) (xy 10.645902 -220.69425) (xy 10.645902 -220.89745) (xy 10.849102 -220.89745)
			)
		)
		(polygon
			(pts
				(xy 9.706102 -220.69425) (xy 9.502902 -220.69425) (xy 9.502902 -220.89745) (xy 9.706102 -220.89745)
			)
		)
	)
	(zone
		(layer "B.Cu")
		(hatch none 0.5)
		(connect_pads
			(clearance 0)
		)
		(min_thickness 0.25)
		(keepout
			(tracks not_allowed)
			(vias allowed)
			(pads allowed)
			(copperpour not_allowed)
			(footprints allowed)
		)
		(placement
			(enabled no)
			(sheetname "")
		)
		(fill
			(thermal_gap 0.5)
			(thermal_bridge_width 0.5)
			(island_removal_mode 0)
		)
		(polygon
			(pts
				(arc
					(start 97.870772 -244.419374)
					(mid 97.385632 -243.934234)
					(end 96.900492 -244.419374)
				)
				(arc
					(start 96.900492 -245.56212)
					(mid 97.385505 -246.047514)
					(end 97.870772 -245.562374)
				)
				(xy 97.870772 -245.213124)
				(arc
					(start 97.529904 -245.213124)
					(mid 97.48177 -245.233062)
					(end 97.461832 -245.281196)
				)
				(arc
					(start 97.461832 -245.30685)
					(mid 97.385632 -245.829018)
					(end 97.309432 -245.30685)
				)
				(xy 97.309432 -245.2497)
				(arc
					(start 97.312226 -245.246906)
					(mid 97.374084 -245.125376)
					(end 97.495614 -245.063518)
				)
				(xy 97.498408 -245.060724) (xy 97.870772 -245.060724) (xy 97.870772 -244.921024) (xy 97.488756 -244.921024)
				(arc
					(start 97.485962 -244.91823)
					(mid 97.37117 -244.859286)
					(end 97.312226 -244.744494)
				)
				(xy 97.309432 -244.7417)
				(arc
					(start 97.309432 -244.674898)
					(mid 97.385632 -244.15273)
					(end 97.461832 -244.674898)
				)
				(arc
					(start 97.461832 -244.710204)
					(mid 97.478943 -244.751513)
					(end 97.520252 -244.768624)
				)
				(xy 97.870772 -244.768624)
			)
		)
	)
	(zone
		(layer "B.Cu")
		(hatch none 0.5)
		(connect_pads
			(clearance 0)
		)
		(min_thickness 0.25)
		(keepout
			(tracks not_allowed)
			(vias allowed)
			(pads allowed)
			(copperpour not_allowed)
			(footprints allowed)
		)
		(placement
			(enabled no)
			(sheetname "")
		)
		(fill
			(thermal_gap 0.5)
			(thermal_bridge_width 0.5)
			(island_removal_mode 0)
		)
		(polygon
			(pts
				(arc
					(start 251.199904 -244.00002)
					(mid 244.199918 -237.000034)
					(end 237.199932 -244.00002)
				)
				(arc
					(start 237.199932 -250.000008)
					(mid 244.199918 -256.999994)
					(end 251.199904 -250.000008)
				)
			)
		)
	)
	(zone
		(layer "B.Cu")
		(hatch none 0.5)
		(connect_pads
			(clearance 0)
		)
		(min_thickness 0.25)
		(keepout
			(tracks not_allowed)
			(vias allowed)
			(pads allowed)
			(copperpour not_allowed)
			(footprints allowed)
		)
		(placement
			(enabled no)
			(sheetname "")
		)
		(fill
			(thermal_gap 0.5)
			(thermal_bridge_width 0.5)
			(island_removal_mode 0)
		)
		(polygon
			(pts
				(arc
					(start 34.770822 -244.419374)
					(mid 34.285682 -243.934234)
					(end 33.800542 -244.419374)
				)
				(arc
					(start 33.800542 -245.56212)
					(mid 34.285555 -246.047514)
					(end 34.770822 -245.562374)
				)
				(xy 34.770822 -245.213124)
				(arc
					(start 34.429954 -245.213124)
					(mid 34.38182 -245.233062)
					(end 34.361882 -245.281196)
				)
				(arc
					(start 34.361882 -245.30685)
					(mid 34.285682 -245.829018)
					(end 34.209482 -245.30685)
				)
				(xy 34.209482 -245.2497)
				(arc
					(start 34.212276 -245.246906)
					(mid 34.274134 -245.125376)
					(end 34.395664 -245.063518)
				)
				(xy 34.398458 -245.060724) (xy 34.770822 -245.060724) (xy 34.770822 -244.921024) (xy 34.388806 -244.921024)
				(arc
					(start 34.386012 -244.91823)
					(mid 34.27122 -244.859286)
					(end 34.212276 -244.744494)
				)
				(xy 34.209482 -244.7417)
				(arc
					(start 34.209482 -244.674898)
					(mid 34.285682 -244.15273)
					(end 34.361882 -244.674898)
				)
				(arc
					(start 34.361882 -244.710204)
					(mid 34.378993 -244.751513)
					(end 34.420302 -244.768624)
				)
				(xy 34.770822 -244.768624)
			)
		)
	)
	(zone
		(layer "B.Cu")
		(hatch none 0.5)
		(connect_pads
			(clearance 0)
		)
		(min_thickness 0.25)
		(keepout
			(tracks allowed)
			(vias allowed)
			(pads allowed)
			(copperpour allowed)
			(footprints allowed)
		)
		(placement
			(enabled no)
			(sheetname "")
		)
		(fill
			(thermal_gap 0.5)
			(thermal_bridge_width 0.5)
			(island_removal_mode 0)
		)
		(polygon
			(pts
				(xy 9.057386 -224.394776) (xy 9.057386 -222.243904) (xy 17.222724 -222.243904) (xy 17.222724 -224.394776)
			)
		)
	)
	(zone
		(layer "B.Cu")
		(hatch none 0.5)
		(connect_pads
			(clearance 0)
		)
		(min_thickness 0.25)
		(keepout
			(tracks not_allowed)
			(vias allowed)
			(pads allowed)
			(copperpour not_allowed)
			(footprints allowed)
		)
		(placement
			(enabled no)
			(sheetname "")
		)
		(fill
			(thermal_gap 0.5)
			(thermal_bridge_width 0.5)
			(island_removal_mode 0)
		)
		(polygon
			(pts
				(arc
					(start 319.8876 -244.312694)
					(mid 319.40246 -243.827554)
					(end 318.91732 -244.312694)
				)
				(xy 318.91732 -244.661944)
				(arc
					(start 319.22466 -244.661944)
					(mid 319.293664 -244.634917)
					(end 319.326006 -244.568218)
				)
				(arc
					(start 319.326006 -244.568218)
					(mid 319.402582 -244.045977)
					(end 319.47866 -244.568218)
				)
				(xy 319.47866 -244.59184)
				(arc
					(start 319.476374 -244.594126)
					(mid 319.404244 -244.739928)
					(end 319.258442 -244.812058)
				)
				(xy 319.256156 -244.814344) (xy 318.91732 -244.814344) (xy 318.91732 -244.954044) (xy 319.256156 -244.954044)
				(arc
					(start 319.258442 -244.95633)
					(mid 319.404244 -245.02846)
					(end 319.476374 -245.174262)
				)
				(xy 319.47866 -245.176548)
				(arc
					(start 319.47866 -245.20017)
					(mid 319.402582 -245.722338)
					(end 319.326006 -245.20017)
				)
				(arc
					(start 319.326006 -245.20017)
					(mid 319.293698 -245.133434)
					(end 319.22466 -245.106444)
				)
				(xy 318.91732 -245.106444)
				(arc
					(start 318.91732 -245.45544)
					(mid 319.402333 -245.940834)
					(end 319.8876 -245.455694)
				)
			)
		)
	)
	(zone
		(net "GND")
		(layer "B.Cu")
		(hatch none 0.5)
		(connect_pads
			(clearance 0.5)
		)
		(min_thickness 0.25)
		(fill yes
			(thermal_gap 0.5)
			(thermal_bridge_width 0.5)
			(island_removal_mode 0)
		)
		(polygon
			(pts
				(xy 9.598152 -223.393) (xy 9.464802 -223.52635) (xy 9.464802 -225.30435) (xy 12.004802 -227.84435)
				(xy 15.052802 -227.84435) (xy 15.179802 -227.71735) (xy 15.179802 -226.32035) (xy 15.687802 -225.812096)
				(xy 15.687802 -224.66935) (xy 16.195802 -224.16135) (xy 16.195802 -223.52635) (xy 16.068802 -223.39935)
				(xy 15.306802 -223.39935) (xy 15.300452 -223.393)
			)
		)
		(polygon
			(pts
				(xy 14.900402 -225.76155) (xy 14.697202 -225.76155) (xy 14.697202 -225.96475) (xy 14.900402 -225.96475)
			)
		)
		(polygon
			(pts
				(xy 14.900402 -224.89795) (xy 14.697202 -224.89795) (xy 14.697202 -225.10115) (xy 14.900402 -225.10115)
			)
		)
		(polygon
			(pts
				(xy 15.611602 -223.93275) (xy 15.408402 -223.93275) (xy 15.408402 -224.13595) (xy 15.611602 -224.13595)
			)
		)
	)
	(zone
		(net "MB0_CM_GATE_R")
		(layer "B.Cu")
		(hatch none 0.5)
		(connect_pads
			(clearance 0.5)
		)
		(min_thickness 0.25)
		(fill yes
			(thermal_gap 0.5)
			(thermal_bridge_width 0.5)
			(island_removal_mode 0)
		)
		(polygon
			(pts
				(xy 207.264 -328.295) (xy 207.01 -328.549) (xy 207.01 -329.819) (xy 207.264 -330.073) (xy 209.042 -330.073)
				(xy 209.296 -329.819) (xy 209.296 -328.549) (xy 209.042 -328.295)
			)
		)
	)
	(zone
		(net "P3V3_STBY_VIN")
		(layer "B.Cu")
		(hatch none 0.5)
		(connect_pads
			(clearance 0.5)
		)
		(min_thickness 0.25)
		(fill yes
			(thermal_gap 0.5)
			(thermal_bridge_width 0.5)
			(island_removal_mode 0)
		)
		(polygon
			(pts
				(xy 253.5936 -283.3624) (xy 252.095 -284.861) (xy 252.095 -291.465) (xy 252.349 -291.719) (xy 254.889 -291.719)
				(xy 255.143 -291.465) (xy 255.143 -286.3088) (xy 254.1524 -285.3182) (xy 254.1524 -284.5054) (xy 254.3302 -284.3276)
				(xy 254.3302 -283.4386) (xy 254.254 -283.3624)
			)
		)
		(polygon
			(pts
				(xy 252.8316 -287.4772) (xy 252.6284 -287.4772) (xy 252.6284 -287.6804) (xy 252.8316 -287.6804)
			)
		)
		(polygon
			(pts
				(xy 252.8316 -286.8676) (xy 252.6284 -286.8676) (xy 252.6284 -287.0708) (xy 252.8316 -287.0708)
			)
		)
	)
	(zone
		(layer "B.Cu")
		(hatch none 0.5)
		(connect_pads
			(clearance 0)
		)
		(min_thickness 0.25)
		(keepout
			(tracks not_allowed)
			(vias allowed)
			(pads allowed)
			(copperpour not_allowed)
			(footprints allowed)
		)
		(placement
			(enabled no)
			(sheetname "")
		)
		(fill
			(thermal_gap 0.5)
			(thermal_bridge_width 0.5)
			(island_removal_mode 0)
		)
		(polygon
			(pts
				(arc
					(start 40.32504 -63.799974)
					(mid 33.325054 -56.799988)
					(end 26.325068 -63.799974)
				)
				(arc
					(start 26.325068 -69.799962)
					(mid 33.325054 -76.799948)
					(end 40.32504 -69.799962)
				)
			)
		)
	)
	(zone
		(layer "B.Cu")
		(hatch none 0.5)
		(connect_pads
			(clearance 0)
		)
		(min_thickness 0.25)
		(keepout
			(tracks allowed)
			(vias allowed)
			(pads allowed)
			(copperpour allowed)
			(footprints not_allowed)
		)
		(placement
			(enabled no)
			(sheetname "")
		)
		(fill
			(thermal_gap 0.5)
			(thermal_bridge_width 0.5)
			(island_removal_mode 0)
		)
		(polygon
			(pts
				(arc
					(start 251.199904 -244.00002)
					(mid 244.199918 -237.000034)
					(end 237.199932 -244.00002)
				)
				(arc
					(start 237.199932 -250.000008)
					(mid 244.199918 -256.999994)
					(end 251.199904 -250.000008)
				)
			)
		)
	)
	(zone
		(layer "B.Cu")
		(hatch none 0.5)
		(connect_pads
			(clearance 0)
		)
		(min_thickness 0.25)
		(keepout
			(tracks allowed)
			(vias allowed)
			(pads allowed)
			(copperpour allowed)
			(footprints allowed)
		)
		(placement
			(enabled no)
			(sheetname "")
		)
		(fill
			(thermal_gap 0.5)
			(thermal_bridge_width 0.5)
			(island_removal_mode 0)
		)
		(polygon
			(pts
				(xy 454.64095 -221.483682) (xy 456.791822 -221.483682) (xy 456.791822 -226.257358) (xy 454.64095 -226.257358)
			)
		)
	)
	(zone
		(layer "B.Cu")
		(hatch none 0.5)
		(connect_pads
			(clearance 0)
		)
		(min_thickness 0.25)
		(keepout
			(tracks not_allowed)
			(vias allowed)
			(pads allowed)
			(copperpour not_allowed)
			(footprints allowed)
		)
		(placement
			(enabled no)
			(sheetname "")
		)
		(fill
			(thermal_gap 0.5)
			(thermal_bridge_width 0.5)
			(island_removal_mode 0)
		)
		(polygon
			(pts
				(arc
					(start 463.674968 -178.799998)
					(mid 456.674982 -171.800012)
					(end 449.674996 -178.799998)
				)
				(arc
					(start 449.674996 -184.799986)
					(mid 456.674982 -191.799972)
					(end 463.674968 -184.799986)
				)
			)
		)
	)
	(zone
		(layer "B.Cu")
		(hatch none 0.5)
		(connect_pads
			(clearance 0)
		)
		(min_thickness 0.25)
		(keepout
			(tracks not_allowed)
			(vias allowed)
			(pads allowed)
			(copperpour not_allowed)
			(footprints allowed)
		)
		(placement
			(enabled no)
			(sheetname "")
		)
		(fill
			(thermal_gap 0.5)
			(thermal_bridge_width 0.5)
			(island_removal_mode 0)
		)
		(polygon
			(pts
				(arc
					(start 160.970722 -14.41958)
					(mid 160.485709 -13.934186)
					(end 160.000442 -14.419326)
				)
				(arc
					(start 160.000442 -15.562326)
					(mid 160.485582 -16.047466)
					(end 160.970722 -15.562326)
				)
				(xy 160.970722 -15.213076)
				(arc
					(start 160.629854 -15.213076)
					(mid 160.58172 -15.233014)
					(end 160.561782 -15.281148)
				)
				(arc
					(start 160.561782 -15.306802)
					(mid 160.485582 -15.82897)
					(end 160.409382 -15.306802)
				)
				(xy 160.409382 -15.249652)
				(arc
					(start 160.412176 -15.246858)
					(mid 160.474034 -15.125328)
					(end 160.595564 -15.06347)
				)
				(xy 160.598358 -15.060676) (xy 160.970722 -15.060676) (xy 160.970722 -14.920976) (xy 160.588706 -14.920976)
				(arc
					(start 160.585912 -14.918182)
					(mid 160.47112 -14.859238)
					(end 160.412176 -14.744446)
				)
				(xy 160.409382 -14.741652)
				(arc
					(start 160.409382 -14.67485)
					(mid 160.485582 -14.152682)
					(end 160.561782 -14.67485)
				)
				(arc
					(start 160.561782 -14.710156)
					(mid 160.578893 -14.751465)
					(end 160.620202 -14.768576)
				)
				(xy 160.970722 -14.768576)
			)
		)
	)
	(zone
		(layer "B.Cu")
		(hatch none 0.5)
		(connect_pads
			(clearance 0)
		)
		(min_thickness 0.25)
		(keepout
			(tracks not_allowed)
			(vias allowed)
			(pads allowed)
			(copperpour not_allowed)
			(footprints allowed)
		)
		(placement
			(enabled no)
			(sheetname "")
		)
		(fill
			(thermal_gap 0.5)
			(thermal_bridge_width 0.5)
			(island_removal_mode 0)
		)
		(polygon
			(pts
				(arc
					(start 67.69989 -339.39988)
					(mid 71.699882 -335.399888)
					(end 67.69989 -331.399896)
				)
				(arc
					(start 62.61989 -331.399896)
					(mid 58.619898 -335.399888)
					(end 62.61989 -339.39988)
				)
			)
		)
	)
	(zone
		(layer "B.Cu")
		(hatch none 0.5)
		(connect_pads
			(clearance 0)
		)
		(min_thickness 0.25)
		(keepout
			(tracks not_allowed)
			(vias allowed)
			(pads allowed)
			(copperpour not_allowed)
			(footprints allowed)
		)
		(placement
			(enabled no)
			(sheetname "")
		)
		(fill
			(thermal_gap 0.5)
			(thermal_bridge_width 0.5)
			(island_removal_mode 0)
		)
		(polygon
			(pts
				(arc
					(start 103.324914 -178.799998)
					(mid 96.324928 -171.800012)
					(end 89.324942 -178.799998)
				)
				(arc
					(start 89.324942 -184.799986)
					(mid 96.324928 -191.799972)
					(end 103.324914 -184.799986)
				)
			)
		)
	)
	(zone
		(layer "B.Cu")
		(hatch none 0.5)
		(connect_pads
			(clearance 0)
		)
		(min_thickness 0.25)
		(keepout
			(tracks not_allowed)
			(vias allowed)
			(pads allowed)
			(copperpour not_allowed)
			(footprints allowed)
		)
		(placement
			(enabled no)
			(sheetname "")
		)
		(fill
			(thermal_gap 0.5)
			(thermal_bridge_width 0.5)
			(island_removal_mode 0)
		)
		(polygon
			(pts
				(arc
					(start 278.23668 -189.545722)
					(mid 277.68804 -190.094362)
					(end 278.23668 -190.643002)
				)
				(arc
					(start 279.636728 -190.643002)
					(mid 280.185368 -190.094362)
					(end 279.636728 -189.545722)
				)
				(arc
					(start 279.141936 -189.545722)
					(mid 279.152757 -189.607728)
					(end 279.158192 -189.670436)
				)
				(xy 279.158954 -189.671198)
				(arc
					(start 279.158954 -189.880494)
					(mid 279.184566 -189.960551)
					(end 279.251918 -190.010796)
				)
				(arc
					(start 279.251918 -190.010796)
					(mid 280.030466 -190.100065)
					(end 279.249632 -190.166752)
				)
				(arc
					(start 279.249632 -190.166752)
					(mid 279.086753 -190.08076)
					(end 279.008586 -189.914022)
				)
				(xy 279.006554 -189.91199)
				(arc
					(start 279.006554 -189.702694)
					(mid 279.001028 -189.623458)
					(end 278.98471 -189.545722)
				)
				(arc
					(start 278.837898 -189.545722)
					(mid 278.856274 -189.606815)
					(end 278.865584 -189.669928)
				)
				(xy 278.866854 -189.671198) (xy 278.866854 -189.91199)
				(arc
					(start 278.864822 -189.914022)
					(mid 278.786577 -190.080685)
					(end 278.623776 -190.166752)
				)
				(arc
					(start 278.623776 -190.166752)
					(mid 277.842915 -190.100066)
					(end 278.62149 -190.010796)
				)
				(arc
					(start 278.62149 -190.010796)
					(mid 278.688775 -189.960503)
					(end 278.714454 -189.880494)
				)
				(arc
					(start 278.714454 -189.702694)
					(mid 278.702457 -189.620765)
					(end 278.667464 -189.545722)
				)
			)
		)
	)
	(zone
		(net "GND")
		(layer "B.Cu")
		(hatch none 0.5)
		(connect_pads
			(clearance 0.5)
		)
		(min_thickness 0.25)
		(fill yes
			(thermal_gap 0.5)
			(thermal_bridge_width 0.5)
			(island_removal_mode 0)
		)
		(polygon
			(pts
				(xy 20.092416 -221.833694) (xy 19.9136 -222.01251) (xy 19.9136 -227.71735) (xy 20.181824 -227.985574)
				(xy 20.181824 -228.833172) (xy 20.666202 -229.31755) (xy 21.520404 -229.31755) (xy 21.529802 -229.326948)
				(xy 23.2156 -227.64115) (xy 23.2156 -222.015304) (xy 23.03399 -221.833694)
			)
		)
	)
	(zone
		(layer "B.Cu")
		(hatch none 0.5)
		(connect_pads
			(clearance 0)
		)
		(min_thickness 0.25)
		(keepout
			(tracks allowed)
			(vias allowed)
			(pads allowed)
			(copperpour allowed)
			(footprints not_allowed)
		)
		(placement
			(enabled no)
			(sheetname "")
		)
		(fill
			(thermal_gap 0.5)
			(thermal_bridge_width 0.5)
			(island_removal_mode 0)
		)
		(polygon
			(pts
				(arc
					(start 196.799962 -204.0001)
					(mid 189.799976 -197.000114)
					(end 182.79999 -204.0001)
				)
				(arc
					(start 182.79999 -210.000088)
					(mid 189.799976 -217.000074)
					(end 196.799962 -210.000088)
				)
			)
		)
	)
	(zone
		(layer "B.Cu")
		(hatch none 0.5)
		(connect_pads
			(clearance 0)
		)
		(min_thickness 0.25)
		(keepout
			(tracks not_allowed)
			(vias allowed)
			(pads allowed)
			(copperpour not_allowed)
			(footprints allowed)
		)
		(placement
			(enabled no)
			(sheetname "")
		)
		(fill
			(thermal_gap 0.5)
			(thermal_bridge_width 0.5)
			(island_removal_mode 0)
		)
		(polygon
			(pts
				(arc
					(start 279.236678 -223.745806)
					(mid 278.688038 -224.294446)
					(end 279.236678 -224.843086)
				)
				(xy 279.716738 -224.843086) (xy 279.715214 -224.822512) (xy 279.714452 -224.821496)
				(arc
					(start 279.714452 -224.5106)
					(mid 279.688782 -224.429896)
					(end 279.621234 -224.378774)
				)
				(arc
					(start 279.621234 -224.378774)
					(mid 278.842983 -224.287716)
					(end 279.623774 -224.22231)
				)
				(arc
					(start 279.623774 -224.22231)
					(mid 279.786765 -224.309509)
					(end 279.86482 -224.477072)
				)
				(xy 279.866852 -224.479104)
				(arc
					(start 279.866852 -224.79)
					(mid 279.867618 -224.816586)
					(end 279.8699 -224.843086)
				)
				(xy 280.01087 -224.843086) (xy 280.00833 -224.823274) (xy 280.006552 -224.821496) (xy 280.006552 -224.479104)
				(arc
					(start 280.008584 -224.477072)
					(mid 280.086637 -224.309508)
					(end 280.24963 -224.22231)
				)
				(arc
					(start 280.24963 -224.22231)
					(mid 281.030386 -224.287717)
					(end 280.25217 -224.378774)
				)
				(arc
					(start 280.25217 -224.378774)
					(mid 280.184556 -224.429849)
					(end 280.158952 -224.5106)
				)
				(arc
					(start 280.158952 -224.79)
					(mid 280.161137 -224.816891)
					(end 280.167588 -224.843086)
				)
				(arc
					(start 280.636726 -224.843086)
					(mid 281.185366 -224.294446)
					(end 280.636726 -223.745806)
				)
			)
		)
	)
	(zone
		(net "P5V_B_1_LL_R")
		(layer "B.Cu")
		(hatch none 0.5)
		(connect_pads
			(clearance 0.5)
		)
		(min_thickness 0.25)
		(fill yes
			(thermal_gap 0.5)
			(thermal_bridge_width 0.5)
			(island_removal_mode 0)
		)
		(polygon
			(pts
				(xy 30.597602 -229.29215) (xy 30.419802 -229.46995) (xy 30.419802 -231.011476) (xy 30.633924 -231.225598)
				(xy 31.271972 -231.225598) (xy 31.40329 -231.356916) (xy 31.40329 -232.383838) (xy 31.689802 -232.67035)
				(xy 32.42564 -232.67035) (xy 32.67964 -232.41635) (xy 32.67964 -229.469188) (xy 32.502602 -229.29215)
			)
		)
		(polygon
			(pts
				(xy 32.170624 -231.114854) (xy 31.967424 -231.114854) (xy 31.967424 -231.318054) (xy 32.170624 -231.318054)
			)
		)
		(polygon
			(pts
				(xy 32.170624 -230.505254) (xy 31.967424 -230.505254) (xy 31.967424 -230.708454) (xy 32.170624 -230.708454)
			)
		)
		(polygon
			(pts
				(xy 31.963614 -230.135176) (xy 31.760414 -230.135176) (xy 31.760414 -230.338376) (xy 31.963614 -230.338376)
			)
		)
		(polygon
			(pts
				(xy 31.301944 -229.710996) (xy 31.098744 -229.710996) (xy 31.098744 -229.914196) (xy 31.301944 -229.914196)
			)
		)
		(polygon
			(pts
				(xy 30.743144 -229.710996) (xy 30.539944 -229.710996) (xy 30.539944 -229.914196) (xy 30.743144 -229.914196)
			)
		)
	)
	(zone
		(layer "B.Cu")
		(hatch none 0.5)
		(connect_pads
			(clearance 0)
		)
		(min_thickness 0.25)
		(keepout
			(tracks allowed)
			(vias allowed)
			(pads allowed)
			(copperpour allowed)
			(footprints allowed)
		)
		(placement
			(enabled no)
			(sheetname "")
		)
		(fill
			(thermal_gap 0.5)
			(thermal_bridge_width 0.5)
			(island_removal_mode 0)
		)
		(polygon
			(pts
				(xy 434.213 -115.1128) (xy 435.991 -115.1128) (xy 435.991 -116.6876) (xy 434.213 -116.6876)
			)
		)
	)
	(zone
		(net "GND")
		(layer "B.Cu")
		(hatch none 0.5)
		(connect_pads
			(clearance 0.5)
		)
		(min_thickness 0.25)
		(fill yes
			(thermal_gap 0.5)
			(thermal_bridge_width 0.5)
			(island_removal_mode 0)
		)
		(polygon
			(pts
				(xy 432.621436 -123.509024) (xy 431.656236 -122.543824)
				(arc
					(start 429.7426 -122.543824)
					(mid 429.097186 -122.594748)
					(end 428.451772 -122.543824)
				)
				(arc
					(start 428.143162 -122.543824)
					(mid 428.007069 -122.541528)
					(end 427.871128 -122.53468)
				)
				(xy 427.068488 -122.53468) (xy 427.068488 -122.540268) (xy 426.86224 -122.746516) (xy 426.86224 -123.093988)
				(xy 427.058328 -123.290076)
				(arc
					(start 427.863 -123.290076)
					(mid 429.231377 -123.525717)
					(end 430.442116 -124.205492)
				)
				(arc
					(start 430.442116 -124.205492)
					(mid 433.788244 -124.966263)
					(end 435.377336 -128.007618)
				)
				(xy 436.308246 -128.938528) (xy 437.131206 -128.938528) (xy 439.471816 -128.440942) (xy 440.425586 -127.487172)
				(arc
					(start 440.425586 -126.524258)
					(mid 439.555309 -125.747501)
					(end 438.939686 -124.756672)
				)
				(arc
					(start 438.939686 -124.756672)
					(mid 438.673484 -124.686044)
					(end 438.412636 -124.597668)
				)
				(arc
					(start 438.412636 -124.597668)
					(mid 437.835849 -124.633812)
					(end 437.25973 -124.58827)
				)
				(xy 435.11343 -124.58827) (xy 434.518562 -123.993402) (xy 433.388262 -123.993402) (xy 433.388262 -123.85929)
				(xy 433.037996 -123.509024)
			)
		)
	)
	(zone
		(net "P12V_B_2_VIN_U32")
		(layer "B.Cu")
		(hatch none 0.5)
		(connect_pads
			(clearance 0.5)
		)
		(min_thickness 0.25)
		(fill yes
			(thermal_gap 0.5)
			(thermal_bridge_width 0.5)
			(island_removal_mode 0)
		)
		(polygon
			(pts
				(xy 35.211258 -108.023406) (xy 34.906458 -108.328206) (xy 34.906458 -109.873542) (xy 34.365184 -110.414816)
				(xy 34.365184 -111.327184) (xy 34.544 -111.506) (xy 39.954454 -111.506) (xy 40.40886 -111.960406)
				(xy 41.17086 -111.960406) (xy 41.42486 -112.214406) (xy 41.42486 -113.230406) (xy 41.67886 -113.484406)
				(xy 42.31386 -113.484406) (xy 42.69486 -113.865406) (xy 44.59986 -113.865406) (xy 44.59986 -110.817406)
				(xy 41.80586 -108.023406)
			)
		)
		(polygon
			(pts
				(xy 41.06926 -111.223806) (xy 40.86606 -111.223806) (xy 40.86606 -111.427006) (xy 41.06926 -111.427006)
			)
		)
		(polygon
			(pts
				(xy 40.45966 -111.223806) (xy 40.25646 -111.223806) (xy 40.25646 -111.427006) (xy 40.45966 -111.427006)
			)
		)
		(polygon
			(pts
				(xy 36.45916 -109.585506) (xy 36.25596 -109.585506) (xy 36.25596 -109.788706) (xy 36.45916 -109.788706)
			)
		)
		(polygon
			(pts
				(xy 35.31616 -109.585506) (xy 35.11296 -109.585506) (xy 35.11296 -109.788706) (xy 35.31616 -109.788706)
			)
		)
		(polygon
			(pts
				(xy 36.45916 -108.188506) (xy 36.25596 -108.188506) (xy 36.25596 -108.391706) (xy 36.45916 -108.391706)
			)
		)
	)
	(zone
		(layer "B.Cu")
		(hatch none 0.5)
		(connect_pads
			(clearance 0)
		)
		(min_thickness 0.25)
		(keepout
			(tracks allowed)
			(vias allowed)
			(pads allowed)
			(copperpour allowed)
			(footprints allowed)
		)
		(placement
			(enabled no)
			(sheetname "")
		)
		(fill
			(thermal_gap 0.5)
			(thermal_bridge_width 0.5)
			(island_removal_mode 0)
		)
		(polygon
			(pts
				(xy 440.6138 -114.7826) (xy 442.5442 -114.7826) (xy 442.5442 -116.7892) (xy 440.6138 -116.7892)
			)
		)
	)
	(zone
		(layer "B.Cu")
		(hatch none 0.5)
		(connect_pads
			(clearance 0)
		)
		(min_thickness 0.25)
		(keepout
			(tracks allowed)
			(vias allowed)
			(pads allowed)
			(copperpour allowed)
			(footprints not_allowed)
		)
		(placement
			(enabled no)
			(sheetname "")
		)
		(fill
			(thermal_gap 0.5)
			(thermal_bridge_width 0.5)
			(island_removal_mode 0)
		)
		(polygon
			(pts
				(arc
					(start 307.200046 -244.00002)
					(mid 300.20006 -237.000034)
					(end 293.200074 -244.00002)
				)
				(arc
					(start 293.200074 -250.000008)
					(mid 300.20006 -256.999994)
					(end 307.200046 -250.000008)
				)
			)
		)
	)
	(zone
		(layer "B.Cu")
		(hatch none 0.5)
		(connect_pads
			(clearance 0)
		)
		(min_thickness 0.25)
		(keepout
			(tracks not_allowed)
			(vias allowed)
			(pads allowed)
			(copperpour not_allowed)
			(footprints allowed)
		)
		(placement
			(enabled no)
			(sheetname "")
		)
		(fill
			(thermal_gap 0.5)
			(thermal_bridge_width 0.5)
			(island_removal_mode 0)
		)
		(polygon
			(pts
				(arc
					(start 279.236678 -184.145936)
					(mid 278.688038 -184.694576)
					(end 279.236678 -185.243216)
				)
				(arc
					(start 280.636726 -185.243216)
					(mid 281.185366 -184.694576)
					(end 280.636726 -184.145936)
				)
				(arc
					(start 280.174954 -184.145936)
					(mid 280.162991 -184.185278)
					(end 280.158952 -184.2262)
				)
				(arc
					(start 280.158952 -184.5056)
					(mid 280.184926 -184.577599)
					(end 280.2509 -184.616344)
				)
				(arc
					(start 280.2509 -184.616344)
					(mid 281.030452 -184.696125)
					(end 280.250392 -184.770776)
				)
				(xy 280.240232 -184.770776)
				(arc
					(start 280.237946 -184.768744)
					(mid 280.08413 -184.693198)
					(end 280.008584 -184.539382)
				)
				(xy 280.006552 -184.537096) (xy 280.006552 -184.194704)
				(arc
					(start 280.008076 -184.19318)
					(mid 280.011101 -184.169431)
					(end 280.015696 -184.145936)
				)
				(arc
					(start 279.873202 -184.145936)
					(mid 279.868417 -184.18594)
					(end 279.866852 -184.2262)
				)
				(xy 279.866852 -184.537096)
				(arc
					(start 279.86482 -184.539382)
					(mid 279.789274 -184.693198)
					(end 279.635458 -184.768744)
				)
				(xy 279.633172 -184.770776)
				(arc
					(start 279.623012 -184.770776)
					(mid 278.842952 -184.696125)
					(end 279.622504 -184.616344)
				)
				(arc
					(start 279.622504 -184.616344)
					(mid 279.688409 -184.577541)
					(end 279.714452 -184.5056)
				)
				(xy 279.714452 -184.194704) (xy 279.715214 -184.193942) (xy 279.719278 -184.145936)
			)
		)
	)
	(zone
		(layer "B.Cu")
		(hatch none 0.5)
		(connect_pads
			(clearance 0)
		)
		(min_thickness 0.25)
		(keepout
			(tracks allowed)
			(vias allowed)
			(pads allowed)
			(copperpour allowed)
			(footprints not_allowed)
		)
		(placement
			(enabled no)
			(sheetname "")
		)
		(fill
			(thermal_gap 0.5)
			(thermal_bridge_width 0.5)
			(island_removal_mode 0)
		)
		(polygon
			(pts
				(xy 126.299976 -380.000002) (xy 126.299976 -358.000046) (xy 72.300084 -358.000046) (xy 72.300084 -380.000002)
			)
		)
	)
	(zone
		(layer "B.Cu")
		(hatch none 0.5)
		(connect_pads
			(clearance 0)
		)
		(min_thickness 0.25)
		(keepout
			(tracks allowed)
			(vias allowed)
			(pads allowed)
			(copperpour allowed)
			(footprints allowed)
		)
		(placement
			(enabled no)
			(sheetname "")
		)
		(fill
			(thermal_gap 0.5)
			(thermal_bridge_width 0.5)
			(island_removal_mode 0)
		)
		(polygon
			(pts
				(xy 444.71082 -224.404936) (xy 444.71082 -222.254064) (xy 452.876158 -222.254064) (xy 452.876158 -224.404936)
			)
		)
	)
	(zone
		(layer "B.Cu")
		(hatch none 0.5)
		(connect_pads
			(clearance 0)
		)
		(min_thickness 0.25)
		(keepout
			(tracks allowed)
			(vias allowed)
			(pads allowed)
			(copperpour allowed)
			(footprints not_allowed)
		)
		(placement
			(enabled no)
			(sheetname "")
		)
		(fill
			(thermal_gap 0.5)
			(thermal_bridge_width 0.5)
			(island_removal_mode 0)
		)
		(polygon
			(pts
				(arc
					(start 154.606498 -173.629574)
					(mid 152.920779 -175.974312)
					(end 152.32507 -178.799998)
				)
				(arc
					(start 152.32507 -184.799986)
					(mid 152.92077 -187.6258)
					(end 154.606498 -189.970664)
				)
				(arc
					(start 154.606498 -189.970664)
					(mid 127.825209 -209.799909)
					(end 101.04374 -189.970664)
				)
				(arc
					(start 101.04374 -189.970664)
					(mid 102.729365 -187.625777)
					(end 103.324914 -184.799986)
				)
				(arc
					(start 103.324914 -178.799998)
					(mid 102.729286 -175.974348)
					(end 101.04374 -173.629574)
				)
				(arc
					(start 101.04374 -173.629574)
					(mid 127.825209 -153.799906)
					(end 154.606498 -173.629574)
				)
			)
		)
	)
	(zone
		(layer "B.Cu")
		(hatch none 0.5)
		(connect_pads
			(clearance 0)
		)
		(min_thickness 0.25)
		(keepout
			(tracks not_allowed)
			(vias allowed)
			(pads allowed)
			(copperpour not_allowed)
			(footprints allowed)
		)
		(placement
			(enabled no)
			(sheetname "")
		)
		(fill
			(thermal_gap 0.5)
			(thermal_bridge_width 0.5)
			(island_removal_mode 0)
		)
		(polygon
			(pts
				(arc
					(start 278.23668 -221.945708)
					(mid 277.68804 -222.494348)
					(end 278.23668 -223.042988)
				)
				(xy 278.719534 -223.042988) (xy 278.715216 -222.993458) (xy 278.714454 -222.992696)
				(arc
					(start 278.714454 -222.6564)
					(mid 278.689309 -222.595693)
					(end 278.628602 -222.570548)
				)
				(arc
					(start 278.623014 -222.570548)
					(mid 277.842903 -222.494348)
					(end 278.623014 -222.418148)
				)
				(xy 278.660098 -222.418148)
				(arc
					(start 278.662638 -222.420688)
					(mid 278.797004 -222.487998)
					(end 278.864314 -222.622364)
				)
				(xy 278.866854 -222.624904)
				(arc
					(start 278.866854 -222.961962)
					(mid 278.868598 -223.002618)
					(end 278.873712 -223.042988)
				)
				(arc
					(start 279.016206 -223.042988)
					(mid 279.011284 -223.018747)
					(end 279.008078 -222.99422)
				)
				(xy 279.006554 -222.992696) (xy 279.006554 -222.624904)
				(arc
					(start 279.009094 -222.622364)
					(mid 279.076404 -222.487998)
					(end 279.21077 -222.420688)
				)
				(xy 279.21331 -222.418148)
				(arc
					(start 279.250394 -222.418148)
					(mid 280.030505 -222.494348)
					(end 279.250394 -222.570548)
				)
				(arc
					(start 279.244806 -222.570548)
					(mid 279.184099 -222.595693)
					(end 279.158954 -222.6564)
				)
				(arc
					(start 279.158954 -222.9612)
					(mid 279.163419 -223.003013)
					(end 279.17648 -223.042988)
				)
				(arc
					(start 279.636728 -223.042988)
					(mid 280.185368 -222.494348)
					(end 279.636728 -221.945708)
				)
			)
		)
	)
	(zone
		(layer "B.Cu")
		(hatch none 0.5)
		(connect_pads
			(clearance 0)
		)
		(min_thickness 0.25)
		(keepout
			(tracks not_allowed)
			(vias allowed)
			(pads allowed)
			(copperpour not_allowed)
			(footprints allowed)
		)
		(placement
			(enabled no)
			(sheetname "")
		)
		(fill
			(thermal_gap 0.5)
			(thermal_bridge_width 0.5)
			(island_removal_mode 0)
		)
		(polygon
			(pts
				(arc
					(start 214.14867 -77.600302)
					(mid 213.600157 -77.051408)
					(end 213.05139 -77.600048)
				)
				(arc
					(start 213.05139 -78.999842)
					(mid 213.60003 -79.548482)
					(end 214.14867 -78.999842)
				)
				(arc
					(start 214.14867 -78.580234)
					(mid 214.085595 -78.551117)
					(end 214.016844 -78.541118)
				)
				(arc
					(start 213.788244 -78.541118)
					(mid 213.728358 -78.562899)
					(end 213.69655 -78.61808)
				)
				(arc
					(start 213.69655 -78.61808)
					(mid 213.599884 -79.393554)
					(end 213.50478 -78.617826)
				)
				(xy 213.50478 -78.594712)
				(arc
					(start 213.508082 -78.59141)
					(mid 213.587855 -78.433693)
					(end 213.745572 -78.35392)
				)
				(xy 213.748874 -78.350618) (xy 214.056214 -78.350618)
				(arc
					(start 214.058246 -78.35265)
					(mid 214.103954 -78.359503)
					(end 214.14867 -78.371192)
				)
				(arc
					(start 214.14867 -78.265528)
					(mid 214.083273 -78.253147)
					(end 214.016844 -78.249018)
				)
				(xy 213.748874 -78.249018)
				(arc
					(start 213.745572 -78.245716)
					(mid 213.587855 -78.165943)
					(end 213.508082 -78.008226)
				)
				(xy 213.50478 -78.004924)
				(arc
					(start 213.50478 -77.982064)
					(mid 213.59976 -77.206275)
					(end 213.696804 -77.98181)
				)
				(arc
					(start 213.696804 -77.98181)
					(mid 213.728596 -78.036741)
					(end 213.788244 -78.058518)
				)
				(xy 214.056214 -78.058518)
				(arc
					(start 214.057484 -78.059534)
					(mid 214.103254 -78.063679)
					(end 214.14867 -78.07071)
				)
			)
		)
	)
	(zone
		(layer "B.Cu")
		(hatch none 0.5)
		(connect_pads
			(clearance 0)
		)
		(min_thickness 0.25)
		(keepout
			(tracks not_allowed)
			(vias allowed)
			(pads allowed)
			(copperpour not_allowed)
			(footprints allowed)
		)
		(placement
			(enabled no)
			(sheetname "")
		)
		(fill
			(thermal_gap 0.5)
			(thermal_bridge_width 0.5)
			(island_removal_mode 0)
		)
		(polygon
			(pts
				(arc
					(start 279.236678 -180.54574)
					(mid 278.688038 -181.09438)
					(end 279.236678 -181.64302)
				)
				(arc
					(start 280.636726 -181.64302)
					(mid 281.185366 -181.09438)
					(end 280.636726 -180.54574)
				)
				(arc
					(start 280.174954 -180.54574)
					(mid 280.162991 -180.585082)
					(end 280.158952 -180.626004)
				)
				(arc
					(start 280.158952 -180.905404)
					(mid 280.184926 -180.977403)
					(end 280.2509 -181.016148)
				)
				(arc
					(start 280.2509 -181.016148)
					(mid 281.030452 -181.095929)
					(end 280.250392 -181.17058)
				)
				(xy 280.240232 -181.17058)
				(arc
					(start 280.237946 -181.168548)
					(mid 280.08413 -181.093002)
					(end 280.008584 -180.939186)
				)
				(xy 280.006552 -180.9369) (xy 280.006552 -180.594508)
				(arc
					(start 280.008076 -180.592984)
					(mid 280.011101 -180.569235)
					(end 280.015696 -180.54574)
				)
				(arc
					(start 279.873202 -180.54574)
					(mid 279.868417 -180.585744)
					(end 279.866852 -180.626004)
				)
				(xy 279.866852 -180.9369)
				(arc
					(start 279.86482 -180.939186)
					(mid 279.789274 -181.093002)
					(end 279.635458 -181.168548)
				)
				(xy 279.633172 -181.17058)
				(arc
					(start 279.623012 -181.17058)
					(mid 278.842952 -181.095929)
					(end 279.622504 -181.016148)
				)
				(arc
					(start 279.622504 -181.016148)
					(mid 279.688409 -180.977345)
					(end 279.714452 -180.905404)
				)
				(xy 279.714452 -180.594508) (xy 279.715214 -180.593746) (xy 279.719278 -180.54574)
			)
		)
	)
	(zone
		(layer "B.Cu")
		(hatch none 0.5)
		(connect_pads
			(clearance 0)
		)
		(min_thickness 0.25)
		(keepout
			(tracks not_allowed)
			(vias allowed)
			(pads allowed)
			(copperpour not_allowed)
			(footprints allowed)
		)
		(placement
			(enabled no)
			(sheetname "")
		)
		(fill
			(thermal_gap 0.5)
			(thermal_bridge_width 0.5)
			(island_removal_mode 0)
		)
		(polygon
			(pts
				(arc
					(start 278.23668 -135.14578)
					(mid 277.68804 -135.69442)
					(end 278.23668 -136.24306)
				)
				(arc
					(start 279.636728 -136.24306)
					(mid 280.185368 -135.69442)
					(end 279.636728 -135.14578)
				)
				(arc
					(start 279.161494 -135.14578)
					(mid 279.171519 -135.203515)
					(end 279.176988 -135.261858)
				)
				(xy 279.178004 -135.263128)
				(arc
					(start 279.178004 -135.50265)
					(mid 279.199755 -135.563688)
					(end 279.25522 -135.597138)
				)
				(arc
					(start 279.25522 -135.597138)
					(mid 280.030442 -135.695467)
					(end 279.254712 -135.78967)
				)
				(xy 279.235154 -135.78967)
				(arc
					(start 279.231852 -135.786368)
					(mid 279.071649 -135.705525)
					(end 278.990806 -135.545322)
				)
				(xy 278.987504 -135.54202)
				(arc
					(start 278.987504 -135.302498)
					(mid 278.981906 -135.223343)
					(end 278.965152 -135.14578)
				)
				(arc
					(start 278.858218 -135.14578)
					(mid 278.874901 -135.202599)
					(end 278.884126 -135.261096)
				)
				(xy 278.885904 -135.263128) (xy 278.885904 -135.54202)
				(arc
					(start 278.882602 -135.545322)
					(mid 278.801759 -135.705525)
					(end 278.641556 -135.786368)
				)
				(xy 278.638254 -135.78967)
				(arc
					(start 278.618696 -135.78967)
					(mid 277.84297 -135.695467)
					(end 278.618188 -135.597138)
				)
				(arc
					(start 278.618188 -135.597138)
					(mid 278.673591 -135.563638)
					(end 278.695404 -135.50265)
				)
				(arc
					(start 278.695404 -135.302498)
					(mid 278.68244 -135.220103)
					(end 278.644604 -135.14578)
				)
			)
		)
	)
	(zone
		(layer "B.Cu")
		(hatch none 0.5)
		(connect_pads
			(clearance 0)
		)
		(min_thickness 0.25)
		(keepout
			(tracks not_allowed)
			(vias allowed)
			(pads allowed)
			(copperpour not_allowed)
			(footprints allowed)
		)
		(placement
			(enabled no)
			(sheetname "")
		)
		(fill
			(thermal_gap 0.5)
			(thermal_bridge_width 0.5)
			(island_removal_mode 0)
		)
		(polygon
			(pts
				(arc
					(start 278.23668 -142.345664)
					(mid 277.68804 -142.894304)
					(end 278.23668 -143.442944)
				)
				(arc
					(start 279.636728 -143.442944)
					(mid 280.185368 -142.894304)
					(end 279.636728 -142.345664)
				)
				(arc
					(start 279.161494 -142.345664)
					(mid 279.171519 -142.403399)
					(end 279.176988 -142.461742)
				)
				(xy 279.178004 -142.463012)
				(arc
					(start 279.178004 -142.702534)
					(mid 279.199755 -142.763572)
					(end 279.25522 -142.797022)
				)
				(arc
					(start 279.25522 -142.797022)
					(mid 280.030442 -142.895351)
					(end 279.254712 -142.989554)
				)
				(xy 279.235154 -142.989554)
				(arc
					(start 279.231852 -142.986252)
					(mid 279.071649 -142.905409)
					(end 278.990806 -142.745206)
				)
				(xy 278.987504 -142.741904)
				(arc
					(start 278.987504 -142.502382)
					(mid 278.981906 -142.423227)
					(end 278.965152 -142.345664)
				)
				(arc
					(start 278.858218 -142.345664)
					(mid 278.874901 -142.402483)
					(end 278.884126 -142.46098)
				)
				(xy 278.885904 -142.463012) (xy 278.885904 -142.741904)
				(arc
					(start 278.882602 -142.745206)
					(mid 278.801759 -142.905409)
					(end 278.641556 -142.986252)
				)
				(xy 278.638254 -142.989554)
				(arc
					(start 278.618696 -142.989554)
					(mid 277.84297 -142.895351)
					(end 278.618188 -142.797022)
				)
				(arc
					(start 278.618188 -142.797022)
					(mid 278.673591 -142.763522)
					(end 278.695404 -142.702534)
				)
				(arc
					(start 278.695404 -142.502382)
					(mid 278.68244 -142.419987)
					(end 278.644604 -142.345664)
				)
			)
		)
	)
	(zone
		(net "P3V3_STBY_VBST_RR")
		(layer "B.Cu")
		(hatch none 0.5)
		(connect_pads
			(clearance 0.5)
		)
		(min_thickness 0.25)
		(fill yes
			(thermal_gap 0.5)
			(thermal_bridge_width 0.5)
			(island_removal_mode 0)
		)
		(polygon
			(pts
				(xy 250.063 -284.734) (xy 249.428 -285.369) (xy 249.428 -286.512) (xy 249.555 -286.639) (xy 251.206 -286.639)
				(xy 251.46 -286.385) (xy 251.46 -285.369) (xy 250.825 -284.734)
			)
		)
		(polygon
			(pts
				(xy 250.5456 -285.6738) (xy 250.3424 -285.6738) (xy 250.3424 -285.877) (xy 250.5456 -285.877)
			)
		)
		(polygon
			(pts
				(xy 250.952 -285.2166) (xy 250.7488 -285.2166) (xy 250.7488 -285.4198) (xy 250.952 -285.4198)
			)
		)
		(polygon
			(pts
				(xy 250.3932 -285.2166) (xy 250.19 -285.2166) (xy 250.19 -285.4198) (xy 250.3932 -285.4198)
			)
		)
	)
	(zone
		(net "GND")
		(layer "B.Cu")
		(hatch none 0.5)
		(connect_pads
			(clearance 0.5)
		)
		(min_thickness 0.25)
		(fill yes
			(thermal_gap 0.5)
			(thermal_bridge_width 0.5)
			(island_removal_mode 0)
		)
		(polygon
			(pts
				(xy 460.720186 -118.289578) (xy 460.466186 -118.543578) (xy 460.466186 -120.321578) (xy 460.847186 -120.702578)
				(xy 466.054186 -120.702578) (xy 466.308186 -120.448578) (xy 466.308186 -118.771924) (xy 465.82584 -118.289578)
			)
		)
	)
	(zone
		(layer "B.Cu")
		(hatch none 0.5)
		(connect_pads
			(clearance 0)
		)
		(min_thickness 0.25)
		(keepout
			(tracks not_allowed)
			(vias allowed)
			(pads allowed)
			(copperpour not_allowed)
			(footprints allowed)
		)
		(placement
			(enabled no)
			(sheetname "")
		)
		(fill
			(thermal_gap 0.5)
			(thermal_bridge_width 0.5)
			(island_removal_mode 0)
		)
		(polygon
			(pts
				(arc
					(start 279.236678 -238.145828)
					(mid 278.688038 -238.694468)
					(end 279.236678 -239.243108)
				)
				(arc
					(start 280.636726 -239.243108)
					(mid 281.185366 -238.694468)
					(end 280.636726 -238.145828)
				)
				(arc
					(start 280.141934 -238.145828)
					(mid 280.152755 -238.207834)
					(end 280.15819 -238.270542)
				)
				(xy 280.158952 -238.271304)
				(arc
					(start 280.158952 -238.4806)
					(mid 280.184564 -238.560657)
					(end 280.251916 -238.610902)
				)
				(arc
					(start 280.251916 -238.610902)
					(mid 281.030464 -238.700171)
					(end 280.24963 -238.766858)
				)
				(arc
					(start 280.24963 -238.766858)
					(mid 280.086751 -238.680866)
					(end 280.008584 -238.514128)
				)
				(xy 280.006552 -238.512096)
				(arc
					(start 280.006552 -238.3028)
					(mid 280.001026 -238.223564)
					(end 279.984708 -238.145828)
				)
				(arc
					(start 279.837896 -238.145828)
					(mid 279.856272 -238.206921)
					(end 279.865582 -238.270034)
				)
				(xy 279.866852 -238.271304) (xy 279.866852 -238.512096)
				(arc
					(start 279.86482 -238.514128)
					(mid 279.786575 -238.680791)
					(end 279.623774 -238.766858)
				)
				(arc
					(start 279.623774 -238.766858)
					(mid 278.842913 -238.700172)
					(end 279.621488 -238.610902)
				)
				(arc
					(start 279.621488 -238.610902)
					(mid 279.688773 -238.560609)
					(end 279.714452 -238.4806)
				)
				(arc
					(start 279.714452 -238.3028)
					(mid 279.702455 -238.220871)
					(end 279.667462 -238.145828)
				)
			)
		)
	)
	(zone
		(layer "B.Cu")
		(hatch none 0.5)
		(connect_pads
			(clearance 0)
		)
		(min_thickness 0.25)
		(keepout
			(tracks allowed)
			(vias allowed)
			(pads allowed)
			(copperpour allowed)
			(footprints not_allowed)
		)
		(placement
			(enabled no)
			(sheetname "")
		)
		(fill
			(thermal_gap 0.5)
			(thermal_bridge_width 0.5)
			(island_removal_mode 0)
		)
		(polygon
			(pts
				(arc
					(start 251.199904 -175.800004)
					(mid 244.199918 -168.800018)
					(end 237.199932 -175.800004)
				)
				(arc
					(start 237.199932 -181.799992)
					(mid 244.199918 -188.799978)
					(end 251.199904 -181.799992)
				)
			)
		)
	)
	(zone
		(layer "B.Cu")
		(hatch none 0.5)
		(connect_pads
			(clearance 0)
		)
		(min_thickness 0.25)
		(keepout
			(tracks not_allowed)
			(vias allowed)
			(pads allowed)
			(copperpour not_allowed)
			(footprints allowed)
		)
		(placement
			(enabled no)
			(sheetname "")
		)
		(fill
			(thermal_gap 0.5)
			(thermal_bridge_width 0.5)
			(island_removal_mode 0)
		)
		(polygon
			(pts
				(arc
					(start 279.236678 -187.745878)
					(mid 278.688038 -188.294518)
					(end 279.236678 -188.843158)
				)
				(arc
					(start 280.636726 -188.843158)
					(mid 281.185366 -188.294518)
					(end 280.636726 -187.745878)
				)
				(arc
					(start 280.141934 -187.745878)
					(mid 280.152755 -187.807884)
					(end 280.15819 -187.870592)
				)
				(xy 280.158952 -187.871354)
				(arc
					(start 280.158952 -188.08065)
					(mid 280.184564 -188.160707)
					(end 280.251916 -188.210952)
				)
				(arc
					(start 280.251916 -188.210952)
					(mid 281.030464 -188.300221)
					(end 280.24963 -188.366908)
				)
				(arc
					(start 280.24963 -188.366908)
					(mid 280.086751 -188.280916)
					(end 280.008584 -188.114178)
				)
				(xy 280.006552 -188.112146)
				(arc
					(start 280.006552 -187.90285)
					(mid 280.001026 -187.823614)
					(end 279.984708 -187.745878)
				)
				(arc
					(start 279.837896 -187.745878)
					(mid 279.856272 -187.806971)
					(end 279.865582 -187.870084)
				)
				(xy 279.866852 -187.871354) (xy 279.866852 -188.112146)
				(arc
					(start 279.86482 -188.114178)
					(mid 279.786575 -188.280841)
					(end 279.623774 -188.366908)
				)
				(arc
					(start 279.623774 -188.366908)
					(mid 278.842913 -188.300222)
					(end 279.621488 -188.210952)
				)
				(arc
					(start 279.621488 -188.210952)
					(mid 279.688773 -188.160659)
					(end 279.714452 -188.08065)
				)
				(arc
					(start 279.714452 -187.90285)
					(mid 279.702455 -187.820921)
					(end 279.667462 -187.745878)
				)
			)
		)
	)
	(zone
		(layer "B.Cu")
		(hatch none 0.5)
		(connect_pads
			(clearance 0)
		)
		(min_thickness 0.25)
		(keepout
			(tracks allowed)
			(vias allowed)
			(pads allowed)
			(copperpour allowed)
			(footprints allowed)
		)
		(placement
			(enabled no)
			(sheetname "")
		)
		(fill
			(thermal_gap 0.5)
			(thermal_bridge_width 0.5)
			(island_removal_mode 0)
		)
		(polygon
			(pts
				(xy 17.8054 -225.4504) (xy 19.685 -225.4504) (xy 19.685 -227.1014) (xy 17.8054 -227.1014)
			)
		)
	)
	(zone
		(layer "B.Cu")
		(hatch none 0.5)
		(connect_pads
			(clearance 0)
		)
		(min_thickness 0.25)
		(keepout
			(tracks not_allowed)
			(vias allowed)
			(pads allowed)
			(copperpour not_allowed)
			(footprints allowed)
		)
		(placement
			(enabled no)
			(sheetname "")
		)
		(fill
			(thermal_gap 0.5)
			(thermal_bridge_width 0.5)
			(island_removal_mode 0)
		)
		(polygon
			(pts
				(arc
					(start 192.520824 -244.419374)
					(mid 192.035684 -243.934234)
					(end 191.550544 -244.419374)
				)
				(arc
					(start 191.550544 -245.56212)
					(mid 192.035557 -246.047514)
					(end 192.520824 -245.562374)
				)
				(xy 192.520824 -245.213124)
				(arc
					(start 192.179956 -245.213124)
					(mid 192.131822 -245.233062)
					(end 192.111884 -245.281196)
				)
				(arc
					(start 192.111884 -245.30685)
					(mid 192.035684 -245.829018)
					(end 191.959484 -245.30685)
				)
				(xy 191.959484 -245.2497)
				(arc
					(start 191.962278 -245.246906)
					(mid 192.024136 -245.125376)
					(end 192.145666 -245.063518)
				)
				(xy 192.14846 -245.060724) (xy 192.520824 -245.060724) (xy 192.520824 -244.921024) (xy 192.138808 -244.921024)
				(arc
					(start 192.136014 -244.91823)
					(mid 192.021222 -244.859286)
					(end 191.962278 -244.744494)
				)
				(xy 191.959484 -244.7417)
				(arc
					(start 191.959484 -244.674898)
					(mid 192.035684 -244.15273)
					(end 192.111884 -244.674898)
				)
				(arc
					(start 192.111884 -244.710204)
					(mid 192.128995 -244.751513)
					(end 192.170304 -244.768624)
				)
				(xy 192.520824 -244.768624)
			)
		)
	)
	(zone
		(layer "B.Cu")
		(hatch none 0.5)
		(connect_pads
			(clearance 0)
		)
		(min_thickness 0.25)
		(keepout
			(tracks not_allowed)
			(vias allowed)
			(pads allowed)
			(copperpour not_allowed)
			(footprints allowed)
		)
		(placement
			(enabled no)
			(sheetname "")
		)
		(fill
			(thermal_gap 0.5)
			(thermal_bridge_width 0.5)
			(island_removal_mode 0)
		)
		(polygon
			(pts
				(arc
					(start 103.324914 -63.799974)
					(mid 96.324928 -56.799988)
					(end 89.324942 -63.799974)
				)
				(arc
					(start 89.324942 -69.799962)
					(mid 96.324928 -76.799948)
					(end 103.324914 -69.799962)
				)
			)
		)
	)
	(zone
		(net "P3V3_STBY_SW")
		(layer "B.Cu")
		(hatch none 0.5)
		(connect_pads
			(clearance 0.5)
		)
		(min_thickness 0.25)
		(fill yes
			(thermal_gap 0.5)
			(thermal_bridge_width 0.5)
			(island_removal_mode 0)
		)
		(polygon
			(pts
				(xy 248.92 -277.114) (xy 248.285 -277.749) (xy 248.285 -282.194) (xy 248.793 -282.702) (xy 253.238 -282.702)
				(xy 253.365 -282.575) (xy 253.365 -281.432) (xy 252.222 -280.289) (xy 252.222 -278.257) (xy 251.079 -277.114)
			)
		)
	)
	(zone
		(net "GND")
		(layer "B.Cu")
		(hatch none 0.5)
		(connect_pads
			(clearance 0.5)
		)
		(min_thickness 0.25)
		(fill yes
			(thermal_gap 0.5)
			(thermal_bridge_width 0.5)
			(island_removal_mode 0)
		)
		(polygon
			(pts
				(xy 349.00362 -60.027312) (xy 351.203768 -56.63946)
				(arc
					(start 351.203768 -52.104798)
					(mid 351.168634 -49.578505)
					(end 352.62439 -47.513494)
				)
				(arc
					(start 352.62439 -47.513494)
					(mid 353.033475 -45.896246)
					(end 354.005388 -44.540424)
				)
				(arc
					(start 354.005388 -43.52417)
					(mid 353.343332 -42.325263)
					(end 353.114102 -40.975026)
				)
				(arc
					(start 353.114102 -38.435026)
					(mid 353.138234 -37.991335)
					(end 353.210368 -37.552884)
				)
				(xy 353.210368 -37.528246) (xy 353.003866 -37.321744)
				(arc
					(start 352.684334 -37.321744)
					(mid 352.331644 -37.659962)
					(end 351.94113 -37.953696)
				)
				(xy 348.944184 -57.480454) (xy 348.342458 -59.366658) (xy 348.342458 -59.728608) (xy 348.641162 -60.027312)
			)
		)
	)
	(zone
		(layer "B.Cu")
		(hatch none 0.5)
		(connect_pads
			(clearance 0)
		)
		(min_thickness 0.25)
		(keepout
			(tracks allowed)
			(vias allowed)
			(pads allowed)
			(copperpour allowed)
			(footprints not_allowed)
		)
		(placement
			(enabled no)
			(sheetname "")
		)
		(fill
			(thermal_gap 0.5)
			(thermal_bridge_width 0.5)
			(island_removal_mode 0)
		)
		(polygon
			(pts
				(arc
					(start 307.200046 -94.000066)
					(mid 300.20006 -87.00008)
					(end 293.200074 -94.000066)
				)
				(arc
					(start 293.200074 -100.000054)
					(mid 300.20006 -107.00004)
					(end 307.200046 -100.000054)
				)
			)
		)
	)
	(zone
		(net "GND")
		(layer "B.Cu")
		(hatch none 0.5)
		(connect_pads
			(clearance 0.5)
		)
		(min_thickness 0.25)
		(fill yes
			(thermal_gap 0.5)
			(thermal_bridge_width 0.5)
			(island_removal_mode 0)
		)
		(polygon
			(pts
				(xy 238.887 -286.385) (xy 238.633 -286.639) (xy 238.633 -288.417) (xy 239.141 -288.925) (xy 243.967 -288.925)
				(xy 244.856 -288.036) (xy 244.856 -286.639) (xy 244.602 -286.385)
			)
		)
	)
	(zone
		(layer "B.Cu")
		(hatch none 0.5)
		(connect_pads
			(clearance 0)
		)
		(min_thickness 0.25)
		(keepout
			(tracks allowed)
			(vias allowed)
			(pads allowed)
			(copperpour allowed)
			(footprints not_allowed)
		)
		(placement
			(enabled no)
			(sheetname "")
		)
		(fill
			(thermal_gap 0.5)
			(thermal_bridge_width 0.5)
			(island_removal_mode 0)
		)
		(polygon
			(pts
				(arc
					(start 141.824964 -181.799992)
					(mid 127.824992 -167.80002)
					(end 113.82502 -181.799992)
				)
				(arc
					(start 113.82502 -181.799992)
					(mid 127.824992 -195.799964)
					(end 141.824964 -181.799992)
				)
			)
		)
	)
	(zone
		(layer "B.Cu")
		(hatch none 0.5)
		(connect_pads
			(clearance 0)
		)
		(min_thickness 0.25)
		(keepout
			(tracks not_allowed)
			(vias allowed)
			(pads allowed)
			(copperpour not_allowed)
			(footprints allowed)
		)
		(placement
			(enabled no)
			(sheetname "")
		)
		(fill
			(thermal_gap 0.5)
			(thermal_bridge_width 0.5)
			(island_removal_mode 0)
		)
		(polygon
			(pts
				(arc
					(start 463.674968 -293.800022)
					(mid 456.674982 -286.800036)
					(end 449.674996 -293.800022)
				)
				(arc
					(start 449.674996 -299.80001)
					(mid 456.674982 -306.799996)
					(end 463.674968 -299.80001)
				)
			)
		)
	)
	(zone
		(net "GND")
		(layer "B.Cu")
		(hatch none 0.5)
		(connect_pads
			(clearance 0.5)
		)
		(min_thickness 0.25)
		(fill yes
			(thermal_gap 0.5)
			(thermal_bridge_width 0.5)
			(island_removal_mode 0)
		)
		(polygon
			(pts
				(xy 436.8038 -111.516922) (xy 436.624984 -111.695738) (xy 436.624984 -117.400578) (xy 436.893208 -117.668802)
				(xy 436.893208 -118.5164) (xy 437.377586 -119.000778) (xy 438.231788 -119.000778) (xy 438.241186 -119.010176)
				(xy 439.926984 -117.324378) (xy 439.926984 -111.698532) (xy 439.745374 -111.516922)
			)
		)
	)
	(zone
		(layer "B.Cu")
		(hatch none 0.5)
		(connect_pads
			(clearance 0)
		)
		(min_thickness 0.25)
		(keepout
			(tracks not_allowed)
			(vias allowed)
			(pads allowed)
			(copperpour not_allowed)
			(footprints allowed)
		)
		(placement
			(enabled no)
			(sheetname "")
		)
		(fill
			(thermal_gap 0.5)
			(thermal_bridge_width 0.5)
			(island_removal_mode 0)
		)
		(polygon
			(pts
				(arc
					(start 196.799962 -94.000066)
					(mid 189.799976 -87.00008)
					(end 182.79999 -94.000066)
				)
				(arc
					(start 182.79999 -100.000054)
					(mid 189.799976 -107.00004)
					(end 196.799962 -100.000054)
				)
			)
		)
	)
	(zone
		(layer "B.Cu")
		(hatch none 0.5)
		(connect_pads
			(clearance 0)
		)
		(min_thickness 0.25)
		(keepout
			(tracks not_allowed)
			(vias allowed)
			(pads allowed)
			(copperpour not_allowed)
			(footprints allowed)
		)
		(placement
			(enabled no)
			(sheetname "")
		)
		(fill
			(thermal_gap 0.5)
			(thermal_bridge_width 0.5)
			(island_removal_mode 0)
		)
		(polygon
			(pts
				(arc
					(start 282.83662 -144.145762)
					(mid 282.28798 -144.694402)
					(end 282.83662 -145.243042)
				)
				(arc
					(start 283.244544 -145.243042)
					(mid 283.282317 -145.168699)
					(end 283.295344 -145.086324)
				)
				(arc
					(start 283.295344 -144.886172)
					(mid 283.273593 -144.825134)
					(end 283.218128 -144.791684)
				)
				(arc
					(start 283.218128 -144.791684)
					(mid 282.442906 -144.693355)
					(end 283.218636 -144.599152)
				)
				(xy 283.238194 -144.599152)
				(arc
					(start 283.241496 -144.602454)
					(mid 283.401699 -144.683297)
					(end 283.482542 -144.8435)
				)
				(xy 283.485844 -144.846802) (xy 283.485844 -145.125694)
				(arc
					(start 283.484066 -145.127726)
					(mid 283.474865 -145.186228)
					(end 283.458158 -145.243042)
				)
				(arc
					(start 283.565092 -145.243042)
					(mid 283.581846 -145.165479)
					(end 283.587444 -145.086324)
				)
				(xy 283.587444 -144.846802)
				(arc
					(start 283.590746 -144.8435)
					(mid 283.671589 -144.683297)
					(end 283.831792 -144.602454)
				)
				(xy 283.835094 -144.599152)
				(arc
					(start 283.854652 -144.599152)
					(mid 284.630378 -144.693355)
					(end 283.85516 -144.791684)
				)
				(arc
					(start 283.85516 -144.791684)
					(mid 283.799757 -144.825184)
					(end 283.777944 -144.886172)
				)
				(xy 283.777944 -145.125694)
				(arc
					(start 283.776928 -145.126964)
					(mid 283.771445 -145.185305)
					(end 283.761434 -145.243042)
				)
				(arc
					(start 284.236668 -145.243042)
					(mid 284.785308 -144.694402)
					(end 284.236668 -144.145762)
				)
			)
		)
	)
	(zone
		(net "GND")
		(layer "B.Cu")
		(hatch none 0.5)
		(connect_pads
			(clearance 0.5)
		)
		(min_thickness 0.25)
		(fill yes
			(thermal_gap 0.5)
			(thermal_bridge_width 0.5)
			(island_removal_mode 0)
		)
		(polygon
			(pts
				(xy 250.19 -287.02) (xy 249.047 -288.163) (xy 249.047 -292.307772) (xy 249.347228 -292.608) (xy 250.825 -292.608)
				(xy 251.46 -291.973) (xy 251.46 -288.036) (xy 251.841 -287.655) (xy 251.841 -287.147) (xy 251.714 -287.02)
			)
		)
		(polygon
			(pts
				(xy 251.3076 -287.4772) (xy 251.1044 -287.4772) (xy 251.1044 -287.6804) (xy 251.3076 -287.6804)
			)
		)
	)
	(zone
		(layer "B.Cu")
		(hatch none 0.5)
		(connect_pads
			(clearance 0)
		)
		(min_thickness 0.25)
		(keepout
			(tracks not_allowed)
			(vias allowed)
			(pads allowed)
			(copperpour not_allowed)
			(footprints allowed)
		)
		(placement
			(enabled no)
			(sheetname "")
		)
		(fill
			(thermal_gap 0.5)
			(thermal_bridge_width 0.5)
			(island_removal_mode 0)
		)
		(polygon
			(pts
				(arc
					(start 279.236678 -191.34582)
					(mid 278.688038 -191.89446)
					(end 279.236678 -192.4431)
				)
				(arc
					(start 280.636726 -192.4431)
					(mid 281.185366 -191.89446)
					(end 280.636726 -191.34582)
				)
				(arc
					(start 280.141934 -191.34582)
					(mid 280.152755 -191.407826)
					(end 280.15819 -191.470534)
				)
				(xy 280.158952 -191.471296)
				(arc
					(start 280.158952 -191.680592)
					(mid 280.184564 -191.760649)
					(end 280.251916 -191.810894)
				)
				(arc
					(start 280.251916 -191.810894)
					(mid 281.030464 -191.900163)
					(end 280.24963 -191.96685)
				)
				(arc
					(start 280.24963 -191.96685)
					(mid 280.086751 -191.880858)
					(end 280.008584 -191.71412)
				)
				(xy 280.006552 -191.712088)
				(arc
					(start 280.006552 -191.502792)
					(mid 280.001026 -191.423556)
					(end 279.984708 -191.34582)
				)
				(arc
					(start 279.837896 -191.34582)
					(mid 279.856272 -191.406913)
					(end 279.865582 -191.470026)
				)
				(xy 279.866852 -191.471296) (xy 279.866852 -191.712088)
				(arc
					(start 279.86482 -191.71412)
					(mid 279.786575 -191.880783)
					(end 279.623774 -191.96685)
				)
				(arc
					(start 279.623774 -191.96685)
					(mid 278.842913 -191.900164)
					(end 279.621488 -191.810894)
				)
				(arc
					(start 279.621488 -191.810894)
					(mid 279.688773 -191.760601)
					(end 279.714452 -191.680592)
				)
				(arc
					(start 279.714452 -191.502792)
					(mid 279.702455 -191.420863)
					(end 279.667462 -191.34582)
				)
			)
		)
	)
	(zone
		(layer "B.Cu")
		(hatch none 0.5)
		(connect_pads
			(clearance 0)
		)
		(min_thickness 0.25)
		(keepout
			(tracks allowed)
			(vias allowed)
			(pads allowed)
			(copperpour allowed)
			(footprints allowed)
		)
		(placement
			(enabled no)
			(sheetname "")
		)
		(fill
			(thermal_gap 0.5)
			(thermal_bridge_width 0.5)
			(island_removal_mode 0)
		)
		(polygon
			(pts
				(xy 254.4318 -283.3624) (xy 255.1938 -283.3624) (xy 255.1938 -284.5816) (xy 254.4318 -284.5816)
			)
		)
	)
	(zone
		(layer "B.Cu")
		(hatch none 0.5)
		(connect_pads
			(clearance 0)
		)
		(min_thickness 0.25)
		(keepout
			(tracks not_allowed)
			(vias allowed)
			(pads allowed)
			(copperpour not_allowed)
			(footprints allowed)
		)
		(placement
			(enabled no)
			(sheetname "")
		)
		(fill
			(thermal_gap 0.5)
			(thermal_bridge_width 0.5)
			(island_removal_mode 0)
		)
		(polygon
			(pts
				(arc
					(start 278.23668 -218.345766)
					(mid 277.68804 -218.894406)
					(end 278.23668 -219.443046)
				)
				(arc
					(start 278.724106 -219.443046)
					(mid 278.718409 -219.402288)
					(end 278.715216 -219.361258)
				)
				(xy 278.714454 -219.360496)
				(arc
					(start 278.714454 -219.1004)
					(mid 278.68872 -219.022824)
					(end 278.621744 -218.97594)
				)
				(arc
					(start 278.621744 -218.97594)
					(mid 277.843051 -218.889744)
					(end 278.623522 -218.821)
				)
				(arc
					(start 278.623522 -218.821)
					(mid 278.786023 -218.902846)
					(end 278.864822 -219.066872)
				)
				(xy 278.866854 -219.068904)
				(arc
					(start 278.866854 -219.329)
					(mid 278.870068 -219.386372)
					(end 278.879554 -219.443046)
				)
				(arc
					(start 279.023826 -219.443046)
					(mid 279.013753 -219.40296)
					(end 279.008078 -219.36202)
				)
				(xy 279.006554 -219.360496) (xy 279.006554 -219.068904)
				(arc
					(start 279.008586 -219.066872)
					(mid 279.087334 -218.902796)
					(end 279.249886 -218.821)
				)
				(arc
					(start 279.249886 -218.821)
					(mid 280.030401 -218.889743)
					(end 279.251664 -218.97594)
				)
				(arc
					(start 279.251664 -218.97594)
					(mid 279.184629 -219.022781)
					(end 279.158954 -219.1004)
				)
				(arc
					(start 279.158954 -219.329)
					(mid 279.166628 -219.387998)
					(end 279.18918 -219.443046)
				)
				(arc
					(start 279.636728 -219.443046)
					(mid 280.185368 -218.894406)
					(end 279.636728 -218.345766)
				)
			)
		)
	)
	(zone
		(layer "B.Cu")
		(hatch none 0.5)
		(connect_pads
			(clearance 0)
		)
		(min_thickness 0.25)
		(keepout
			(tracks not_allowed)
			(vias allowed)
			(pads allowed)
			(copperpour not_allowed)
			(footprints allowed)
		)
		(placement
			(enabled no)
			(sheetname "")
		)
		(fill
			(thermal_gap 0.5)
			(thermal_bridge_width 0.5)
			(island_removal_mode 0)
		)
		(polygon
			(pts
				(arc
					(start 307.200046 -244.00002)
					(mid 300.20006 -237.000034)
					(end 293.200074 -244.00002)
				)
				(arc
					(start 293.200074 -250.000008)
					(mid 300.20006 -256.999994)
					(end 307.200046 -250.000008)
				)
			)
		)
	)
	(zone
		(layer "B.Cu")
		(hatch none 0.5)
		(connect_pads
			(clearance 0)
		)
		(min_thickness 0.25)
		(keepout
			(tracks not_allowed)
			(vias allowed)
			(pads allowed)
			(copperpour not_allowed)
			(footprints allowed)
		)
		(placement
			(enabled no)
			(sheetname "")
		)
		(fill
			(thermal_gap 0.5)
			(thermal_bridge_width 0.5)
			(island_removal_mode 0)
		)
		(polygon
			(pts
				(arc
					(start 192.520824 -129.419604)
					(mid 192.035811 -128.93421)
					(end 191.550544 -129.41935)
				)
				(arc
					(start 191.550544 -130.56235)
					(mid 192.035684 -131.04749)
					(end 192.520824 -130.56235)
				)
				(xy 192.520824 -130.2131)
				(arc
					(start 192.179956 -130.2131)
					(mid 192.131822 -130.233038)
					(end 192.111884 -130.281172)
				)
				(arc
					(start 192.111884 -130.306826)
					(mid 192.035684 -130.828994)
					(end 191.959484 -130.306826)
				)
				(xy 191.959484 -130.249676)
				(arc
					(start 191.962278 -130.246882)
					(mid 192.024136 -130.125352)
					(end 192.145666 -130.063494)
				)
				(xy 192.14846 -130.0607) (xy 192.520824 -130.0607) (xy 192.520824 -129.921) (xy 192.138808 -129.921)
				(arc
					(start 192.136014 -129.918206)
					(mid 192.021222 -129.859262)
					(end 191.962278 -129.74447)
				)
				(xy 191.959484 -129.741676)
				(arc
					(start 191.959484 -129.674874)
					(mid 192.035684 -129.152706)
					(end 192.111884 -129.674874)
				)
				(arc
					(start 192.111884 -129.71018)
					(mid 192.128995 -129.751489)
					(end 192.170304 -129.7686)
				)
				(xy 192.520824 -129.7686)
			)
		)
	)
	(zone
		(net "AGND_P3V3_STBY")
		(layer "B.Cu")
		(hatch none 0.5)
		(connect_pads
			(clearance 0.5)
		)
		(min_thickness 0.25)
		(fill yes
			(thermal_gap 0.5)
			(thermal_bridge_width 0.5)
			(island_removal_mode 0)
		)
		(polygon
			(pts
				(xy 257.188716 -279.716484) (xy 255.4986 -281.4066) (xy 255.4986 -281.6352) (xy 255.6002 -281.7368)
				(xy 256.474468 -281.7368) (xy 257.617722 -280.593546) (xy 259.005324 -280.593546) (xy 259.437378 -281.0256)
				(xy 262.2042 -281.0256) (xy 262.3312 -280.8986) (xy 262.3312 -280.3398) (xy 262.2042 -280.2128)
				(xy 261.380478 -280.2128) (xy 261.339838 -280.17216) (xy 259.617972 -280.17216) (xy 259.162296 -279.716484)
			)
		)
	)
	(zone
		(net "GND")
		(layer "B.Cu")
		(hatch none 0.5)
		(connect_pads
			(clearance 0.5)
		)
		(min_thickness 0.25)
		(fill yes
			(thermal_gap 0.5)
			(thermal_bridge_width 0.5)
			(island_removal_mode 0)
		)
		(polygon
			(pts
				(arc
					(start 319.17894 -91.742514)
					(mid 319.37791 -91.489644)
					(end 319.596262 -91.25331)
				)
				(arc
					(start 322.587874 -88.261698)
					(mid 323.906467 -87.380579)
					(end 325.461884 -87.0712)
				)
				(xy 328.373994 -87.0712) (xy 330.168758 -84.307426) (xy 330.168758 -82.685636)
				(arc
					(start 327.67397 -80.190848)
					(mid 325.930838 -79.519872)
					(end 324.329044 -78.559152)
				)
				(xy 320.807842 -78.559152) (xy 318.519048 -80.847946) (xy 317.677546 -91.202002) (xy 318.218058 -91.742514)
			)
		)
	)
	(zone
		(net "P3V3_STBY_SNB")
		(layer "B.Cu")
		(hatch none 0.5)
		(connect_pads
			(clearance 0.5)
		)
		(min_thickness 0.25)
		(fill yes
			(thermal_gap 0.5)
			(thermal_bridge_width 0.5)
			(island_removal_mode 0)
		)
		(polygon
			(pts
				(xy 245.364 -273.812) (xy 245.11 -274.066) (xy 245.11 -275.717) (xy 245.491 -276.098) (xy 247.523 -276.098)
				(xy 247.904 -275.717) (xy 247.904 -274.066) (xy 247.65 -273.812)
			)
		)
		(polygon
			(pts
				(xy 247.3706 -275.6662) (xy 247.1674 -275.6662) (xy 247.1674 -275.8694) (xy 247.3706 -275.8694)
			)
		)
		(polygon
			(pts
				(xy 247.3706 -275.0566) (xy 247.1674 -275.0566) (xy 247.1674 -275.2598) (xy 247.3706 -275.2598)
			)
		)
	)
	(zone
		(layer "B.Cu")
		(hatch none 0.5)
		(connect_pads
			(clearance 0)
		)
		(min_thickness 0.25)
		(keepout
			(tracks allowed)
			(vias allowed)
			(pads allowed)
			(copperpour allowed)
			(footprints not_allowed)
		)
		(placement
			(enabled no)
			(sheetname "")
		)
		(fill
			(thermal_gap 0.5)
			(thermal_bridge_width 0.5)
			(island_removal_mode 0)
		)
		(polygon
			(pts
				(arc
					(start 395.48054 -39.99992)
					(mid 425.175257 -106.80014)
					(end 454.86955 -39.99992)
				)
				(xy 491.450122 -39.99992)
				(arc
					(start 491.450122 -370.000022)
					(mid 491.157229 -370.707127)
					(end 490.450124 -371.00002)
				)
				(arc
					(start 489.450126 -371.00002)
					(mid 488.742856 -371.292823)
					(end 488.449874 -372.000018)
				)
				(arc
					(start 488.449874 -384.999992)
					(mid 488.156981 -385.707097)
					(end 487.449876 -385.99999)
				)
				(arc
					(start 474.749876 -385.99999)
					(mid 474.042771 -385.707097)
					(end 473.749878 -384.999992)
				)
				(arc
					(start 473.749878 -383.29997)
					(mid 473.456985 -382.592865)
					(end 472.74988 -382.299972)
				)
				(arc
					(start 466.25002 -382.299972)
					(mid 465.542915 -382.592865)
					(end 465.250022 -383.29997)
				)
				(arc
					(start 465.250022 -384.999992)
					(mid 464.957129 -385.707097)
					(end 464.250024 -385.99999)
				)
				(arc
					(start 418.69995 -385.99999)
					(mid 417.992845 -385.707097)
					(end 417.699952 -384.999992)
				)
				(arc
					(start 417.699952 -381)
					(mid 417.407059 -380.292895)
					(end 416.699954 -380.000002)
				)
				(xy 417.699952 -380.000002) (xy 417.699952 -358.000046) (xy 363.70006 -358.000046) (xy 363.70006 -380.000002)
				(arc
					(start 364.700058 -380.000002)
					(mid 363.992953 -380.292895)
					(end 363.70006 -381)
				)
				(arc
					(start 363.70006 -384.999992)
					(mid 363.407167 -385.707097)
					(end 362.700062 -385.99999)
				)
				(arc
					(start 317.149988 -385.99999)
					(mid 316.442883 -385.707097)
					(end 316.14999 -384.999992)
				)
				(arc
					(start 316.14999 -383.29997)
					(mid 315.857097 -382.592865)
					(end 315.149992 -382.299972)
				)
				(arc
					(start 308.649878 -382.299972)
					(mid 307.942773 -382.592865)
					(end 307.64988 -383.29997)
				)
				(arc
					(start 307.64988 -384.999992)
					(mid 307.356987 -385.707097)
					(end 306.649882 -385.99999)
				)
				(arc
					(start 280.164286 -385.99999)
					(mid 279.781603 -385.92387)
					(end 279.45715 -385.707128)
				)
				(arc
					(start 277.04288 -383.292858)
					(mid 276.826098 -382.968421)
					(end 276.750018 -382.585722)
				)
				(arc
					(start 276.750018 -361.00004)
					(mid 276.457125 -360.292935)
					(end 275.75002 -360.000042)
				)
				(arc
					(start 273.45005 -360.000042)
					(mid 272.742945 -360.292935)
					(end 272.450052 -361.00004)
				)
				(arc
					(start 272.450052 -382.585722)
					(mid 272.373932 -382.968405)
					(end 272.15719 -383.292858)
				)
				(arc
					(start 269.74292 -385.707128)
					(mid 269.418483 -385.92391)
					(end 269.035784 -385.99999)
				)
				(arc
					(start 253.000002 -385.99999)
					(mid 252.292897 -385.707097)
					(end 252.000004 -384.999992)
				)
				(arc
					(start 252.000004 -381)
					(mid 251.707111 -380.292895)
					(end 251.000006 -380.000002)
				)
				(xy 252.000004 -380.000002) (xy 252.000004 -358.000046) (xy 198.000112 -358.000046) (xy 198.000112 -380.000002)
				(arc
					(start 199.00011 -380.000002)
					(mid 198.293005 -380.292895)
					(end 198.000112 -381)
				)
				(arc
					(start 198.000112 -384.999992)
					(mid 197.707219 -385.707097)
					(end 197.000114 -385.99999)
				)
				(arc
					(start 183.3499 -385.99999)
					(mid 182.642795 -385.707097)
					(end 182.349902 -384.999992)
				)
				(arc
					(start 182.349902 -383.29997)
					(mid 182.057009 -382.592865)
					(end 181.349904 -382.299972)
				)
				(arc
					(start 174.850044 -382.299972)
					(mid 174.142939 -382.592865)
					(end 173.850046 -383.29997)
				)
				(arc
					(start 173.850046 -384.999992)
					(mid 173.557153 -385.707097)
					(end 172.850048 -385.99999)
				)
				(arc
					(start 127.299974 -385.99999)
					(mid 126.592869 -385.707097)
					(end 126.299976 -384.999992)
				)
				(arc
					(start 126.299976 -381)
					(mid 126.007083 -380.292895)
					(end 125.299978 -380.000002)
				)
				(xy 126.299976 -380.000002) (xy 126.299976 -358.000046) (xy 72.300084 -358.000046) (xy 72.300084 -380.000002)
				(arc
					(start 73.300082 -380.000002)
					(mid 72.592977 -380.292895)
					(end 72.300084 -381)
				)
				(arc
					(start 72.300084 -384.999992)
					(mid 72.007191 -385.707097)
					(end 71.300086 -385.99999)
				)
				(arc
					(start 25.750012 -385.99999)
					(mid 25.042907 -385.707097)
					(end 24.750014 -384.999992)
				)
				(arc
					(start 24.750014 -383.29997)
					(mid 24.457121 -382.592865)
					(end 23.750016 -382.299972)
				)
				(arc
					(start 17.249902 -382.299972)
					(mid 16.542797 -382.592865)
					(end 16.249904 -383.29997)
				)
				(arc
					(start 16.249904 -384.999992)
					(mid 15.957011 -385.707097)
					(end 15.249906 -385.99999)
				)
				(arc
					(start 3.999992 -385.99999)
					(mid 3.292887 -385.707097)
					(end 2.999994 -384.999992)
				)
				(arc
					(start 2.999994 -372.000018)
					(mid 2.707101 -371.292913)
					(end 1.999996 -371.00002)
				)
				(arc
					(start 0.999998 -371.00002)
					(mid 0.292893 -370.707127)
					(end 0 -370.000022)
				)
				(xy 0 -39.99992) (xy 199.00011 -39.99992)
				(arc
					(start 199.00011 -47.200058)
					(mid 199.293003 -47.907163)
					(end 200.000108 -48.200056)
				)
				(arc
					(start 206.000096 -48.200056)
					(mid 206.707201 -48.492949)
					(end 207.000094 -49.200054)
				)
				(arc
					(start 207.000094 -61.999876)
					(mid 207.292987 -62.706981)
					(end 208.000092 -62.999874)
				)
				(arc
					(start 267.999972 -62.999874)
					(mid 268.707077 -62.706981)
					(end 268.99997 -61.999876)
				)
				(arc
					(start 268.99997 -49.200054)
					(mid 269.292863 -48.492949)
					(end 269.999968 -48.200056)
				)
				(arc
					(start 309.999888 -48.200056)
					(mid 310.706993 -47.907163)
					(end 310.999886 -47.200058)
				)
				(xy 310.999886 -39.99992)
			)
		)
	)
	(zone
		(net "GND")
		(layer "B.Cu")
		(hatch none 0.5)
		(connect_pads
			(clearance 0.5)
		)
		(min_thickness 0.25)
		(fill yes
			(thermal_gap 0.5)
			(thermal_bridge_width 0.5)
			(island_removal_mode 0)
		)
		(polygon
			(pts
				(xy 455.928984 -104.491028) (xy 455.284586 -105.135426) (xy 455.284586 -107.310428) (xy 455.767186 -107.793028)
				(xy 459.856586 -107.793028) (xy 460.110586 -107.539028) (xy 460.110586 -105.16743) (xy 459.434184 -104.491028)
			)
		)
	)
	(zone
		(net "P12V_IN")
		(layer "B.Cu")
		(hatch none 0.5)
		(connect_pads
			(clearance 0.5)
		)
		(min_thickness 0.25)
		(fill yes
			(thermal_gap 0.5)
			(thermal_bridge_width 0.5)
			(island_removal_mode 0)
		)
		(polygon
			(pts
				(xy 131.063746 -365.080042) (xy 130.842258 -365.30153) (xy 130.842258 -366.748822) (xy 130.51028 -367.0808)
				(xy 128.7272 -367.0808) (xy 128.4986 -367.3094) (xy 128.4986 -368.0968) (xy 128.888744 -368.486944)
				(xy 132.47116 -368.486944) (xy 132.743448 -368.214656) (xy 132.743448 -365.394494) (xy 132.428996 -365.080042)
			)
		)
		(polygon
			(pts
				(xy 131.558284 -366.552988) (xy 131.355084 -366.552988) (xy 131.355084 -366.756188) (xy 131.558284 -366.756188)
			)
		)
		(polygon
			(pts
				(xy 131.558284 -365.943388) (xy 131.355084 -365.943388) (xy 131.355084 -366.146588) (xy 131.558284 -366.146588)
			)
		)
		(polygon
			(pts
				(xy 131.673092 -365.536734) (xy 131.469892 -365.536734) (xy 131.469892 -365.739934) (xy 131.673092 -365.739934)
			)
		)
	)
	(zone
		(layer "B.Cu")
		(hatch none 0.5)
		(connect_pads
			(clearance 0)
		)
		(min_thickness 0.25)
		(keepout
			(tracks allowed)
			(vias allowed)
			(pads allowed)
			(copperpour allowed)
			(footprints not_allowed)
		)
		(placement
			(enabled no)
			(sheetname "")
		)
		(fill
			(thermal_gap 0.5)
			(thermal_bridge_width 0.5)
			(island_removal_mode 0)
		)
		(polygon
			(pts
				(arc
					(start 284.299914 -295.209976)
					(mid 280.550112 -291.460174)
					(end 276.800056 -295.209976)
				)
				(arc
					(start 276.800056 -295.209976)
					(mid 280.550112 -298.960032)
					(end 284.299914 -295.209976)
				)
			)
		)
	)
	(zone
		(layer "B.Cu")
		(hatch none 0.5)
		(connect_pads
			(clearance 0)
		)
		(min_thickness 0.25)
		(keepout
			(tracks not_allowed)
			(vias allowed)
			(pads allowed)
			(copperpour not_allowed)
			(footprints allowed)
		)
		(placement
			(enabled no)
			(sheetname "")
		)
		(fill
			(thermal_gap 0.5)
			(thermal_bridge_width 0.5)
			(island_removal_mode 0)
		)
		(polygon
			(pts
				(arc
					(start 196.799962 -204.0001)
					(mid 189.799976 -197.000114)
					(end 182.79999 -204.0001)
				)
				(arc
					(start 182.79999 -210.000088)
					(mid 189.799976 -217.000074)
					(end 196.799962 -210.000088)
				)
			)
		)
	)
	(zone
		(layer "B.Cu")
		(hatch none 0.5)
		(connect_pads
			(clearance 0)
		)
		(min_thickness 0.25)
		(keepout
			(tracks not_allowed)
			(vias allowed)
			(pads allowed)
			(copperpour not_allowed)
			(footprints allowed)
		)
		(placement
			(enabled no)
			(sheetname "")
		)
		(fill
			(thermal_gap 0.5)
			(thermal_bridge_width 0.5)
			(island_removal_mode 0)
		)
		(polygon
			(pts
				(arc
					(start 279.236678 -234.545886)
					(mid 278.688038 -235.094526)
					(end 279.236678 -235.643166)
				)
				(arc
					(start 280.636726 -235.643166)
					(mid 281.185366 -235.094526)
					(end 280.636726 -234.545886)
				)
				(arc
					(start 280.141934 -234.545886)
					(mid 280.152755 -234.607892)
					(end 280.15819 -234.6706)
				)
				(xy 280.158952 -234.671362)
				(arc
					(start 280.158952 -234.880658)
					(mid 280.184564 -234.960715)
					(end 280.251916 -235.01096)
				)
				(arc
					(start 280.251916 -235.01096)
					(mid 281.030464 -235.100229)
					(end 280.24963 -235.166916)
				)
				(arc
					(start 280.24963 -235.166916)
					(mid 280.086751 -235.080924)
					(end 280.008584 -234.914186)
				)
				(xy 280.006552 -234.912154)
				(arc
					(start 280.006552 -234.702858)
					(mid 280.001026 -234.623622)
					(end 279.984708 -234.545886)
				)
				(arc
					(start 279.837896 -234.545886)
					(mid 279.856272 -234.606979)
					(end 279.865582 -234.670092)
				)
				(xy 279.866852 -234.671362) (xy 279.866852 -234.912154)
				(arc
					(start 279.86482 -234.914186)
					(mid 279.786575 -235.080849)
					(end 279.623774 -235.166916)
				)
				(arc
					(start 279.623774 -235.166916)
					(mid 278.842913 -235.10023)
					(end 279.621488 -235.01096)
				)
				(arc
					(start 279.621488 -235.01096)
					(mid 279.688773 -234.960667)
					(end 279.714452 -234.880658)
				)
				(arc
					(start 279.714452 -234.702858)
					(mid 279.702455 -234.620929)
					(end 279.667462 -234.545886)
				)
			)
		)
	)
	(zone
		(layer "B.Cu")
		(hatch none 0.5)
		(connect_pads
			(clearance 0)
		)
		(min_thickness 0.25)
		(keepout
			(tracks allowed)
			(vias allowed)
			(pads allowed)
			(copperpour allowed)
			(footprints allowed)
		)
		(placement
			(enabled no)
			(sheetname "")
		)
		(fill
			(thermal_gap 0.5)
			(thermal_bridge_width 0.5)
			(island_removal_mode 0)
		)
		(polygon
			(pts
				(xy 203.523596 -358.8258) (xy 203.523596 -328.6252) (xy 205.945232 -328.6252) (xy 205.945232 -358.8258)
			)
		)
	)
	(zone
		(layer "B.Cu")
		(hatch none 0.5)
		(connect_pads
			(clearance 0)
		)
		(min_thickness 0.25)
		(keepout
			(tracks allowed)
			(vias allowed)
			(pads allowed)
			(copperpour allowed)
			(footprints not_allowed)
		)
		(placement
			(enabled no)
			(sheetname "")
		)
		(fill
			(thermal_gap 0.5)
			(thermal_bridge_width 0.5)
			(island_removal_mode 0)
		)
		(polygon
			(pts
				(arc
					(start 62.61989 -331.399896)
					(mid 58.619898 -335.399888)
					(end 62.61989 -339.39988)
				)
				(arc
					(start 67.69989 -339.39988)
					(mid 71.699882 -335.399888)
					(end 67.69989 -331.399896)
				)
			)
		)
	)
	(zone
		(layer "B.Cu")
		(hatch none 0.5)
		(connect_pads
			(clearance 0)
		)
		(min_thickness 0.25)
		(keepout
			(tracks not_allowed)
			(vias allowed)
			(pads allowed)
			(copperpour not_allowed)
			(footprints allowed)
		)
		(placement
			(enabled no)
			(sheetname "")
		)
		(fill
			(thermal_gap 0.5)
			(thermal_bridge_width 0.5)
			(island_removal_mode 0)
		)
		(polygon
			(pts
				(arc
					(start 476.964756 -13.14196)
					(mid 476.479362 -13.626973)
					(end 476.964502 -14.11224)
				)
				(xy 477.313752 -14.11224)
				(arc
					(start 477.313752 -13.789152)
					(mid 477.288607 -13.728445)
					(end 477.2279 -13.7033)
				)
				(arc
					(start 477.220026 -13.7033)
					(mid 476.697858 -13.6271)
					(end 477.220026 -13.5509)
				)
				(xy 477.259396 -13.5509)
				(arc
					(start 477.261936 -13.55344)
					(mid 477.396302 -13.62075)
					(end 477.463612 -13.755116)
				)
				(xy 477.466152 -13.757656) (xy 477.466152 -14.11224) (xy 477.605852 -14.11224) (xy 477.605852 -13.751052)
				(arc
					(start 477.608392 -13.748512)
					(mid 477.673718 -13.618766)
					(end 477.803464 -13.55344)
				)
				(xy 477.806004 -13.5509)
				(arc
					(start 477.851978 -13.5509)
					(mid 478.374146 -13.6271)
					(end 477.851978 -13.7033)
				)
				(arc
					(start 477.8375 -13.7033)
					(mid 477.781463 -13.726511)
					(end 477.758252 -13.782548)
				)
				(xy 477.758252 -14.11224)
				(arc
					(start 478.107502 -14.11224)
					(mid 478.592642 -13.6271)
					(end 478.107502 -13.14196)
				)
			)
		)
	)
	(zone
		(layer "B.Cu")
		(hatch none 0.5)
		(connect_pads
			(clearance 0)
		)
		(min_thickness 0.25)
		(keepout
			(tracks not_allowed)
			(vias allowed)
			(pads allowed)
			(copperpour not_allowed)
			(footprints allowed)
		)
		(placement
			(enabled no)
			(sheetname "")
		)
		(fill
			(thermal_gap 0.5)
			(thermal_bridge_width 0.5)
			(island_removal_mode 0)
		)
		(polygon
			(pts
				(arc
					(start 279.236678 -220.145864)
					(mid 278.688038 -220.694504)
					(end 279.236678 -221.243144)
				)
				(arc
					(start 279.723596 -221.243144)
					(mid 279.71825 -221.204024)
					(end 279.715214 -221.164658)
				)
				(xy 279.714452 -221.163896)
				(arc
					(start 279.714452 -220.8784)
					(mid 279.688374 -220.808137)
					(end 279.622758 -220.771974)
				)
				(arc
					(start 279.622758 -220.771974)
					(mid 278.842903 -220.693856)
					(end 279.623012 -220.618304)
				)
				(xy 279.638252 -220.618304)
				(arc
					(start 279.640538 -220.62059)
					(mid 279.790614 -220.694542)
					(end 279.864566 -220.844618)
				)
				(xy 279.866852 -220.846904)
				(arc
					(start 279.866852 -221.1324)
					(mid 279.869845 -221.188093)
					(end 279.87879 -221.243144)
				)
				(arc
					(start 280.023062 -221.243144)
					(mid 280.013548 -221.204672)
					(end 280.008076 -221.16542)
				)
				(xy 280.006552 -221.163896) (xy 280.006552 -220.846904)
				(arc
					(start 280.008838 -220.844618)
					(mid 280.08279 -220.694542)
					(end 280.232866 -220.62059)
				)
				(xy 280.235152 -220.618304)
				(arc
					(start 280.250392 -220.618304)
					(mid 281.030503 -220.693856)
					(end 280.250646 -220.771974)
				)
				(arc
					(start 280.250646 -220.771974)
					(mid 280.185086 -220.808185)
					(end 280.158952 -220.8784)
				)
				(arc
					(start 280.158952 -221.1324)
					(mid 280.166204 -221.189615)
					(end 280.187654 -221.243144)
				)
				(arc
					(start 280.636726 -221.243144)
					(mid 281.185366 -220.694504)
					(end 280.636726 -220.145864)
				)
			)
		)
	)
	(zone
		(net "GND")
		(layer "B.Cu")
		(hatch none 0.5)
		(connect_pads
			(clearance 0.5)
		)
		(min_thickness 0.25)
		(fill yes
			(thermal_gap 0.5)
			(thermal_bridge_width 0.5)
			(island_removal_mode 0)
		)
		(polygon
			(pts
				(xy 178.11369 -122.890534) (xy 149.1996 -104.11333)
				(arc
					(start 147.171918 -104.11333)
					(mid 145.936602 -104.831718)
					(end 144.529556 -105.081324)
				)
				(arc
					(start 143.259556 -105.081324)
					(mid 143.062731 -105.076525)
					(end 142.866364 -105.062274)
				)
				(arc
					(start 142.866364 -105.062274)
					(mid 142.175779 -105.376002)
					(end 141.439138 -105.556812)
				)
				(arc
					(start 141.439138 -105.556812)
					(mid 140.112402 -105.903292)
					(end 138.745722 -105.791762)
				)
				(arc
					(start 138.745722 -105.791762)
					(mid 134.980564 -104.550316)
					(end 134.036816 -100.699824)
				)
				(arc
					(start 134.036816 -99.041458)
					(mid 133.079496 -97.105166)
					(end 133.24205 -94.951296)
				)
				(xy 133.24205 -93.75013) (xy 128.368298 -90.585036) (xy 112.60328 -66.309494) (xy 108.406184 -66.309494)
				(xy 107.14609 -67.569588)
				(arc
					(start 107.14609 -69.794374)
					(mid 96.324928 -80.615536)
					(end 85.503766 -69.794374)
				)
				(arc
					(start 85.503766 -50.880518)
					(mid 83.608443 -48.836181)
					(end 83.463384 -46.052232)
				)
				(arc
					(start 83.463384 -44.733972)
					(mid 82.371598 -43.667859)
					(end 81.746598 -42.27576)
				)
				(arc
					(start 77.355192 -39.423848)
					(mid 73.464282 -39.117381)
					(end 71.601838 -35.687508)
				)
				(arc
					(start 67.730624 -33.17367)
					(mid 66.087096 -34.241915)
					(end 64.135254 -34.422842)
				)
				(arc
					(start 64.135254 -34.422842)
					(mid 63.967056 -34.436224)
					(end 63.79845 -34.442654)
				)
				(arc
					(start 63.79845 -34.442654)
					(mid 63.503034 -35.205883)
					(end 63.061596 -35.895026)
				)
				(arc
					(start 63.061596 -35.895026)
					(mid 63.71841 -37.090285)
					(end 63.94577 -38.435026)
				)
				(arc
					(start 63.94577 -40.975026)
					(mid 63.886392 -41.669249)
					(end 63.710058 -42.343324)
				)
				(arc
					(start 63.710058 -45.6819)
					(mid 64.081047 -46.624347)
					(end 64.231012 -47.626016)
				)
				(arc
					(start 64.231012 -47.626016)
					(mid 63.807225 -54.249377)
					(end 57.658508 -51.75123)
				)
				(arc
					(start 57.658508 -51.75123)
					(mid 57.229417 -51.493418)
					(end 56.831738 -51.189382)
				)
				(arc
					(start 56.831738 -51.189382)
					(mid 52.891031 -50.166131)
					(end 51.786028 -46.247558)
				)
				(arc
					(start 51.786028 -44.60621)
					(mid 50.348729 -42.619801)
					(end 50.305716 -40.168322)
				)
				(xy 48.906938 -38.769544)
				(arc
					(start 46.75759 -38.769544)
					(mid 41.858273 -39.128407)
					(end 40.147748 -34.523426)
				)
				(arc
					(start 40.147748 -34.523426)
					(mid 38.792473 -31.369688)
					(end 39.688516 -28.056078)
				)
				(xy 39.688516 -23.459186) (xy 38.818312 -22.894036) (xy 38.81755 -22.894036) (xy 37.802312 -22.234144)
				(xy 37.596826 -22.10054) (xy 37.378894 -21.959062)
				(arc
					(start 36.264342 -21.959062)
					(mid 35.998291 -22.487779)
					(end 35.658298 -22.972268)
				)
				(xy 35.658298 -25.043384) (xy 37.200332 -26.585418)
				(arc
					(start 37.200332 -28.674314)
					(mid 37.145736 -31.953252)
					(end 34.70021 -34.138108)
				)
				(xy 32.23895 -36.599368)
				(arc
					(start 32.23895 -37.312854)
					(mid 32.356486 -37.868478)
					(end 32.395922 -38.435026)
				)
				(arc
					(start 32.395922 -40.975026)
					(mid 32.356557 -41.541181)
					(end 32.239204 -42.096436)
				)
				(arc
					(start 32.239204 -45.837856)
					(mid 32.552978 -46.708999)
					(end 32.681164 -47.626016)
				)
				(arc
					(start 32.681164 -47.626016)
					(mid 33.691101 -48.858533)
					(end 34.153348 -50.38344)
				)
				(arc
					(start 37.651182 -53.881274)
					(mid 42.377833 -57.872007)
					(end 44.145962 -63.799974)
				)
				(arc
					(start 44.145962 -69.794374)
					(mid 33.3248 -80.615536)
					(end 22.503638 -69.794374)
				)
				(xy 22.503638 -55.964328) (xy 23.58263 -54.885336) (xy 23.58263 -51.909726)
				(arc
					(start 22.698456 -51.025552)
					(mid 20.633948 -49.142074)
					(end 20.260818 -46.372526)
				)
				(arc
					(start 20.260818 -44.676822)
					(mid 18.884702 -39.628605)
					(end 23.598632 -37.357812)
				)
				(arc
					(start 24.3586 -37.357812)
					(mid 24.654428 -36.589006)
					(end 25.098248 -35.895026)
				)
				(arc
					(start 25.098248 -35.895026)
					(mid 24.441434 -34.699767)
					(end 24.214074 -33.355026)
				)
				(arc
					(start 24.214074 -30.815026)
					(mid 24.284403 -30.059728)
					(end 24.492966 -29.330396)
				)
				(arc
					(start 24.492966 -29.330396)
					(mid 23.455926 -27.962345)
					(end 23.071582 -26.289254)
				)
				(arc
					(start 23.071582 -26.289254)
					(mid 22.839171 -26.309227)
					(end 22.606 -26.315924)
				)
				(xy 20.53971 -26.315924) (xy 20.305776 -26.549858) (xy 20.305776 -26.805128)
				(arc
					(start 20.403312 -26.902664)
					(mid 22.52103 -29.23157)
					(end 22.357334 -32.375094)
				)
				(arc
					(start 22.357334 -32.375094)
					(mid 21.450445 -36.632118)
					(end 17.221454 -37.66185)
				)
				(arc
					(start 16.154908 -37.66185)
					(mid 11.032736 -39.476153)
					(end 8.629142 -34.602674)
				)
				(arc
					(start 8.629142 -27.202384)
					(mid 9.25193 -24.595402)
					(end 11.354816 -22.933406)
				)
				(xy 11.354816 -22.023324) (xy 10.116566 -20.785074)
				(arc
					(start 9.340342 -20.785074)
					(mid 7.574697 -21.104551)
					(end 5.842254 -20.6375)
				)
				(arc
					(start 5.842254 -20.6375)
					(mid 4.854711 -19.910035)
					(end 4.127246 -18.922492)
				)
				(xy 2.032 -16.827246) (xy 2.032 -2.032) (xy 14.899386 -2.032)
				(arc
					(start 16.433038 -3.565652)
					(mid 18.109762 -4.419624)
					(end 19.341338 -5.842254)
				)
				(arc
					(start 19.341338 -5.842254)
					(mid 19.984432 -8.525098)
					(end 19.077178 -11.130534)
				)
				(xy 19.077178 -11.568176) (xy 19.511518 -12.002516) (xy 21.11883 -12.002516)
				(arc
					(start 24.023066 -9.09828)
					(mid 24.748959 -7.502299)
					(end 26.053796 -6.331204)
				)
				(arc
					(start 26.053796 -6.331204)
					(mid 26.104695 -6.084932)
					(end 26.170636 -5.842254)
				)
				(xy 26.170636 -2.032) (xy 65.545208 -2.032)
				(arc
					(start 65.545208 -5.842254)
					(mid 65.722073 -6.945066)
					(end 65.593976 -8.054594)
				)
				(arc
					(start 67.0687 -9.529318)
					(mid 68.436877 -10.278964)
					(end 69.42201 -11.488674)
				)
				(xy 69.705982 -11.548618) (xy 71.590408 -12.771882)
				(arc
					(start 75.306428 -12.771882)
					(mid 77.025183 -12.564574)
					(end 78.675738 -13.086842)
				)
				(arc
					(start 84.140802 -13.086842)
					(mid 85.20259 -12.421804)
					(end 86.41588 -12.10945)
				)
				(arc
					(start 87.213948 -11.311382)
					(mid 87.311139 -8.481363)
					(end 89.153746 -6.331204)
				)
				(arc
					(start 89.153746 -6.331204)
					(mid 89.204645 -6.084932)
					(end 89.270586 -5.842254)
				)
				(xy 89.270586 -2.032) (xy 97.09531 -2.032)
				(arc
					(start 97.09531 -5.842254)
					(mid 97.265262 -6.782015)
					(end 97.212658 -7.73557)
				)
				(arc
					(start 99.286822 -9.809734)
					(mid 100.432048 -10.711157)
					(end 101.185726 -11.958574)
				)
				(xy 102.128066 -12.570714) (xy 103.212646 -14.242542) (xy 103.374698 -15.005304)
				(arc
					(start 104.274874 -15.90548)
					(mid 104.667411 -15.779002)
					(end 105.065576 -15.671546)
				)
				(arc
					(start 105.065576 -15.671546)
					(mid 105.344255 -15.396217)
					(end 105.647998 -15.148814)
				)
				(arc
					(start 105.647998 -13.76934)
					(mid 104.011142 -10.024667)
					(end 106.431842 -6.732016)
				)
				(xy 108.54055 -4.623308) (xy 108.54055 -2.032) (xy 128.645158 -2.032)
				(arc
					(start 128.645158 -5.842254)
					(mid 128.820948 -6.907277)
					(end 128.71196 -7.981188)
				)
				(arc
					(start 130.306826 -9.576054)
					(mid 131.828933 -10.547362)
					(end 132.780278 -12.082018)
				)
				(xy 133.375908 -12.468606) (xy 135.167624 -15.22603)
				(arc
					(start 135.924544 -15.22603)
					(mid 139.210612 -12.584297)
					(end 143.084296 -14.248892)
				)
				(arc
					(start 146.492468 -14.248892)
					(mid 147.771278 -12.910777)
					(end 149.508972 -12.27328)
				)
				(arc
					(start 150.35276 -11.429492)
					(mid 150.389015 -8.539483)
					(end 152.253696 -6.331204)
				)
				(arc
					(start 152.253696 -6.331204)
					(mid 152.304595 -6.084932)
					(end 152.370536 -5.842254)
				)
				(xy 152.370536 -2.032) (xy 196.96811 -2.032) (xy 196.96811 -43.865546) (xy 195.464176 -43.865546)
				(xy 193.98996 -45.339762) (xy 193.98996 -49.223676) (xy 194.392804 -51.12131) (xy 194.392804 -51.121056)
				(xy 203.240132 -92.746068) (xy 203.0603 -93.592142) (xy 203.0603 -96.35998) (xy 203.97978 -97.27946)
				(arc
					(start 205.141322 -97.27946)
					(mid 205.811467 -97.33374)
					(end 206.464154 -97.495106)
				)
				(xy 208.316322 -95.642938) (xy 208.316322 -94.940628) (xy 206.602076 -92.300806) (xy 205.060804 -85.050376)
				(xy 205.060804 -75.182984)
				(arc
					(start 205.06182 -75.098656)
					(mid 205.263992 -73.843409)
					(end 205.807564 -72.694038)
				)
				(arc
					(start 205.807564 -66.799968)
					(mid 205.821886 -66.453982)
					(end 205.864714 -66.110358)
				)
				(arc
					(start 205.864714 -66.110358)
					(mid 205.850487 -65.948523)
					(end 205.842616 -65.786254)
				)
				(xy 205.842362 -65.786254) (xy 205.842362 -61.976) (xy 206.237078 -61.976)
				(arc
					(start 206.237078 -49.200054)
					(mid 206.167668 -49.032482)
					(end 206.000096 -48.963072)
				)
				(arc
					(start 200.000108 -48.963072)
					(mid 198.753469 -48.446697)
					(end 198.237094 -47.200058)
				)
				(arc
					(start 198.237094 -0.999998)
					(mid 198.167684 -0.832426)
					(end 198.000112 -0.763016)
				)
				(arc
					(start 0.999998 -0.763016)
					(mid 0.832426 -0.832426)
					(end 0.763016 -0.999998)
				)
				(arc
					(start 0.763016 -370.000022)
					(mid 0.832426 -370.167594)
					(end 0.999998 -370.237004)
				)
				(arc
					(start 1.999996 -370.237004)
					(mid 3.246635 -370.753379)
					(end 3.76301 -372.000018)
				)
				(arc
					(start 3.76301 -384.999992)
					(mid 3.83242 -385.167564)
					(end 3.999992 -385.236974)
				)
				(arc
					(start 15.249906 -385.236974)
					(mid 15.417478 -385.167564)
					(end 15.486888 -384.999992)
				)
				(arc
					(start 15.486888 -383.29997)
					(mid 16.003263 -382.053331)
					(end 17.249902 -381.536956)
				)
				(arc
					(start 23.750016 -381.536956)
					(mid 24.996655 -382.053331)
					(end 25.51303 -383.29997)
				)
				(arc
					(start 25.51303 -384.999992)
					(mid 25.58244 -385.167564)
					(end 25.750012 -385.236974)
				)
				(arc
					(start 71.300086 -385.236974)
					(mid 71.467658 -385.167564)
					(end 71.537068 -384.999992)
				)
				(arc
					(start 71.537068 -381)
					(mid 72.053443 -379.753361)
					(end 73.300082 -379.236986)
				)
				(arc
					(start 125.299978 -379.236986)
					(mid 126.546617 -379.753361)
					(end 127.062992 -381)
				)
				(arc
					(start 127.062992 -384.999992)
					(mid 127.132402 -385.167564)
					(end 127.299974 -385.236974)
				)
				(arc
					(start 172.850048 -385.236974)
					(mid 173.01762 -385.167564)
					(end 173.08703 -384.999992)
				)
				(arc
					(start 173.08703 -383.29997)
					(mid 173.603405 -382.053331)
					(end 174.850044 -381.536956)
				)
				(arc
					(start 181.349904 -381.536956)
					(mid 182.596543 -382.053331)
					(end 183.112918 -383.29997)
				)
				(arc
					(start 183.112918 -384.999992)
					(mid 183.182328 -385.167564)
					(end 183.3499 -385.236974)
				)
				(arc
					(start 197.000114 -385.236974)
					(mid 197.167686 -385.167564)
					(end 197.237096 -384.999992)
				)
				(arc
					(start 197.237096 -381)
					(mid 197.753471 -379.753361)
					(end 199.00011 -379.236986)
				)
				(arc
					(start 251.000006 -379.236986)
					(mid 252.246645 -379.753361)
					(end 252.76302 -381)
				)
				(arc
					(start 252.76302 -384.999992)
					(mid 252.83243 -385.167564)
					(end 253.000002 -385.236974)
				)
				(arc
					(start 269.036292 -385.236974)
					(mid 269.126761 -385.218921)
					(end 269.203424 -385.167632)
				)
				(arc
					(start 271.617694 -382.753362)
					(mid 271.668989 -382.676683)
					(end 271.687036 -382.58623)
				)
				(arc
					(start 271.687036 -361.00004)
					(mid 272.203411 -359.753401)
					(end 273.45005 -359.237026)
				)
				(arc
					(start 275.75002 -359.237026)
					(mid 276.996659 -359.753401)
					(end 277.513034 -361.00004)
				)
				(arc
					(start 277.513034 -382.58623)
					(mid 277.531087 -382.676699)
					(end 277.582376 -382.753362)
				)
				(arc
					(start 279.996646 -385.167632)
					(mid 280.07334 -385.218844)
					(end 280.163778 -385.236974)
				)
				(arc
					(start 306.649882 -385.236974)
					(mid 306.817454 -385.167564)
					(end 306.886864 -384.999992)
				)
				(arc
					(start 306.886864 -383.29997)
					(mid 307.403239 -382.053331)
					(end 308.649878 -381.536956)
				)
				(arc
					(start 315.149992 -381.536956)
					(mid 316.396631 -382.053331)
					(end 316.913006 -383.29997)
				)
				(arc
					(start 316.913006 -384.999992)
					(mid 316.982416 -385.167564)
					(end 317.149988 -385.236974)
				)
				(arc
					(start 362.700062 -385.236974)
					(mid 362.867634 -385.167564)
					(end 362.937044 -384.999992)
				)
				(arc
					(start 362.937044 -381)
					(mid 363.453419 -379.753361)
					(end 364.700058 -379.236986)
				)
				(arc
					(start 416.699954 -379.236986)
					(mid 417.946593 -379.753361)
					(end 418.462968 -381)
				)
				(arc
					(start 418.462968 -384.999992)
					(mid 418.532378 -385.167564)
					(end 418.69995 -385.236974)
				)
				(arc
					(start 464.250024 -385.236974)
					(mid 464.417596 -385.167564)
					(end 464.487006 -384.999992)
				)
				(arc
					(start 464.487006 -383.29997)
					(mid 465.003381 -382.053331)
					(end 466.25002 -381.536956)
				)
				(arc
					(start 472.74988 -381.536956)
					(mid 473.996519 -382.053331)
					(end 474.512894 -383.29997)
				)
				(arc
					(start 474.512894 -384.999992)
					(mid 474.582304 -385.167564)
					(end 474.749876 -385.236974)
				)
				(arc
					(start 487.449876 -385.236974)
					(mid 487.617448 -385.167564)
					(end 487.686858 -384.999992)
				)
				(arc
					(start 487.686858 -372.000018)
					(mid 488.203143 -370.753469)
					(end 489.449618 -370.237004)
				)
				(arc
					(start 490.450124 -370.237004)
					(mid 490.617696 -370.167594)
					(end 490.687106 -370.000022)
				)
				(arc
					(start 490.687106 -0.999998)
					(mid 490.617696 -0.832426)
					(end 490.450124 -0.763016)
				)
				(arc
					(start 311.999884 -0.763016)
					(mid 311.832312 -0.832426)
					(end 311.762902 -0.999998)
				)
				(arc
					(start 311.762902 -47.200058)
					(mid 311.246527 -48.446697)
					(end 309.999888 -48.963072)
				)
				(arc
					(start 269.999968 -48.963072)
					(mid 269.832396 -49.032482)
					(end 269.762986 -49.200054)
				)
				(xy 269.762986 -80.959452)
				(arc
					(start 268.417802 -82.304636)
					(mid 268.126178 -82.626422)
					(end 267.804392 -82.918046)
				)
				(xy 266.173966 -84.548472) (xy 264.892536 -84.548472) (xy 264.11047 -85.330538) (xy 264.11047 -88.547194)
				(xy 266.388596 -90.82532) (xy 274.926806 -90.82532) (xy 277.924006 -93.82252) (xy 277.924006 -96.316292)
				(xy 278.627078 -97.019364)
				(arc
					(start 280.791158 -97.019364)
					(mid 281.743737 -97.129761)
					(end 282.645866 -97.454974)
				)
				(arc
					(start 282.645866 -97.454974)
					(mid 283.524274 -97.148619)
					(end 284.448758 -97.044764)
				)
				(xy 288.202624 -97.044764) (xy 289.378644 -95.868744)
				(arc
					(start 289.378644 -93.999812)
					(mid 296.970342 -83.671786)
					(end 309.093362 -87.835232)
				)
				(xy 309.494682 -87.835232) (xy 309.918608 -87.411306) (xy 312.675016 -53.497734)
				(arc
					(start 312.675016 -48.627284)
					(mid 312.941318 -47.93577)
					(end 313.031886 -47.200312)
				)
				(xy 313.031886 -2.032) (xy 362.895388 -2.032)
				(arc
					(start 362.895388 -5.842254)
					(mid 363.056706 -6.668372)
					(end 363.045502 -7.510018)
				)
				(xy 363.76356 -8.228076)
				(arc
					(start 364.744 -8.228076)
					(mid 367.297286 -9.122691)
					(end 368.733832 -11.415268)
				)
				(arc
					(start 368.733832 -11.415268)
					(mid 371.645189 -12.969429)
					(end 372.461536 -16.1671)
				)
				(arc
					(start 372.461536 -18.403824)
					(mid 373.454904 -19.185258)
					(end 374.16232 -20.232624)
				)
				(xy 374.687592 -20.232624) (xy 375.140728 -19.779488) (xy 377.342654 -16.388842)
				(arc
					(start 377.342654 -14.565376)
					(mid 378.109148 -11.105783)
					(end 381.29845 -9.561576)
				)
				(xy 383.3876 -9.561576)
				(arc
					(start 384.81381 -8.135366)
					(mid 385.525681 -7.108656)
					(end 386.503672 -6.331204)
				)
				(arc
					(start 386.503672 -6.331204)
					(mid 386.554571 -6.084932)
					(end 386.620512 -5.842254)
				)
				(xy 386.620512 -2.032) (xy 398.451578 -2.032) (xy 398.333976 -2.149602) (xy 398.333976 -5.842254)
				(arc
					(start 398.334484 -5.842762)
					(mid 399.003512 -6.612838)
					(end 399.461228 -7.524496)
				)
				(arc
					(start 400.7866 -8.849868)
					(mid 403.50178 -10.543965)
					(end 404.165816 -13.674598)
				)
				(xy 404.165816 -14.650466)
				(arc
					(start 404.960328 -15.444978)
					(mid 406.72394 -15.747682)
					(end 408.38628 -16.409924)
				)
				(xy 408.520392 -16.409924) (xy 409.052522 -15.877794)
				(arc
					(start 409.052522 -15.082774)
					(mid 409.498405 -11.323766)
					(end 412.848552 -9.561576)
				)
				(xy 415.054288 -9.561576)
				(arc
					(start 416.26409 -8.351774)
					(mid 416.995495 -7.196723)
					(end 418.053774 -6.331204)
				)
				(arc
					(start 418.053774 -6.331204)
					(mid 418.104673 -6.084932)
					(end 418.170614 -5.842254)
				)
				(xy 418.170614 -2.032) (xy 425.995338 -2.032)
				(arc
					(start 425.995338 -5.842254)
					(mid 426.143787 -6.546403)
					(end 426.166534 -7.26567)
				)
				(xy 427.12894 -8.228076)
				(arc
					(start 427.863 -8.228076)
					(mid 429.995627 -8.827931)
					(end 431.50282 -10.451592)
				)
				(arc
					(start 432.590702 -11.539474)
					(mid 435.011099 -13.320807)
					(end 435.560724 -16.275304)
				)
				(xy 435.560724 -17.180814) (xy 435.85384 -17.47393) (xy 436.456328 -17.47393) (xy 440.374024 -14.929866)
				(arc
					(start 440.374024 -14.204188)
					(mid 441.326364 -10.964164)
					(end 444.3984 -9.561576)
				)
				(xy 446.633346 -9.561576)
				(arc
					(start 447.792856 -8.402066)
					(mid 448.527363 -7.21722)
					(end 449.603622 -6.331204)
				)
				(arc
					(start 449.603622 -6.331204)
					(mid 449.654521 -6.084932)
					(end 449.720462 -5.842254)
				)
				(xy 449.720462 -2.032) (xy 489.418122 -2.032) (xy 489.418122 -54.853078)
				(arc
					(start 485.607868 -54.853078)
					(mid 482.826011 -54.127868)
					(end 481.208588 -51.75123)
				)
				(arc
					(start 481.208588 -51.75123)
					(mid 480.192129 -51.017034)
					(end 479.41865 -50.030126)
				)
				(arc
					(start 479.41865 -50.030126)
					(mid 475.352933 -48.955921)
					(end 474.383354 -44.86402)
				)
				(arc
					(start 474.383354 -43.486578)
					(mid 474.342495 -38.972776)
					(end 478.480882 -37.170106)
				)
				(xy 479.314002 -36.336986)
				(arc
					(start 479.314002 -30.815026)
					(mid 479.343823 -30.321971)
					(end 479.432874 -29.83611)
				)
				(arc
					(start 479.432874 -29.185108)
					(mid 478.686208 -28.217536)
					(end 478.258632 -27.07259)
				)
				(xy 477.374966 -26.188924) (xy 474.15196 -26.188924) (xy 473.954602 -26.386282) (xy 473.954602 -26.579068)
				(arc
					(start 474.048836 -26.673302)
					(mid 476.115135 -28.346892)
					(end 476.715836 -30.9372)
				)
				(arc
					(start 476.715836 -30.9372)
					(mid 477.307652 -35.503227)
					(end 473.275914 -37.726874)
				)
				(xy 469.62695 -41.375838)
				(arc
					(start 469.62695 -41.579292)
					(mid 469.018007 -45.699646)
					(end 465.11337 -47.149258)
				)
				(arc
					(start 463.225134 -49.037494)
					(mid 461.720033 -50.623597)
					(end 459.613 -51.207924)
				)
				(xy 458.497178 -51.207924) (xy 457.814934 -51.890168) (xy 457.814934 -52.704492)
				(arc
					(start 458.196442 -53.086)
					(mid 464.846967 -56.706251)
					(end 467.496144 -63.79972)
				)
				(arc
					(start 467.496144 -69.79412)
					(mid 456.674982 -80.615282)
					(end 445.85382 -69.79412)
				)
				(arc
					(start 445.85382 -63.79972)
					(mid 446.260942 -60.859394)
					(end 447.451734 -58.140346)
				)
				(arc
					(start 447.451734 -49.061878)
					(mid 447.296692 -47.262016)
					(end 447.864484 -45.547026)
				)
				(arc
					(start 447.864484 -41.876472)
					(mid 447.789141 -41.428545)
					(end 447.7639 -40.975026)
				)
				(xy 447.7639 -39.136066) (xy 446.854834 -38.227)
				(arc
					(start 445.97574 -38.227)
					(mid 442.181626 -37.86382)
					(end 440.3344 -34.53003)
				)
				(xy 439.893456 -34.089086) (xy 438.804558 -34.089086) (xy 436.891684 -34.49574)
				(arc
					(start 432.387756 -38.999668)
					(mid 431.741393 -40.544714)
					(end 430.53 -41.701212)
				)
				(arc
					(start 430.53 -43.813476)
					(mid 430.988265 -44.202986)
					(end 431.384456 -44.655486)
				)
				(arc
					(start 433.838096 -44.655486)
					(mid 438.859671 -49.87966)
					(end 431.705258 -51.030124)
				)
				(arc
					(start 429.310038 -51.030124)
					(mid 428.720235 -51.163231)
					(end 428.117254 -51.207924)
				)
				(xy 427.67758 -51.207924) (xy 426.810932 -52.074572) (xy 426.810932 -52.671726)
				(arc
					(start 427.067218 -52.928012)
					(mid 435.722369 -57.593401)
					(end 439.175144 -66.799714)
				)
				(arc
					(start 439.175144 -66.799714)
					(mid 423.39831 -80.686758)
					(end 411.625542 -63.27521)
				)
				(arc
					(start 411.625542 -63.27521)
					(mid 414.333852 -57.941106)
					(end 419.021514 -54.224428)
				)
				(arc
					(start 419.021514 -53.49748)
					(mid 418.458364 -52.680142)
					(end 418.108638 -51.75123)
				)
				(arc
					(start 418.108638 -51.75123)
					(mid 415.844153 -48.848448)
					(end 416.516312 -45.228764)
				)
				(xy 416.516312 -44.331636) (xy 415.864548 -43.679872) (xy 415.007044 -43.679872) (xy 403.00656 -51.4731)
				(arc
					(start 403.00656 -58.321194)
					(mid 404.117022 -60.961156)
					(end 404.496016 -63.799974)
				)
				(arc
					(start 404.496016 -69.794374)
					(mid 393.843024 -80.614229)
					(end 382.859026 -70.13067)
				)
				(xy 381.244094 -68.515738) (xy 376.763026 -68.515738) (xy 349.682816 -86.101936) (xy 346.284296 -91.335352)
				(xy 346.284296 -95.717106) (xy 347.339666 -96.772476)
				(arc
					(start 347.348556 -96.772476)
					(mid 347.580452 -96.779112)
					(end 347.811598 -96.798892)
				)
				(xy 365.379762 -96.798892)
				(arc
					(start 367.700306 -94.478348)
					(mid 367.953369 -94.042548)
					(end 368.25809 -93.641164)
				)
				(arc
					(start 368.25809 -93.641164)
					(mid 372.45039 -90.464586)
					(end 376.30481 -94.0435)
				)
				(arc
					(start 379.034294 -96.772984)
					(mid 383.062333 -100.89477)
					(end 378.971556 -104.954324)
				)
				(arc
					(start 377.699016 -104.954324)
					(mid 377.506268 -104.949721)
					(end 377.313952 -104.936036)
				)
				(arc
					(start 377.313952 -104.936036)
					(mid 376.539821 -105.325344)
					(end 375.701052 -105.542842)
				)
				(arc
					(start 375.701052 -105.542842)
					(mid 374.375587 -105.889024)
					(end 373.010176 -105.778046)
				)
				(arc
					(start 373.010176 -105.778046)
					(mid 371.243523 -105.723111)
					(end 369.664996 -104.927908)
				)
				(xy 351.847912 -104.927908) (xy 350.223328 -106.552492) (xy 350.222566 -106.553254) (xy 345.749372 -111.026702)
				(xy 345.749372 -124.828046) (xy 346.37218 -125.450854)
				(arc
					(start 347.210888 -125.450854)
					(mid 348.404094 -124.790331)
					(end 349.748602 -124.5616)
				)
				(xy 351.71253 -124.5616)
				(arc
					(start 353.411536 -122.862594)
					(mid 354.083863 -121.997386)
					(end 354.953824 -121.331228)
				)
				(arc
					(start 354.953824 -121.331228)
					(mid 359.500086 -117.977661)
					(end 363.05998 -122.364246)
				)
				(xy 363.98581 -123.290076)
				(arc
					(start 364.744 -123.290076)
					(mid 366.112377 -123.525717)
					(end 367.323116 -124.205492)
				)
				(arc
					(start 367.323116 -124.205492)
					(mid 371.030448 -125.279837)
					(end 372.193058 -128.960372)
				)
				(arc
					(start 372.193058 -128.960372)
					(mid 372.494122 -130.122028)
					(end 372.445026 -131.321048)
				)
				(arc
					(start 372.445026 -133.456426)
					(mid 373.984691 -134.957985)
					(end 374.549924 -137.033)
				)
				(xy 374.549924 -138.640058) (xy 375.379996 -139.47013) (xy 376.08383 -139.47013) (xy 378.590302 -135.610854)
				(xy 378.865892 -134.314438)
				(arc
					(start 378.865892 -131.88442)
					(mid 377.440377 -127.34549)
					(end 381.29845 -124.5616)
				)
				(xy 383.547366 -124.5616)
				(arc
					(start 384.683254 -123.425712)
					(mid 385.419038 -122.22687)
					(end 386.503672 -121.331228)
				)
				(arc
					(start 386.503672 -121.331228)
					(mid 390.801876 -117.953703)
					(end 394.61948 -121.866152)
				)
				(xy 396.043404 -123.290076)
				(arc
					(start 396.367 -123.290076)
					(mid 397.735377 -123.525717)
					(end 398.946116 -124.205492)
				)
				(arc
					(start 398.946116 -124.205492)
					(mid 402.653448 -125.279837)
					(end 403.816058 -128.960372)
				)
				(arc
					(start 403.816058 -128.960372)
					(mid 404.120021 -130.150099)
					(end 404.057104 -131.37642)
				)
				(arc
					(start 404.057104 -133.450584)
					(mid 405.531755 -134.83421)
					(end 406.163526 -136.755124)
				)
				(xy 406.949402 -137.541) (xy 407.520902 -137.541) (xy 410.31668 -133.236208) (xy 410.41574 -132.769356)
				(arc
					(start 410.41574 -131.88442)
					(mid 408.990366 -127.345346)
					(end 412.848552 -124.5616)
				)
				(xy 414.871662 -124.5616)
				(arc
					(start 416.434778 -122.998484)
					(mid 417.128965 -122.052881)
					(end 418.053774 -121.331228)
				)
				(arc
					(start 418.053774 -121.331228)
					(mid 418.695015 -119.743432)
					(end 419.930072 -118.557294)
				)
				(xy 420.624 -117.863366) (xy 420.624 -116.094002) (xy 417.920932 -113.390934) (xy 417.920932 -107.313222)
				(xy 420.40683 -104.827324) (xy 426.865542 -104.827324) (xy 427.119542 -105.081324) (xy 435.247542 -105.081324)
				(xy 437.872886 -107.706668) (xy 438.372758 -107.706668) (xy 438.658 -107.421426)
				(arc
					(start 438.658 -104.412034)
					(mid 436.740471 -99.810113)
					(end 440.693556 -96.772476)
				)
				(arc
					(start 441.963556 -96.772476)
					(mid 443.368251 -97.021201)
					(end 444.602108 -97.737168)
				)
				(arc
					(start 446.301114 -97.737168)
					(mid 448.365739 -97.903538)
					(end 450.08419 -99.06)
				)
				(xy 452.698358 -99.06) (xy 453.644 -98.114358)
				(arc
					(start 453.644 -97.372932)
					(mid 453.639755 -95.446334)
					(end 454.518014 -93.731588)
				)
				(arc
					(start 454.518014 -93.731588)
					(mid 458.122443 -90.568332)
					(end 462.254092 -93.002862)
				)
				(arc
					(start 466.34908 -97.09785)
					(mid 469.447742 -101.094045)
					(end 466.29574 -105.048304)
				)
				(xy 465.73186 -105.612184) (xy 465.73186 -105.88371) (xy 465.945474 -106.097324) (xy 468.635334 -106.097324)
				(xy 471.475054 -108.937044) (xy 471.475054 -118.129558)
				(arc
					(start 470.530428 -119.07393)
					(mid 470.495082 -119.32431)
					(end 470.444322 -119.572024)
				)
				(xy 470.444322 -122.972576) (xy 471.329512 -123.857766) (xy 475.57563 -123.857766) (xy 476.279464 -124.5616)
				(xy 478.617026 -124.5616)
				(arc
					(start 479.135948 -124.042678)
					(mid 479.865929 -122.479408)
					(end 481.153724 -121.331228)
				)
				(arc
					(start 481.153724 -121.331228)
					(mid 482.28907 -119.144483)
					(end 484.47452 -118.006622)
				)
				(arc
					(start 484.47452 -118.006622)
					(mid 484.942455 -117.130785)
					(end 485.607614 -116.393468)
				)
				(arc
					(start 485.607614 -116.393214)
					(mid 487.405691 -115.48787)
					(end 489.417868 -115.549934)
				)
				(xy 489.417868 -119.14505) (xy 489.418122 -119.145304) (xy 489.418122 -169.853102)
				(arc
					(start 485.607868 -169.853102)
					(mid 482.826011 -169.127892)
					(end 481.208588 -166.751254)
				)
				(arc
					(start 481.208588 -166.751254)
					(mid 480.747679 -166.471568)
					(end 480.323652 -166.138606)
				)
				(arc
					(start 480.323652 -166.138606)
					(mid 476.375823 -165.041049)
					(end 475.360746 -161.071306)
				)
				(arc
					(start 475.360746 -159.652462)
					(mid 473.903249 -154.613179)
					(end 478.603564 -152.284176)
				)
				(xy 479.24847 -152.284176)
				(arc
					(start 479.599752 -151.932894)
					(mid 479.723227 -151.651637)
					(end 479.867468 -151.380444)
				)
				(arc
					(start 479.867468 -150.409656)
					(mid 479.454788 -149.418971)
					(end 479.314002 -148.35505)
				)
				(arc
					(start 479.314002 -145.814796)
					(mid 479.3275 -145.482995)
					(end 479.36785 -145.15338)
				)
				(arc
					(start 479.36785 -144.121378)
					(mid 478.62366 -143.100585)
					(end 478.226374 -141.901418)
				)
				(xy 477.702626 -141.37767) (xy 477.648778 -141.377924) (xy 476.080836 -141.377924) (xy 475.795086 -141.663674)
				(xy 475.795086 -141.91361)
				(arc
					(start 476.115126 -142.23365)
					(mid 477.663007 -144.491502)
					(end 477.440244 -147.219924)
				)
				(arc
					(start 477.440244 -147.219924)
					(mid 476.640695 -151.489875)
					(end 472.449398 -152.631902)
				)
				(arc
					(start 471.176096 -152.631902)
					(mid 466.24688 -154.476644)
					(end 463.581496 -149.938486)
				)
				(xy 463.581496 -149.169882) (xy 462.393538 -147.981924)
				(arc
					(start 460.883 -147.981924)
					(mid 456.793329 -143.992252)
					(end 460.680562 -139.805156)
				)
				(xy 460.983076 -139.502642) (xy 460.983076 -139.063222) (xy 460.77632 -138.856466)
				(arc
					(start 460.158084 -138.856466)
					(mid 458.054525 -140.510556)
					(end 455.378566 -140.510006)
				)
				(arc
					(start 455.378566 -140.510006)
					(mid 455.095031 -140.636128)
					(end 454.802748 -140.740384)
				)
				(arc
					(start 454.802748 -141.230096)
					(mid 454.732419 -141.985394)
					(end 454.523856 -142.714726)
				)
				(arc
					(start 454.523856 -142.714726)
					(mid 455.57333 -144.109631)
					(end 455.945748 -145.81505)
				)
				(arc
					(start 455.945748 -148.35505)
					(mid 455.943245 -148.496614)
					(end 455.935842 -148.638006)
				)
				(arc
					(start 456.878182 -149.580346)
					(mid 457.399264 -149.604943)
					(end 457.912978 -149.695662)
				)
				(arc
					(start 457.912978 -149.695662)
					(mid 463.32226 -151.100687)
					(end 462.28 -156.591508)
				)
				(arc
					(start 462.28 -159.076898)
					(mid 463.686042 -162.561436)
					(end 461.655922 -165.723316)
				)
				(xy 461.018636 -166.360602) (xy 461.018636 -168.4782)
				(arc
					(start 461.82153 -169.281094)
					(mid 465.969816 -173.259009)
					(end 467.496144 -178.799998)
				)
				(arc
					(start 467.496144 -184.794398)
					(mid 456.674982 -195.61556)
					(end 445.85382 -184.794398)
				)
				(arc
					(start 445.85382 -178.799998)
					(mid 447.076717 -173.802975)
					(end 450.469 -169.935398)
				)
				(arc
					(start 450.469 -168.377362)
					(mid 449.972325 -167.609876)
					(end 449.658486 -166.751254)
				)
				(arc
					(start 449.658486 -166.751254)
					(mid 447.419824 -163.949166)
					(end 447.951606 -160.40227)
				)
				(arc
					(start 447.951606 -157.200092)
					(mid 447.811093 -156.594848)
					(end 447.7639 -155.975304)
				)
				(xy 447.7639 -155.278328)
				(arc
					(start 445.326008 -152.840436)
					(mid 443.21465 -150.703751)
					(end 443.13221 -147.701)
				)
				(arc
					(start 443.13221 -147.701)
					(mid 443.505022 -144.140897)
					(end 446.536572 -142.23746)
				)
				(arc
					(start 446.70726 -142.066772)
					(mid 446.680366 -141.92509)
					(end 446.658492 -141.782546)
				)
				(xy 446.503298 -141.627352)
				(arc
					(start 436.855108 -143.678148)
					(mid 436.442278 -144.169253)
					(end 435.957726 -144.589754)
				)
				(arc
					(start 435.957726 -144.589754)
					(mid 434.850607 -146.752579)
					(end 432.712114 -147.905978)
				)
				(xy 431.8 -148.818092)
				(arc
					(start 431.8 -151.059642)
					(mid 432.43098 -153.783291)
					(end 431.165 -156.27604)
				)
				(arc
					(start 431.165 -159.450278)
					(mid 431.851931 -163.848288)
					(end 428.117 -166.269924)
				)
				(xy 427.11878 -166.269924)
				(arc
					(start 425.706286 -167.682418)
					(mid 421.58541 -169.844565)
					(end 418.108638 -166.751254)
				)
				(arc
					(start 418.108638 -166.751254)
					(mid 415.861639 -163.917699)
					(end 416.43681 -160.347406)
				)
				(arc
					(start 416.43681 -157.306772)
					(mid 416.304881 -156.832663)
					(end 416.230816 -156.346144)
				)
				(xy 415.524696 -155.640024) (xy 413.348932 -155.640024)
				(arc
					(start 400.42211 -164.034724)
					(mid 399.590484 -165.33719)
					(end 398.334992 -166.238174)
				)
				(xy 397.750792 -166.822374) (xy 397.750792 -168.674542)
				(arc
					(start 397.924528 -168.848278)
					(mid 402.704878 -172.837186)
					(end 404.496016 -178.799998)
				)
				(arc
					(start 404.496016 -184.794398)
					(mid 393.674854 -195.61556)
					(end 382.853692 -184.794398)
				)
				(xy 382.853692 -180.589174) (xy 381.178816 -178.914298) (xy 377.509786 -178.914298) (xy 372.201186 -182.361586)
				(xy 372.156482 -182.572152) (xy 369.14328 -184.529222) (xy 369.143026 -184.529222) (xy 367.35385 -185.691272)
				(xy 367.353596 -185.691272) (xy 366.461294 -186.270646) (xy 366.250474 -186.225942) (xy 344.53957 -200.325228)
				(xy 317.397638 -206.093568) (xy 316.507622 -206.983584) (xy 316.507622 -209.0039)
				(arc
					(start 317.356998 -209.853276)
					(mid 320.306634 -211.671953)
					(end 320.802 -215.101678)
				)
				(xy 320.802 -216.86012) (xy 322.737988 -218.796108) (xy 332.944978 -219.747592) (xy 336.673444 -216.019126)
				(arc
					(start 336.673444 -214.193628)
					(mid 335.71734 -211.585507)
					(end 336.64779 -208.968086)
				)
				(arc
					(start 336.64779 -208.968086)
					(mid 340.718603 -205.459948)
					(end 344.750898 -209.012282)
				)
				(arc
					(start 348.107508 -212.368892)
					(mid 350.823921 -214.235685)
					(end 351.282 -217.499692)
				)
				(xy 351.282 -220.38691) (xy 352.833432 -221.938342)
				(arc
					(start 396.009622 -227.231702)
					(mid 400.014236 -225.276816)
					(end 403.4282 -228.141022)
				)
				(xy 426.960538 -231.026208)
				(arc
					(start 430.260252 -227.726494)
					(mid 435.145977 -224.795462)
					(end 438.221374 -229.591616)
				)
				(xy 438.221374 -230.961692) (xy 439.693812 -232.43413) (xy 440.6138 -232.54716) (xy 440.746388 -232.716324)
				(xy 449.62064 -233.80446)
				(arc
					(start 451.12432 -233.80446)
					(mid 451.577882 -233.498652)
					(end 452.068184 -233.256074)
				)
				(xy 452.068184 -232.96118) (xy 451.841616 -232.734612)
				(arc
					(start 451.731888 -232.734612)
					(mid 451.234045 -232.828935)
					(end 450.728334 -232.860596)
				)
				(arc
					(start 448.641216 -232.860596)
					(mid 447.995802 -232.91152)
					(end 447.350388 -232.860596)
				)
				(arc
					(start 447.04254 -232.860596)
					(mid 445.487134 -232.551189)
					(end 444.16853 -231.670098)
				)
				(arc
					(start 440.930792 -228.43236)
					(mid 440.667003 -228.141884)
					(end 440.432444 -227.827332)
				)
				(xy 440.069986 -227.464874) (xy 439.561478 -227.464874) (xy 439.561478 -226.449636) (xy 436.819548 -223.707706)
				(xy 436.819548 -222.22968)
				(arc
					(start 435.438042 -220.848174)
					(mid 432.083904 -219.219783)
					(end 431.444654 -215.546432)
				)
				(arc
					(start 431.444654 -214.07755)
					(mid 430.367368 -211.375854)
					(end 431.35804 -208.641188)
				)
				(arc
					(start 431.35804 -208.641188)
					(mid 435.308482 -205.459878)
					(end 439.316622 -208.568036)
				)
				(arc
					(start 442.639958 -211.891372)
					(mid 444.312023 -212.578205)
					(end 445.52489 -213.918546)
				)
				(xy 447.00444 -215.398096) (xy 454.146158 -215.398096) (xy 455.156062 -216.408) (xy 459.504542 -216.408)
				(xy 460.48803 -215.424512)
				(arc
					(start 463.034634 -215.424512)
					(mid 463.101343 -215.245055)
					(end 463.176366 -215.068912)
				)
				(arc
					(start 463.176366 -214.263224)
					(mid 461.92151 -211.50567)
					(end 462.908142 -208.641188)
				)
				(arc
					(start 462.908142 -208.641188)
					(mid 466.784195 -205.461436)
					(end 470.82837 -208.424272)
				)
				(xy 472.797632 -210.393534) (xy 480.71786 -210.393534) (xy 486.738422 -216.414096) (xy 489.418122 -216.414096)
				(arc
					(start 489.418122 -286.016954)
					(mid 487.530939 -286.560586)
					(end 485.607868 -286.161988)
				)
				(arc
					(start 485.607868 -286.161988)
					(mid 484.665686 -285.537462)
					(end 483.930452 -284.678882)
				)
				(arc
					(start 483.930452 -284.678882)
					(mid 482.18749 -283.57026)
					(end 481.208588 -281.751278)
				)
				(arc
					(start 481.208588 -281.751278)
					(mid 480.777421 -281.492037)
					(end 480.378008 -281.186128)
				)
				(arc
					(start 480.378008 -281.186128)
					(mid 476.296729 -280.019997)
					(end 475.447614 -275.861272)
				)
				(arc
					(start 475.447614 -274.771358)
					(mid 473.840276 -269.826571)
					(end 478.384362 -267.299694)
				)
				(xy 479.392996 -266.29106)
				(arc
					(start 479.392996 -264.15492)
					(mid 479.333803 -263.756942)
					(end 479.314002 -263.355074)
				)
				(arc
					(start 479.314002 -260.815074)
					(mid 479.332969 -260.421582)
					(end 479.389694 -260.031738)
				)
				(arc
					(start 479.389694 -259.143246)
					(mid 478.66961 -258.187486)
					(end 478.256854 -257.064256)
				)
				(xy 477.540066 -256.347468) (xy 475.440756 -256.347468) (xy 475.366334 -256.346706) (xy 475.288356 -256.424684)
				(xy 475.288356 -256.788412)
				(arc
					(start 475.36227 -256.862326)
					(mid 477.54088 -259.170653)
					(end 477.412558 -262.342122)
				)
				(arc
					(start 477.412558 -262.342122)
					(mid 476.528287 -266.617207)
					(end 472.28887 -267.659104)
				)
				(arc
					(start 471.195908 -267.659104)
					(mid 468.395967 -269.699055)
					(end 465.035138 -268.859)
				)
				(arc
					(start 463.907378 -268.859)
					(mid 463.276259 -270.483641)
					(end 462.026 -271.697958)
				)
				(arc
					(start 462.026 -273.810476)
					(mid 463.655388 -276.485559)
					(end 462.915 -279.529032)
				)
				(arc
					(start 462.915 -284.959044)
					(mid 466.28287 -288.821171)
					(end 467.496144 -293.799768)
				)
				(arc
					(start 467.496144 -299.794168)
					(mid 456.674982 -310.61533)
					(end 445.85382 -299.794168)
				)
				(arc
					(start 445.85382 -293.799768)
					(mid 446.489112 -290.146516)
					(end 448.320414 -286.92221)
				)
				(arc
					(start 448.320414 -280.673556)
					(mid 447.267818 -277.660036)
					(end 448.486784 -274.70989)
				)
				(arc
					(start 448.486784 -273.297142)
					(mid 447.948796 -272.191068)
					(end 447.7639 -270.975074)
				)
				(arc
					(start 447.7639 -268.435074)
					(mid 447.820123 -267.759422)
					(end 447.987166 -267.102336)
				)
				(xy 447.987166 -266.768072)
				(arc
					(start 445.339724 -264.12063)
					(mid 442.871263 -261.219138)
					(end 443.865 -257.541522)
				)
				(arc
					(start 443.865 -255.822958)
					(mid 442.100689 -253.505415)
					(end 442.326014 -250.60148)
				)
				(arc
					(start 442.326014 -248.878852)
					(mid 442.071416 -248.487039)
					(end 441.86348 -248.068592)
				)
				(xy 438.492646 -246.86006) (xy 437.713882 -246.86006) (xy 437.127396 -247.446546)
				(arc
					(start 437.127396 -249.933968)
					(mid 437.531235 -250.915556)
					(end 437.668924 -251.968)
				)
				(arc
					(start 437.668924 -255.778)
					(mid 437.230955 -257.619684)
					(end 436.010812 -259.067046)
				)
				(arc
					(start 436.010812 -259.067046)
					(mid 434.733201 -261.80272)
					(end 431.927 -262.916924)
				)
				(arc
					(start 429.387 -262.916924)
					(mid 425.315381 -259.222963)
					(end 428.596806 -254.812038)
				)
				(xy 429.487076 -253.921768)
				(arc
					(start 429.487076 -251.968)
					(mid 429.579836 -251.102031)
					(end 429.853852 -250.275344)
				)
				(xy 429.62068 -250.042172) (xy 429.22952 -250.042172) (xy 428.982124 -250.289568)
				(arc
					(start 428.982124 -250.7742)
					(mid 427.348785 -254.044664)
					(end 423.753026 -254.70358)
				)
				(xy 423.491406 -254.70358) (xy 423.2529 -254.942086)
				(arc
					(start 423.2529 -256.23012)
					(mid 423.182571 -256.985418)
					(end 422.974008 -257.71475)
				)
				(arc
					(start 422.974008 -257.71475)
					(mid 424.023482 -259.109655)
					(end 424.3959 -260.815074)
				)
				(xy 424.3959 -261.16026)
				(arc
					(start 427.469808 -264.234168)
					(mid 431.943263 -266.231554)
					(end 431.292 -271.087088)
				)
				(arc
					(start 431.292 -274.534376)
					(mid 431.810775 -278.872155)
					(end 428.117 -281.204924)
				)
				(arc
					(start 426.151548 -281.204924)
					(mid 422.360189 -284.865836)
					(end 418.108638 -281.751278)
				)
				(arc
					(start 418.108638 -281.751278)
					(mid 415.868616 -278.944119)
					(end 416.407346 -275.393404)
				)
				(arc
					(start 416.407346 -272.217642)
					(mid 416.262661 -271.603831)
					(end 416.214052 -270.975074)
				)
				(arc
					(start 416.214052 -268.435074)
					(mid 416.441467 -267.090352)
					(end 417.098226 -265.895074)
				)
				(arc
					(start 417.098226 -265.895074)
					(mid 416.65027 -265.193)
					(end 416.353752 -264.414762)
				)
				(arc
					(start 416.353752 -264.414762)
					(mid 415.985829 -264.400153)
					(end 415.620708 -264.352532)
				)
				(arc
					(start 415.620708 -264.352532)
					(mid 411.951347 -262.600259)
					(end 411.607 -258.548632)
				)
				(arc
					(start 411.607 -255.463294)
					(mid 410.425293 -253.437309)
					(end 410.550868 -251.095256)
				)
				(xy 410.550868 -249.162062) (xy 409.637738 -248.248932) (xy 406.42413 -247.248426) (xy 406.02027 -247.248426)
				(xy 405.439372 -247.829324)
				(arc
					(start 405.439372 -249.630692)
					(mid 405.985167 -250.743155)
					(end 406.172924 -251.968)
				)
				(arc
					(start 406.172924 -255.778)
					(mid 405.734955 -257.619684)
					(end 404.514812 -259.067046)
				)
				(arc
					(start 404.514812 -259.067046)
					(mid 403.237201 -261.80272)
					(end 400.431 -262.916924)
				)
				(arc
					(start 397.891 -262.916924)
					(mid 393.800076 -258.826)
					(end 397.891 -254.735076)
				)
				(xy 397.991076 -254.735076)
				(arc
					(start 397.991076 -251.968)
					(mid 398.08051 -251.117298)
					(end 398.344898 -250.303792)
				)
				(xy 398.344898 -250.107196) (xy 398.149572 -249.91187)
				(arc
					(start 397.692118 -249.91187)
					(mid 397.604196 -250.039055)
					(end 397.511524 -250.162822)
				)
				(arc
					(start 397.511524 -250.8504)
					(mid 395.930477 -254.080907)
					(end 392.409426 -254.814324)
				)
				(xy 392.008614 -254.814324) (xy 391.702798 -255.12014)
				(arc
					(start 391.702798 -256.23012)
					(mid 391.632469 -256.985418)
					(end 391.423906 -257.71475)
				)
				(arc
					(start 391.423906 -257.71475)
					(mid 392.47338 -259.109655)
					(end 392.845798 -260.815074)
				)
				(xy 392.845798 -261.754874)
				(arc
					(start 395.472666 -264.381742)
					(mid 400.403464 -266.155928)
					(end 399.542 -271.325086)
				)
				(arc
					(start 399.542 -274.249896)
					(mid 400.662575 -277.747252)
					(end 398.526 -280.734262)
				)
				(arc
					(start 398.526 -284.12694)
					(mid 402.883333 -288.11636)
					(end 404.496016 -293.799768)
				)
				(arc
					(start 404.496016 -299.794168)
					(mid 393.674854 -310.61533)
					(end 382.853692 -299.794168)
				)
				(arc
					(start 382.853692 -293.799768)
					(mid 383.398986 -290.408)
					(end 384.979926 -287.358074)
				)
				(arc
					(start 384.979926 -280.361136)
					(mid 384.168914 -277.944712)
					(end 384.805936 -275.476716)
				)
				(arc
					(start 384.805936 -272.043398)
					(mid 384.699616 -271.513932)
					(end 384.66395 -270.975074)
				)
				(arc
					(start 384.66395 -268.435074)
					(mid 384.891365 -267.090352)
					(end 385.548124 -265.895074)
				)
				(arc
					(start 385.548124 -265.895074)
					(mid 385.105805 -265.204167)
					(end 384.810254 -264.438892)
				)
				(arc
					(start 384.810254 -264.438892)
					(mid 384.402453 -264.408385)
					(end 383.99974 -264.337292)
				)
				(arc
					(start 383.99974 -264.337292)
					(mid 380.528224 -262.570179)
					(end 380.111 -258.697222)
				)
				(arc
					(start 380.111 -255.524762)
					(mid 378.626357 -253.462638)
					(end 378.645928 -250.921774)
				)
				(xy 378.645928 -248.945146) (xy 377.832874 -248.132092) (xy 375.68886 -247.500902) (xy 374.979946 -247.500902)
				(xy 374.549924 -247.930924)
				(arc
					(start 374.549924 -255.778)
					(mid 374.111955 -257.619684)
					(end 372.891812 -259.067046)
				)
				(arc
					(start 372.891812 -259.067046)
					(mid 371.614201 -261.80272)
					(end 368.808 -262.916924)
				)
				(arc
					(start 366.268 -262.916924)
					(mid 362.213574 -259.371242)
					(end 365.18723 -254.880364)
				)
				(xy 366.368076 -253.699518)
				(arc
					(start 366.368076 -251.968)
					(mid 366.509454 -250.901816)
					(end 366.923828 -249.90933)
				)
				(xy 366.719866 -249.705368)
				(arc
					(start 366.197388 -249.705368)
					(mid 366.010544 -249.997647)
					(end 365.799624 -250.273058)
				)
				(arc
					(start 365.792512 -250.305062)
					(mid 365.009989 -253.129776)
					(end 362.538518 -254.705612)
				)
				(xy 360.727498 -256.516632)
				(arc
					(start 360.727498 -258.734814)
					(mid 361.151272 -259.736811)
					(end 361.29595 -260.815074)
				)
				(xy 361.29595 -263.34847)
				(arc
					(start 362.46435 -264.51687)
					(mid 362.8841 -264.552264)
					(end 363.297978 -264.630662)
				)
				(arc
					(start 363.297978 -264.630662)
					(mid 368.3978 -265.609765)
					(end 368.427 -270.802608)
				)
				(arc
					(start 368.427 -274.882864)
					(mid 368.594075 -279.064449)
					(end 364.998 -281.204924)
				)
				(xy 363.587792 -281.204924)
				(arc
					(start 362.928154 -281.864562)
					(mid 358.924531 -284.874797)
					(end 355.008688 -281.751278)
				)
				(arc
					(start 355.008688 -281.751278)
					(mid 352.777957 -278.978298)
					(end 353.270058 -275.453602)
				)
				(arc
					(start 353.270058 -272.093944)
					(mid 353.153272 -271.540045)
					(end 353.114102 -270.975328)
				)
				(arc
					(start 353.114102 -268.435074)
					(mid 353.341517 -267.090352)
					(end 353.998276 -265.895074)
				)
				(arc
					(start 353.998276 -265.895074)
					(mid 353.54432 -265.181019)
					(end 353.246944 -264.388854)
				)
				(arc
					(start 353.246944 -264.388854)
					(mid 352.920053 -264.370408)
					(end 352.595688 -264.325862)
				)
				(arc
					(start 352.595688 -264.325862)
					(mid 348.691101 -262.223988)
					(end 348.996 -257.800094)
				)
				(arc
					(start 348.996 -255.502664)
					(mid 347.42873 -253.365392)
					(end 347.500702 -250.716034)
				)
				(xy 347.500702 -249.075448) (xy 346.03055 -247.605296) (xy 344.419428 -247.00103)
				(arc
					(start 340.732364 -247.00103)
					(mid 340.617879 -247.262256)
					(end 340.485476 -247.514872)
				)
				(arc
					(start 340.485476 -248.170954)
					(mid 342.351495 -249.675928)
					(end 343.053924 -251.968)
				)
				(arc
					(start 343.053924 -255.778)
					(mid 342.615955 -257.619684)
					(end 341.395812 -259.067046)
				)
				(arc
					(start 341.395812 -259.067046)
					(mid 340.118201 -261.80272)
					(end 337.312 -262.916924)
				)
				(arc
					(start 334.772 -262.916924)
					(mid 330.705746 -259.274593)
					(end 333.880206 -254.833374)
				)
				(xy 334.872076 -253.841504)
				(arc
					(start 334.872076 -251.967492)
					(mid 334.937592 -251.238532)
					(end 335.131918 -250.5329)
				)
				(xy 335.131918 -250.188984) (xy 335.01203 -250.069096) (xy 334.664304 -250.069096)
				(arc
					(start 334.428084 -250.305316)
					(mid 333.260544 -253.523097)
					(end 330.055982 -254.72644)
				)
				(xy 328.80046 -255.981962)
				(arc
					(start 328.80046 -258.199382)
					(mid 329.502258 -259.424424)
					(end 329.745848 -260.815074)
				)
				(xy 329.745848 -262.965184)
				(arc
					(start 331.324966 -264.544302)
					(mid 331.564751 -264.580415)
					(end 331.801978 -264.630662)
				)
				(arc
					(start 331.801978 -264.630662)
					(mid 336.9018 -265.609765)
					(end 336.931 -270.802608)
				)
				(arc
					(start 336.931 -274.882864)
					(mid 337.580949 -277.427349)
					(end 336.55 -279.842722)
				)
				(arc
					(start 336.55 -284.71241)
					(mid 340.179536 -288.626645)
					(end 341.496142 -293.799768)
				)
				(arc
					(start 341.496142 -299.794168)
					(mid 330.67498 -310.61533)
					(end 319.853818 -299.794168)
				)
				(arc
					(start 319.853818 -293.799768)
					(mid 320.437235 -290.294568)
					(end 322.124578 -287.16732)
				)
				(arc
					(start 322.124578 -280.678382)
					(mid 321.076555 -278.090065)
					(end 321.763644 -275.383498)
				)
				(arc
					(start 321.763644 -272.237454)
					(mid 321.614219 -271.614109)
					(end 321.564 -270.975074)
				)
				(arc
					(start 321.564 -268.435074)
					(mid 321.711666 -267.346119)
					(end 322.143882 -266.335764)
				)
				(xy 322.143882 -265.64717) (xy 321.79641 -265.299698) (xy 321.371976 -265.299698) (xy 318.649604 -268.021816)
				(arc
					(start 227.762308 -268.021816)
					(mid 226.218511 -267.717217)
					(end 224.906078 -266.849098)
				)
				(arc
					(start 224.906078 -266.849098)
					(mid 223.947537 -261.552208)
					(end 229.068376 -259.8928)
				)
				(xy 231.650032 -259.8928) (xy 234.061 -257.481832)
				(arc
					(start 234.061 -253.775718)
					(mid 233.550686 -251.915467)
					(end 233.378756 -249.994166)
				)
				(xy 233.378756 -244.50421) (xy 231.30383 -242.429284) (xy 228.775768 -242.429284) (xy 225.748088 -242.829334)
				(xy 225.617278 -242.999514) (xy 224.561146 -243.139468) (xy 224.560384 -243.140484) (xy 223.50095 -243.280184)
				(xy 223.500696 -243.280438) (xy 222.781876 -243.37518) (xy 222.443802 -243.419884) (xy 222.443548 -243.420138)
				(xy 222.130366 -243.46154) (xy 222.059754 -243.470938) (xy 222.0595 -243.470938) (xy 220.681296 -243.652548)
				(xy 219.329 -245.004844)
				(arc
					(start 219.329 -246.000524)
					(mid 219.217845 -249.112312)
					(end 216.948258 -251.2441)
				)
				(arc
					(start 216.948258 -251.2441)
					(mid 215.444676 -252.808767)
					(end 213.35238 -253.384304)
				)
				(arc
					(start 212.763862 -253.384304)
					(mid 211.102435 -254.271643)
					(end 209.219546 -254.320294)
				)
				(xy 207.912208 -254.320294) (xy 203.745338 -250.153424) (xy 198.390256 -250.153424) (xy 196.45757 -252.08611)
				(arc
					(start 196.45757 -254.309372)
					(mid 196.80669 -257.268376)
					(end 195.055744 -259.679186)
				)
				(arc
					(start 195.055744 -259.679186)
					(mid 195.067482 -262.770051)
					(end 192.913254 -264.986516)
				)
				(arc
					(start 190.096902 -267.802868)
					(mid 190.133624 -268.11726)
					(end 190.145924 -268.43355)
				)
				(arc
					(start 190.145924 -270.975074)
					(mid 190.058081 -271.818029)
					(end 189.798452 -272.624804)
				)
				(arc
					(start 189.798452 -275.483828)
					(mid 190.250359 -276.514913)
					(end 190.431166 -277.626064)
				)
				(arc
					(start 190.431166 -277.626064)
					(mid 190.007379 -284.249425)
					(end 183.858662 -281.751278)
				)
				(arc
					(start 183.858662 -281.751278)
					(mid 183.433025 -281.495764)
					(end 183.038242 -281.194764)
				)
				(arc
					(start 183.038242 -281.194764)
					(mid 179.146529 -280.180039)
					(end 178.004978 -276.323552)
				)
				(arc
					(start 178.004978 -274.626578)
					(mid 176.602321 -269.846275)
					(end 180.858414 -267.256768)
				)
				(xy 182.044848 -266.070334)
				(arc
					(start 182.044848 -264.16381)
					(mid 181.98432 -263.761453)
					(end 181.964076 -263.355074)
				)
				(arc
					(start 181.964076 -260.815074)
					(mid 182.034405 -260.059776)
					(end 182.242968 -259.330444)
				)
				(arc
					(start 182.242968 -259.330444)
					(mid 181.463866 -258.431509)
					(end 180.97627 -257.34645)
				)
				(xy 179.942744 -256.312924) (xy 178.205638 -256.312924) (xy 178.023266 -256.495296) (xy 178.023266 -256.788666)
				(arc
					(start 178.13147 -256.89687)
					(mid 180.248373 -259.209895)
					(end 180.105558 -262.342122)
				)
				(arc
					(start 180.105558 -262.342122)
					(mid 179.404898 -266.413413)
					(end 175.512476 -267.79728)
				)
				(arc
					(start 173.809152 -267.79728)
					(mid 166.460847 -267.076167)
					(end 171.645072 -261.818882)
				)
				(xy 171.967144 -261.818882) (xy 172.320204 -261.465822) (xy 172.320204 -261.162038) (xy 172.04309 -260.884924)
				(arc
					(start 170.434 -260.884924)
					(mid 166.577121 -258.157871)
					(end 167.86225 -253.612396)
				)
				(arc
					(start 167.86225 -250.812808)
					(mid 167.676238 -250.355121)
					(end 167.546782 -249.878342)
				)
				(xy 166.982902 -249.314462) (xy 165.234112 -249.314462)
				(arc
					(start 162.696398 -251.852176)
					(mid 161.624185 -255.00089)
					(end 158.56712 -256.311908)
				)
				(xy 158.003748 -256.87528) (xy 158.003748 -258.254246) (xy 158.307786 -258.558284)
				(arc
					(start 158.899352 -258.558284)
					(mid 165.474002 -259.098825)
					(end 162.98164 -265.206734)
				)
				(xy 159.891222 -268.297152)
				(arc
					(start 159.891222 -278.85898)
					(mid 160.368125 -280.585464)
					(end 160.061656 -282.35021)
				)
				(xy 160.061656 -282.79725)
				(arc
					(start 160.285684 -283.021278)
					(mid 167.30907 -286.495618)
					(end 170.145964 -293.799768)
				)
				(arc
					(start 170.145964 -299.794422)
					(mid 169.923527 -301.977212)
					(end 169.265346 -304.070258)
				)
				(xy 169.265346 -305.222148) (xy 169.52087 -305.477672) (xy 170.004486 -305.477672) (xy 180.537866 -294.944292)
				(xy 187.228734 -294.944292) (xy 189.100714 -293.072312)
				(arc
					(start 189.100714 -290.548314)
					(mid 188.895141 -289.623953)
					(end 188.907674 -288.677096)
				)
				(arc
					(start 188.907674 -288.677096)
					(mid 192.084478 -284.299182)
					(end 196.826632 -286.901128)
				)
				(xy 198.22541 -288.299906)
				(arc
					(start 200.728072 -288.299906)
					(mid 201.629173 -288.124453)
					(end 202.546712 -288.154364)
				)
				(arc
					(start 202.546712 -288.154364)
					(mid 203.367123 -288.160713)
					(end 204.169772 -288.33064)
				)
				(arc
					(start 208.903316 -288.33064)
					(mid 211.5312 -287.374769)
					(end 214.159084 -288.33064)
				)
				(xy 230.844344 -288.33064) (xy 237.71987 -295.206166)
				(arc
					(start 240.412524 -295.206166)
					(mid 241.737642 -294.986999)
					(end 243.06276 -295.206166)
				)
				(xy 244.710204 -295.206166) (xy 245.237 -294.67937) (xy 245.237 -293.886382) (xy 245.236746 -293.886128)
				(xy 245.236746 -293.534592) (xy 244.437408 -292.735254) (xy 237.562644 -292.735254) (xy 236.306614 -291.479224)
				(xy 235.392976 -291.479224) (xy 235.392976 -290.565586) (xy 234.822746 -289.995356) (xy 234.822746 -284.280356)
				(xy 234.073446 -283.531056) (xy 234.073446 -278.596344) (xy 231.67721 -276.200108)
				(arc
					(start 215.152478 -276.200108)
					(mid 209.955726 -272.2626)
					(end 215.152478 -268.325092)
				)
				(xy 255.176274 -268.325092)
				(arc
					(start 259.004054 -272.152618)
					(mid 259.366369 -272.569753)
					(end 259.66674 -273.03349)
				)
				(xy 259.993638 -273.360388) (xy 260.29793 -273.360388)
				(arc
					(start 260.29793 -273.834606)
					(mid 260.34392 -273.882875)
					(end 260.389116 -273.931888)
				)
				(arc
					(start 260.470396 -273.931888)
					(mid 261.963529 -274.225954)
					(end 263.233662 -275.06422)
				)
				(xy 264.61466 -275.06422)
				(arc
					(start 264.61466 -276.067774)
					(mid 265.270261 -276.773117)
					(end 265.74877 -277.608792)
				)
				(arc
					(start 265.74877 -277.608792)
					(mid 266.40375 -278.774481)
					(end 266.630912 -280.09215)
				)
				(arc
					(start 266.630912 -281.14625)
					(mid 266.547913 -281.950216)
					(end 266.30249 -282.720288)
				)
				(arc
					(start 266.30249 -282.720288)
					(mid 266.123716 -284.18581)
					(end 265.43635 -285.492444)
				)
				(arc
					(start 265.43635 -285.492444)
					(mid 265.384594 -285.851551)
					(end 265.301222 -286.20466)
				)
				(arc
					(start 265.301222 -286.20466)
					(mid 265.747954 -288.324595)
					(end 265.049254 -290.37534)
				)
				(xy 265.049254 -293.678356) (xy 261.293356 -297.434254) (xy 255.596644 -297.434254) (xy 253.645924 -299.384974)
				(xy 253.645924 -311.597802) (xy 255.23571 -313.187588) (xy 276.752304 -313.187588) (xy 277.620476 -312.319416)
				(xy 277.620476 -310.31561) (xy 277.300182 -309.995316)
				(arc
					(start 275.822918 -309.995316)
					(mid 270.741559 -311.416458)
					(end 268.487144 -306.645818)
				)
				(arc
					(start 268.487144 -306.645818)
					(mid 268.428051 -306.058494)
					(end 268.454124 -305.468782)
				)
				(arc
					(start 268.454124 -305.468782)
					(mid 267.765117 -300.805702)
					(end 271.925796 -298.590208)
				)
				(arc
					(start 271.925796 -298.590208)
					(mid 272.793824 -298.555036)
					(end 273.649694 -298.704)
				)
				(xy 274.540218 -298.704) (xy 275.082 -298.162218)
				(arc
					(start 275.082 -296.237914)
					(mid 275.026875 -294.546958)
					(end 275.482558 -292.917626)
				)
				(arc
					(start 275.482558 -288.819844)
					(mid 275.342681 -287.442854)
					(end 275.635466 -286.090106)
				)
				(arc
					(start 275.635466 -286.090106)
					(mid 276.108633 -281.992928)
					(end 279.75687 -280.069036)
				)
				(arc
					(start 281.457146 -280.069036)
					(mid 282.199987 -280.131932)
					(end 282.92171 -280.318718)
				)
				(arc
					(start 282.92171 -280.318718)
					(mid 283.643302 -280.131922)
					(end 284.38602 -280.069036)
				)
				(arc
					(start 286.086804 -280.069036)
					(mid 289.735091 -281.992893)
					(end 290.208208 -286.090106)
				)
				(arc
					(start 290.208208 -286.090106)
					(mid 290.086047 -289.574689)
					(end 287.476438 -291.887148)
				)
				(xy 286.23133 -293.132256) (xy 286.23133 -293.990268) (xy 287.616138 -295.375076)
				(arc
					(start 293.5986 -295.375076)
					(mid 296.545202 -296.595598)
					(end 297.765724 -299.5422)
				)
				(arc
					(start 297.765724 -301.9806)
					(mid 296.545202 -304.927202)
					(end 293.5986 -306.147724)
				)
				(xy 293.522908 -306.147724) (xy 292.025324 -307.645308) (xy 292.025324 -311.755536) (xy 293.457376 -313.187588)
				(xy 316.118748 -313.187588) (xy 325.733664 -322.802758) (xy 325.733664 -350.73844) (xy 328.1426 -353.147376)
				(xy 418.389054 -353.147376)
				(arc
					(start 424.17111 -358.929432)
					(mid 425.32533 -359.139999)
					(end 426.372274 -359.669588)
				)
				(arc
					(start 426.372274 -359.669588)
					(mid 426.835156 -359.755032)
					(end 427.28515 -359.893108)
				)
				(arc
					(start 427.28515 -359.893108)
					(mid 428.187064 -359.7665)
					(end 429.094646 -359.842562)
				)
				(xy 429.435768 -359.842562)
				(arc
					(start 432.728878 -356.549452)
					(mid 435.971573 -352.282775)
					(end 440.65444 -354.888292)
				)
				(arc
					(start 441.488576 -355.722428)
					(mid 442.295943 -355.964961)
					(end 443.036452 -356.367842)
				)
				(arc
					(start 447.093086 -356.367842)
					(mid 450.769038 -357.280036)
					(end 452.187564 -360.79176)
				)
				(arc
					(start 452.187564 -360.79176)
					(mid 452.542158 -361.461775)
					(end 452.769478 -362.18495)
				)
				(xy 454.058528 -363.474)
				(arc
					(start 454.589134 -363.474)
					(mid 455.350166 -363.318609)
					(end 456.12685 -363.309916)
				)
				(arc
					(start 456.12685 -363.309916)
					(mid 459.404429 -363.736474)
					(end 461.296512 -366.446562)
				)
				(arc
					(start 461.296512 -366.446562)
					(mid 461.792538 -367.26538)
					(end 462.084674 -368.177064)
				)
				(arc
					(start 463.42681 -369.5192)
					(mid 465.784398 -370.211919)
					(end 467.319614 -372.130574)
				)
				(xy 467.607142 -372.418102) (xy 469.475058 -372.418102)
				(arc
					(start 469.996774 -371.896386)
					(mid 471.91972 -367.292267)
					(end 476.880428 -366.75695)
				)
				(arc
					(start 476.880428 -366.75695)
					(mid 478.021609 -367.479593)
					(end 478.922334 -368.486182)
				)
				(arc
					(start 479.982022 -369.54587)
					(mid 485.240896 -372.396285)
					(end 482.60762 -377.767088)
				)
				(arc
					(start 482.60762 -377.767088)
					(mid 480.041078 -377.890197)
					(end 477.858836 -376.533664)
				)
				(xy 476.750888 -376.533664)
				(arc
					(start 476.468186 -376.816366)
					(mid 476.068364 -379.102538)
					(end 474.57106 -380.875794)
				)
				(arc
					(start 474.57106 -380.875794)
					(mid 473.709975 -380.423941)
					(end 472.750134 -380.267972)
				)
				(arc
					(start 466.25002 -380.267972)
					(mid 464.106074 -381.156024)
					(end 463.218022 -383.29997)
				)
				(xy 463.218022 -383.96799) (xy 419.731952 -383.96799)
				(arc
					(start 419.731952 -381)
					(mid 419.278199 -379.404487)
					(end 418.052758 -378.286518)
				)
				(arc
					(start 418.052758 -377.546362)
					(mid 417.751454 -376.299064)
					(end 417.83 -375.0183)
				)
				(arc
					(start 417.83 -374.083326)
					(mid 416.77323 -372.342513)
					(end 416.687 -370.30787)
				)
				(xy 416.687 -366.141254) (xy 415.772854 -365.227108) (xy 357.130096 -365.227108)
				(arc
					(start 355.858064 -366.49914)
					(mid 355.862287 -367.663345)
					(end 355.602032 -368.798094)
				)
				(arc
					(start 355.602032 -370.901976)
					(mid 355.890192 -372.777791)
					(end 355.47173 -374.628918)
				)
				(arc
					(start 355.47173 -377.350782)
					(mid 355.987119 -378.709881)
					(end 356.11562 -380.157736)
				)
				(xy 356.11562 -383.96799) (xy 318.18199 -383.96799)
				(arc
					(start 318.18199 -383.29997)
					(mid 317.293938 -381.156024)
					(end 315.149992 -380.267972)
				)
				(arc
					(start 308.649878 -380.267972)
					(mid 307.68992 -380.42395)
					(end 306.828698 -380.875794)
				)
				(arc
					(start 306.828698 -380.875794)
					(mid 305.502931 -379.432688)
					(end 304.926238 -377.559824)
				)
				(arc
					(start 304.926492 -377.55957)
					(mid 306.098014 -374.198232)
					(end 309.360062 -372.773448)
				)
				(xy 311.293256 -372.773448) (xy 312.870088 -371.196616) (xy 312.870088 -365.47933) (xy 311.37098 -363.980222)
				(arc
					(start 308.2925 -363.980222)
					(mid 306.239046 -363.965568)
					(end 304.451512 -362.954824)
				)
				(arc
					(start 304.451512 -362.954824)
					(mid 303.886468 -362.830739)
					(end 303.34458 -362.62818)
				)
				(xy 278.782018 -362.62818)
				(arc
					(start 278.782018 -361.00004)
					(mid 277.893966 -358.856094)
					(end 275.75002 -357.968042)
				)
				(arc
					(start 273.45005 -357.968042)
					(mid 271.306104 -358.856094)
					(end 270.418052 -361.00004)
				)
				(xy 270.418052 -382.158494) (xy 268.608556 -383.96799) (xy 254.032004 -383.96799)
				(arc
					(start 254.032004 -381)
					(mid 253.143952 -378.856054)
					(end 251.000006 -377.968002)
				)
				(arc
					(start 199.00011 -377.968002)
					(mid 196.856164 -378.856054)
					(end 195.968112 -381)
				)
				(xy 195.968112 -383.96799) (xy 184.381902 -383.96799)
				(arc
					(start 184.381902 -383.29997)
					(mid 183.49385 -381.156024)
					(end 181.349904 -380.267972)
				)
				(arc
					(start 174.850044 -380.267972)
					(mid 172.706098 -381.156024)
					(end 171.818046 -383.29997)
				)
				(xy 171.818046 -383.96799) (xy 128.331976 -383.96799)
				(arc
					(start 128.331976 -381)
					(mid 127.443924 -378.856054)
					(end 125.299978 -377.968002)
				)
				(xy 90.76436 -377.968002) (xy 82.16392 -369.367308) (xy 64.48933 -369.367308) (xy 63.947548 -369.90909)
				(arc
					(start 63.947548 -370.305838)
					(mid 64.487073 -372.345354)
					(end 64.153796 -374.428512)
				)
				(arc
					(start 64.153796 -377.5075)
					(mid 64.606166 -378.79627)
					(end 64.715644 -380.157736)
				)
				(arc
					(start 64.715644 -380.157736)
					(mid 64.379542 -381.778107)
					(end 63.561976 -383.216912)
				)
				(xy 63.561976 -383.96799) (xy 26.782014 -383.96799)
				(arc
					(start 26.782014 -383.29997)
					(mid 25.893962 -381.156024)
					(end 23.750016 -380.267972)
				)
				(arc
					(start 17.249902 -380.267972)
					(mid 15.105956 -381.156024)
					(end 14.217904 -383.29997)
				)
				(xy 14.217904 -383.96799) (xy 5.031994 -383.96799) (xy 5.031994 -372.332758)
				(arc
					(start 6.04012 -371.324632)
					(mid 6.711513 -369.572933)
					(end 8.062214 -368.271044)
				)
				(arc
					(start 8.062468 -368.271298)
					(mid 9.479474 -367.72)
					(end 10.999724 -367.693956)
				)
				(arc
					(start 11.516614 -367.693956)
					(mid 15.993086 -364.541137)
					(end 20.599146 -367.501424)
				)
				(xy 21.270722 -368.173)
				(arc
					(start 22.870414 -368.173)
					(mid 23.647744 -367.161351)
					(end 24.69896 -366.438434)
				)
				(arc
					(start 24.69896 -366.438434)
					(mid 25.188453 -364.237772)
					(end 26.769568 -362.63072)
				)
				(arc
					(start 26.769568 -362.63072)
					(mid 26.693866 -362.190615)
					(end 26.668476 -361.744768)
				)
				(arc
					(start 26.668476 -358.206548)
					(mid 26.490523 -357.009446)
					(end 26.668476 -355.812344)
				)
				(xy 26.668476 -329.331828) (xy 48.406812 -307.593492) (xy 82.330036 -307.593492) (xy 85.503766 -304.419762)
				(xy 85.503766 -295.345358) (xy 83.45297 -293.294562) (xy 83.45297 -279.452324) (xy 81.800192 -277.799546)
				(arc
					(start 81.800192 -272.474182)
					(mid 82.843662 -268.419752)
					(end 86.905846 -267.406628)
				)
				(arc
					(start 87.445596 -267.406628)
					(mid 87.743035 -266.611583)
					(end 88.198198 -265.895074)
				)
				(arc
					(start 88.198198 -265.895074)
					(mid 87.541384 -264.699815)
					(end 87.314024 -263.355074)
				)
				(arc
					(start 87.314024 -260.815074)
					(mid 87.384353 -260.059776)
					(end 87.592916 -259.330444)
				)
				(arc
					(start 87.592916 -259.330444)
					(mid 86.555714 -257.962048)
					(end 86.171532 -256.28854)
				)
				(arc
					(start 86.171532 -256.28854)
					(mid 85.949107 -256.306812)
					(end 85.726016 -256.312924)
				)
				(xy 83.60537 -256.312924) (xy 83.447382 -256.470912) (xy 83.447382 -256.777744)
				(arc
					(start 83.613244 -256.943606)
					(mid 85.667472 -259.307969)
					(end 85.44687 -262.432292)
				)
				(arc
					(start 85.44687 -262.432292)
					(mid 84.156927 -266.959153)
					(end 79.460344 -267.274294)
				)
				(arc
					(start 79.460344 -267.274294)
					(mid 71.876926 -267.158674)
					(end 77.411072 -261.972552)
				)
				(xy 77.724508 -261.659116) (xy 77.724508 -261.149084) (xy 77.460348 -260.884924)
				(arc
					(start 75.819 -260.884924)
					(mid 71.80902 -257.603767)
					(end 74.2315 -253.023624)
				)
				(arc
					(start 74.2315 -251.698506)
					(mid 73.169618 -250.469976)
					(end 72.6694 -248.92508)
				)
				(xy 72.298306 -248.553986) (xy 70.898766 -248.553986)
				(arc
					(start 69.235574 -248.807478)
					(mid 68.73562 -249.427704)
					(end 68.124324 -249.93854)
				)
				(arc
					(start 68.124324 -250.401074)
					(mid 68.098581 -250.85761)
					(end 68.021708 -251.308362)
				)
				(arc
					(start 68.021708 -251.308362)
					(mid 67.792885 -253.645256)
					(end 66.316606 -255.471168)
				)
				(xy 66.316606 -256.234692)
				(arc
					(start 67.232022 -257.150108)
					(mid 70.470531 -258.893141)
					(end 70.999858 -262.532622)
				)
				(arc
					(start 70.999858 -262.532622)
					(mid 70.108415 -266.81513)
					(end 65.856612 -267.843)
				)
				(arc
					(start 63.90259 -267.843)
					(mid 63.934935 -268.138253)
					(end 63.94577 -268.435074)
				)
				(arc
					(start 63.94577 -270.975074)
					(mid 63.706098 -272.354754)
					(end 63.015114 -273.572732)
				)
				(arc
					(start 63.015114 -274.711922)
					(mid 63.888088 -276.058417)
					(end 64.231012 -277.626064)
				)
				(arc
					(start 64.231012 -277.626064)
					(mid 63.807225 -284.249425)
					(end 57.658508 -281.751278)
				)
				(arc
					(start 57.658508 -281.751278)
					(mid 57.244051 -281.503352)
					(end 56.858662 -281.21229)
				)
				(arc
					(start 56.858662 -281.21229)
					(mid 52.544946 -279.608771)
					(end 52.45354 -275.007578)
				)
				(arc
					(start 52.45354 -275.007578)
					(mid 50.423558 -269.823315)
					(end 55.44439 -267.417296)
				)
				(xy 55.791862 -267.417296)
				(arc
					(start 55.9308 -267.278358)
					(mid 56.051997 -266.926941)
					(end 56.204612 -266.587986)
				)
				(arc
					(start 56.204612 -265.201908)
					(mid 55.875623 -264.304413)
					(end 55.763922 -263.355074)
				)
				(arc
					(start 55.763922 -260.815074)
					(mid 55.834251 -260.059776)
					(end 56.042814 -259.330444)
				)
				(arc
					(start 56.042814 -259.330444)
					(mid 55.182189 -258.298274)
					(end 54.702456 -257.04292)
				)
				(xy 53.97246 -256.312924) (xy 52.159916 -256.312924) (xy 51.942238 -256.530602) (xy 51.942238 -256.785618)
				(arc
					(start 52.083716 -256.927096)
					(mid 54.1601 -259.274461)
					(end 53.965602 -262.40232)
				)
				(arc
					(start 53.965602 -262.40232)
					(mid 53.186482 -266.478931)
					(end 49.243742 -267.775436)
				)
				(arc
					(start 47.711106 -267.775436)
					(mid 40.326642 -267.009951)
					(end 45.68952 -261.876286)
				)
				(xy 46.079664 -261.876286) (xy 46.166532 -261.789418) (xy 46.166532 -261.007606) (xy 46.04385 -260.884924)
				(arc
					(start 44.323 -260.884924)
					(mid 40.536133 -258.341674)
					(end 41.457626 -253.874016)
				)
				(arc
					(start 41.457626 -249.835924)
					(mid 41.317819 -249.415908)
					(end 41.2242 -248.983246)
				)
				(xy 40.534336 -248.293382) (xy 38.587172 -248.293382)
				(arc
					(start 37.882322 -248.473468)
					(mid 37.3182 -249.286168)
					(end 36.574476 -249.93854)
				)
				(arc
					(start 36.574476 -250.401328)
					(mid 36.411987 -251.53897)
					(end 35.937698 -252.585728)
				)
				(arc
					(start 35.937698 -252.585728)
					(mid 35.464054 -254.060232)
					(end 34.476182 -255.252982)
				)
				(xy 34.476182 -256.12598)
				(arc
					(start 35.506406 -257.156204)
					(mid 39.018663 -258.77975)
					(end 39.605966 -262.60425)
				)
				(arc
					(start 39.605966 -262.60425)
					(mid 39.009047 -266.441422)
					(end 35.474656 -268.050264)
				)
				(arc
					(start 32.392874 -271.132046)
					(mid 32.211494 -272.189429)
					(end 31.76143 -273.163284)
				)
				(arc
					(start 31.76143 -275.060664)
					(mid 32.420934 -276.271793)
					(end 32.681164 -277.626064)
				)
				(arc
					(start 32.681164 -277.626064)
					(mid 34.030189 -279.712952)
					(end 33.922208 -282.195524)
				)
				(xy 33.922208 -282.710382)
				(arc
					(start 34.228278 -283.016452)
					(mid 41.289497 -286.474485)
					(end 44.145962 -293.799768)
				)
				(arc
					(start 44.145962 -299.794168)
					(mid 33.3248 -310.61533)
					(end 22.503638 -299.794168)
				)
				(xy 22.503638 -281.074114)
				(arc
					(start 22.598126 -280.979626)
					(mid 20.335053 -278.401825)
					(end 20.83054 -275.007578)
				)
				(arc
					(start 20.83054 -275.007578)
					(mid 18.648901 -270.287803)
					(end 22.862032 -267.240512)
				)
				(arc
					(start 24.740362 -265.362182)
					(mid 24.347882 -264.392546)
					(end 24.214074 -263.355074)
				)
				(arc
					(start 24.214074 -260.815074)
					(mid 24.284403 -260.059776)
					(end 24.492966 -259.330444)
				)
				(arc
					(start 24.492966 -259.330444)
					(mid 23.455366 -257.960994)
					(end 23.071582 -256.286254)
				)
				(arc
					(start 23.071582 -256.286254)
					(mid 22.839171 -256.306227)
					(end 22.606 -256.312924)
				)
				(arc
					(start 20.198588 -256.312924)
					(mid 20.118511 -256.531659)
					(end 20.026122 -256.745486)
				)
				(arc
					(start 20.026122 -256.745486)
					(mid 22.464531 -259.07958)
					(end 22.317964 -262.45185)
				)
				(arc
					(start 22.317964 -262.45185)
					(mid 21.007209 -266.93818)
					(end 16.3449 -267.266166)
				)
				(arc
					(start 16.3449 -267.266166)
					(mid 9.919546 -268.796947)
					(end 10.414 -262.210296)
				)
				(arc
					(start 10.414 -260.186678)
					(mid 8.728786 -255.81139)
					(end 12.259818 -252.726698)
				)
				(arc
					(start 12.259818 -252.726698)
					(mid 12.269015 -251.647669)
					(end 12.560046 -250.608592)
				)
				(arc
					(start 12.560046 -250.608592)
					(mid 9.811482 -244.920654)
					(end 15.922498 -243.319808)
				)
				(arc
					(start 21.059902 -243.319808)
					(mid 22.058547 -242.422084)
					(end 23.294086 -241.896138)
				)
				(arc
					(start 24.06142 -241.128804)
					(mid 23.935327 -239.665458)
					(end 24.311356 -238.24565)
				)
				(xy 24.311356 -237.433866)
				(arc
					(start 23.726902 -236.849412)
					(mid 22.84883 -236.070089)
					(end 22.228302 -235.073444)
				)
				(arc
					(start 22.228302 -235.073444)
					(mid 21.9621 -235.002816)
					(end 21.701252 -234.91444)
				)
				(arc
					(start 21.701252 -234.91444)
					(mid 21.124465 -234.950584)
					(end 20.548346 -234.905042)
				)
				(xy 18.402046 -234.905042) (xy 17.807178 -234.310174) (xy 16.676878 -234.310174) (xy 16.676878 -233.179874)
				(arc
					(start 16.208502 -232.711498)
					(mid 15.668486 -232.823095)
					(end 15.118334 -232.860596)
				)
				(arc
					(start 13.031216 -232.860596)
					(mid 12.385802 -232.91152)
					(end 11.740388 -232.860596)
				)
				(arc
					(start 11.43254 -232.860596)
					(mid 9.877134 -232.551189)
					(end 8.55853 -231.670098)
				)
				(xy 5.842254 -228.954076) (xy 2.032 -228.954076) (xy 2.032 -215.144096) (xy 6.268974 -215.144096)
				(xy 7.228332 -214.184738)
				(arc
					(start 7.228332 -213.09838)
					(mid 6.851189 -210.783002)
					(end 7.808214 -208.641188)
				)
				(arc
					(start 7.808214 -208.641188)
					(mid 12.559666 -205.531575)
					(end 15.839694 -210.166966)
				)
				(xy 17.507204 -211.834476)
				(arc
					(start 18.675604 -211.834476)
					(mid 21.133189 -212.654936)
					(end 22.604984 -214.787226)
				)
				(xy 23.237698 -215.41994) (xy 30.966664 -215.41994) (xy 31.96082 -216.414096) (xy 34.1884 -216.414096)
				(xy 34.737548 -215.864948) (xy 34.737548 -212.791548)
				(arc
					(start 39.078154 -208.450942)
					(mid 42.439553 -205.427779)
					(end 46.532546 -207.34782)
				)
				(arc
					(start 46.532546 -207.34782)
					(mid 48.130595 -208.636905)
					(end 48.900842 -210.540092)
				)
				(arc
					(start 50.217578 -211.856828)
					(mid 53.4299 -214.056948)
					(end 53.345588 -217.949526)
				)
				(xy 55.439056 -220.042994) (xy 55.439056 -228.533706) (xy 54.05628 -229.916482) (xy 54.043326 -229.963726)
				(xy 54.043326 -232.227374) (xy 53.523388 -232.227374) (xy 53.217826 -232.532936) (xy 53.217826 -233.827574)
				(xy 51.923188 -233.827574) (xy 50.921158 -234.829604) (xy 48.213772 -234.829604) (xy 47.244 -235.799376)
				(xy 47.244 -237.195106) (xy 49.541938 -237.195106)
				(arc
					(start 58.076846 -235.014008)
					(mid 60.620146 -233.072217)
					(end 63.78321 -233.555794)
				)
				(xy 80.034892 -229.402386) (xy 137.713974 -221.325186) (xy 139.7 -219.33916)
				(arc
					(start 139.7 -217.936318)
					(mid 139.439962 -214.468228)
					(end 141.942566 -212.05317)
				)
				(arc
					(start 143.041624 -210.954112)
					(mid 143.353436 -209.799785)
					(end 143.985742 -208.784952)
				)
				(arc
					(start 143.985742 -208.784952)
					(mid 149.078172 -205.663098)
					(end 151.855424 -210.951318)
				)
				(xy 151.855424 -211.957666)
				(arc
					(start 152.896316 -212.998558)
					(mid 154.436343 -214.52512)
					(end 154.979624 -216.624408)
				)
				(xy 156.98216 -218.626944) (xy 162.489896 -217.855546)
				(arc
					(start 163.468304 -216.877138)
					(mid 163.515628 -216.033052)
					(end 163.735512 -215.21674)
				)
				(arc
					(start 163.735512 -214.09406)
					(mid 162.571876 -211.36351)
					(end 163.561014 -208.564988)
				)
				(arc
					(start 163.561014 -208.564988)
					(mid 167.987155 -205.407507)
					(end 171.638976 -209.4357)
				)
				(xy 174.037752 -211.834476)
				(arc
					(start 174.123604 -211.834476)
					(mid 175.396445 -212.037503)
					(end 176.542954 -212.626448)
				)
				(xy 178.268376 -212.626448) (xy 178.978814 -211.91601)
				(arc
					(start 178.978814 -203.999846)
					(mid 180.002541 -199.405579)
					(end 182.88 -195.680584)
				)
				(xy 182.88 -194.332098)
				(arc
					(start 181.511194 -192.963292)
					(mid 179.038445 -191.272881)
					(end 178.380644 -188.350652)
				)
				(arc
					(start 178.380644 -188.350652)
					(mid 178.770036 -185.689025)
					(end 180.728366 -183.844946)
				)
				(xy 181.371748 -183.201564) (xy 181.371748 -182.404512) (xy 173.382178 -177.217832) (xy 171.435014 -177.217832)
				(xy 170.145964 -178.506882)
				(arc
					(start 170.145964 -184.794398)
					(mid 159.324802 -195.61556)
					(end 148.50364 -184.794398)
				)
				(arc
					(start 148.50364 -178.799998)
					(mid 149.135225 -175.157232)
					(end 150.956264 -171.939712)
				)
				(xy 150.956264 -169.249344) (xy 143.453104 -161.746184) (xy 136.873996 -160.347914)
				(arc
					(start 135.150606 -162.071304)
					(mid 133.319669 -165.314744)
					(end 129.618232 -165.728904)
				)
				(xy 129.554986 -165.728904) (xy 129.055622 -166.228268) (xy 129.055622 -167.292528)
				(arc
					(start 129.686558 -167.923464)
					(mid 138.362301 -172.581434)
					(end 141.825218 -181.799484)
				)
				(arc
					(start 141.825218 -181.799992)
					(mid 137.724647 -191.699647)
					(end 127.824992 -195.800218)
				)
				(arc
					(start 127.824738 -195.800218)
					(mid 114.871092 -187.111659)
					(end 117.995192 -171.829984)
				)
				(xy 117.995192 -166.586408)
				(arc
					(start 117.405912 -165.997128)
					(mid 115.155788 -163.886671)
					(end 115.019836 -160.804606)
				)
				(xy 115.019836 -158.289752) (xy 111.7346 -155.004516)
				(arc
					(start 109.007656 -154.424888)
					(mid 106.291789 -154.785618)
					(end 103.957628 -153.35123)
				)
				(arc
					(start 101.58603 -152.847294)
					(mid 99.776981 -153.562678)
					(end 97.84207 -153.36139)
				)
				(xy 96.549464 -154.653996) (xy 96.549464 -162.841432) (xy 98.339656 -164.631624)
				(arc
					(start 98.339656 -168.168066)
					(mid 104.658558 -171.897265)
					(end 107.14609 -178.799998)
				)
				(arc
					(start 107.14609 -184.794398)
					(mid 96.324928 -195.61556)
					(end 85.503766 -184.794398)
				)
				(arc
					(start 85.503766 -178.799998)
					(mid 85.781916 -176.362312)
					(end 86.602062 -174.049944)
				)
				(xy 86.602062 -166.664894)
				(arc
					(start 85.94979 -166.012622)
					(mid 83.736348 -164.04519)
					(end 83.430872 -161.0995)
				)
				(arc
					(start 83.430872 -159.647128)
					(mid 82.123597 -158.199907)
					(end 81.635092 -156.311854)
				)
				(xy 79.760318 -154.43708)
				(arc
					(start 77.16647 -154.43708)
					(mid 74.323998 -154.476539)
					(end 72.14235 -152.654)
				)
				(arc
					(start 68.887594 -152.654)
					(mid 67.2465 -152.997665)
					(end 65.605406 -152.654)
				)
				(xy 64.928242 -152.654) (xy 63.94577 -153.636472)
				(arc
					(start 63.94577 -155.97505)
					(mid 63.830902 -156.937414)
					(end 63.492888 -157.84576)
				)
				(arc
					(start 63.492888 -160.316164)
					(mid 64.021052 -161.420259)
					(end 64.231012 -162.62604)
				)
				(arc
					(start 64.231012 -162.62604)
					(mid 63.807225 -169.249401)
					(end 57.658508 -166.751254)
				)
				(arc
					(start 57.658508 -166.751254)
					(mid 57.198147 -166.47203)
					(end 56.774588 -166.139622)
				)
				(arc
					(start 56.774588 -166.139622)
					(mid 52.856575 -165.06706)
					(end 51.795426 -161.145982)
				)
				(arc
					(start 51.795426 -159.548068)
					(mid 50.532862 -154.509704)
					(end 55.231284 -152.295352)
				)
				(arc
					(start 55.925974 -152.295352)
					(mid 56.109007 -151.790855)
					(end 56.356504 -151.314658)
				)
				(arc
					(start 56.356504 -150.475442)
					(mid 55.914897 -149.455858)
					(end 55.763922 -148.35505)
				)
				(arc
					(start 55.763922 -145.81505)
					(mid 55.834251 -145.059752)
					(end 56.042814 -144.33042)
				)
				(arc
					(start 56.042814 -144.33042)
					(mid 55.097366 -143.146153)
					(end 54.647846 -141.69898)
				)
				(xy 54.198774 -141.249908) (xy 54.102508 -141.250924) (xy 53.370734 -141.250924) (xy 53.055266 -141.566392)
				(xy 53.055266 -142.239492) (xy 53.229002 -142.413228)
				(arc
					(start 53.229002 -142.832328)
					(mid 54.208925 -144.927916)
					(end 53.895244 -147.219924)
				)
				(arc
					(start 53.895244 -147.219924)
					(mid 53.013047 -151.5769)
					(end 48.676814 -152.555702)
				)
				(arc
					(start 47.67326 -152.555702)
					(mid 44.324686 -154.70422)
					(end 40.734234 -152.990296)
				)
				(arc
					(start 37.578792 -152.990296)
					(mid 36.576173 -153.180328)
					(end 35.557714 -153.11628)
				)
				(xy 32.395922 -156.278072) (xy 32.395922 -160.424622) (xy 44.145962 -172.174662)
				(arc
					(start 44.145962 -184.794398)
					(mid 33.3248 -195.61556)
					(end 22.503638 -184.794398)
				)
				(xy 22.503638 -166.398956) (xy 19.978624 -163.873942)
				(arc
					(start 19.978624 -159.395668)
					(mid 18.985503 -154.357512)
					(end 23.698708 -152.319228)
				)
				(arc
					(start 24.369268 -152.319228)
					(mid 24.495561 -151.943941)
					(end 24.657558 -151.582628)
				)
				(arc
					(start 24.657558 -150.207472)
					(mid 24.326523 -149.307429)
					(end 24.214074 -148.35505)
				)
				(arc
					(start 24.214074 -145.81505)
					(mid 24.284403 -145.059752)
					(end 24.492966 -144.33042)
				)
				(arc
					(start 24.492966 -144.33042)
					(mid 23.544946 -143.141293)
					(end 23.096728 -141.688058)
				)
				(xy 22.65934 -141.25067) (xy 22.607778 -141.250924) (xy 20.476972 -141.250924) (xy 20.357338 -141.370558)
				(xy 20.357338 -141.772386)
				(arc
					(start 20.440142 -141.85519)
					(mid 22.533332 -144.201684)
					(end 22.342602 -147.34032)
				)
				(arc
					(start 22.342602 -147.34032)
					(mid 21.428945 -151.562734)
					(end 17.23771 -152.610312)
				)
				(arc
					(start 16.147542 -152.610312)
					(mid 10.849338 -154.33141)
					(end 8.748522 -149.172168)
				)
				(arc
					(start 8.748522 -142.79118)
					(mid 8.844887 -140.363005)
					(end 10.301478 -138.417808)
				)
				(arc
					(start 10.301478 -134.088886)
					(mid 10.604487 -128.708532)
					(end 15.977616 -128.298194)
				)
				(arc
					(start 21.011896 -128.298194)
					(mid 21.987451 -127.613181)
					(end 23.11908 -127.238506)
				)
				(arc
					(start 24.09825 -126.259336)
					(mid 24.221279 -123.456127)
					(end 26.053796 -121.331228)
				)
				(arc
					(start 26.053796 -121.331228)
					(mid 26.357749 -120.346166)
					(end 26.898346 -119.468392)
				)
				(xy 26.898346 -106.854244) (xy 29.723588 -104.029002) (xy 35.951414 -104.029002) (xy 36.135564 -104.213152)
				(xy 43.384216 -104.213152) (xy 44.143422 -104.972358) (xy 44.541694 -104.972358) (xy 44.791376 -104.722676)
				(xy 44.791376 -101.646228) (xy 44.758864 -101.613716)
				(arc
					(start 44.758864 -98.618294)
					(mid 44.007023 -96.058212)
					(end 44.993814 -93.579188)
				)
				(arc
					(start 44.993814 -93.579188)
					(mid 49.399364 -90.419265)
					(end 53.071268 -94.40799)
				)
				(arc
					(start 55.56504 -96.901762)
					(mid 57.496108 -97.461616)
					(end 58.927238 -98.873818)
				)
				(xy 59.866022 -99.812602) (xy 69.12483 -99.812602) (xy 69.963538 -98.973894)
				(arc
					(start 69.963538 -97.344738)
					(mid 69.941658 -95.394232)
					(end 70.825614 -93.655388)
				)
				(arc
					(start 70.825614 -93.655388)
					(mid 75.006664 -90.478461)
					(end 78.86954 -94.035372)
				)
				(arc
					(start 81.747614 -96.913446)
					(mid 85.496143 -100.782699)
					(end 82.159348 -105.012236)
				)
				(xy 80.287114 -106.88447) (xy 80.287114 -117.348254) (xy 78.904338 -118.731538) (xy 78.891384 -118.778782)
				(xy 78.891384 -122.415554) (xy 77.662278 -123.64466) (xy 72.638158 -123.64466) (xy 72.006714 -124.276104)
				(xy 72.006714 -125.75921) (xy 71.37527 -126.390654) (xy 71.37527 -128.24714) (xy 72.436736 -128.936496)
				(arc
					(start 73.51649 -128.936496)
					(mid 76.637378 -127.481734)
					(end 79.763366 -128.925574)
				)
				(arc
					(start 83.463638 -128.925574)
					(mid 84.55235 -127.861316)
					(end 85.95487 -127.268986)
				)
				(arc
					(start 87.147908 -126.075948)
					(mid 87.357313 -123.368155)
					(end 89.153746 -121.331228)
				)
				(arc
					(start 89.153746 -121.331228)
					(mid 93.941083 -118.015514)
					(end 97.191576 -122.847354)
				)
				(arc
					(start 99.029012 -124.68479)
					(mid 100.1408 -125.413796)
					(end 100.957888 -126.462536)
				)
				(xy 104.887268 -127.296672)
				(arc
					(start 106.242866 -127.296672)
					(mid 109.302617 -126.219729)
					(end 112.18418 -127.709168)
				)
				(arc
					(start 116.392452 -127.709168)
					(mid 117.093167 -127.405014)
					(end 117.83822 -127.236474)
				)
				(arc
					(start 118.763796 -126.310898)
					(mid 118.861216 -123.481216)
					(end 120.703594 -121.331228)
				)
				(arc
					(start 120.703594 -121.331228)
					(mid 125.48242 -118.014127)
					(end 128.744726 -122.830336)
				)
				(arc
					(start 130.61569 -124.7013)
					(mid 132.004033 -125.736468)
					(end 132.83565 -127.255524)
				)
				(xy 134.86765 -129.055876)
				(arc
					(start 136.53897 -129.055876)
					(mid 138.607297 -127.648644)
					(end 141.108176 -127.709168)
				)
				(xy 143.167862 -127.709168)
				(arc
					(start 144.590008 -126.287022)
					(mid 146.47603 -124.469561)
					(end 149.077934 -124.168916)
				)
				(xy 149.488144 -124.168916)
				(arc
					(start 150.607522 -123.049538)
					(mid 151.308806 -122.073691)
					(end 152.253696 -121.331228)
				)
				(arc
					(start 152.253696 -121.331228)
					(mid 157.110584 -118.029677)
					(end 160.261046 -122.985784)
				)
				(arc
					(start 161.848292 -124.57303)
					(mid 163.122063 -125.308629)
					(end 164.050726 -126.449328)
				)
				(arc
					(start 167.44823 -126.449328)
					(mid 169.794721 -126.329456)
					(end 171.820078 -127.520446)
				)
				(arc
					(start 171.820078 -127.520446)
					(mid 172.307103 -127.618285)
					(end 172.778674 -127.774446)
				)
				(arc
					(start 173.902116 -127.774446)
					(mid 175.26363 -126.359074)
					(end 177.127916 -125.74143)
				)
				(arc
					(start 177.61966 -125.249686)
					(mid 177.831577 -124.725724)
					(end 178.11369 -124.235972)
				)
			)
		)
		(polygon
			(pts
				(arc
					(start 377.62307 -220.397578)
					(mid 383.156894 -218.185464)
					(end 380.613666 -212.795866)
				)
				(arc
					(start 376.153934 -208.336134)
					(mid 372.088598 -205.461055)
					(end 368.256566 -208.640426)
				)
				(arc
					(start 368.256566 -208.640426)
					(mid 367.265193 -211.316307)
					(end 368.263932 -213.989412)
				)
				(arc
					(start 368.263932 -215.838532)
					(mid 369.299872 -219.593601)
					(end 373.010176 -220.779848)
				)
				(arc
					(start 373.010176 -220.779848)
					(mid 374.375837 -220.890763)
					(end 375.70156 -220.544644)
				)
				(arc
					(start 375.70156 -220.544644)
					(mid 376.200735 -220.43815)
					(end 376.682762 -220.270324)
				)
				(arc
					(start 376.682762 -220.270324)
					(mid 377.149215 -220.361303)
					(end 377.62307 -220.397578)
				)
			)
		)
		(polygon
			(pts
				(arc
					(start 409.83281 -104.90581)
					(mid 414.494395 -101.590414)
					(end 411.286452 -96.854264)
				)
				(arc
					(start 407.673302 -93.241114)
					(mid 403.5887 -90.463216)
					(end 399.806668 -93.640656)
				)
				(arc
					(start 399.806668 -93.640656)
					(mid 398.815614 -96.338696)
					(end 399.843498 -99.022916)
				)
				(arc
					(start 399.843498 -100.719128)
					(mid 400.807722 -104.548913)
					(end 404.560278 -105.779824)
				)
				(arc
					(start 404.560278 -105.779824)
					(mid 405.925939 -105.890739)
					(end 407.251662 -105.54462)
				)
				(arc
					(start 407.251662 -105.54462)
					(mid 408.087309 -105.328234)
					(end 408.858974 -104.94137)
				)
				(arc
					(start 408.858974 -104.94137)
					(mid 409.346953 -104.952673)
					(end 409.83281 -104.90581)
				)
			)
		)
		(polygon
			(pts
				(arc
					(start 225.603054 -243.964714)
					(mid 221.694343 -245.832644)
					(end 221.653862 -250.1646)
				)
				(arc
					(start 221.653862 -250.1646)
					(mid 223.327019 -252.354111)
					(end 226.0092 -252.986286)
				)
				(arc
					(start 226.0092 -252.986286)
					(mid 226.466274 -253.011908)
					(end 226.923346 -252.986286)
				)
				(arc
					(start 226.923346 -252.986286)
					(mid 229.458321 -252.445316)
					(end 231.159558 -250.48972)
				)
				(arc
					(start 231.159558 -250.48972)
					(mid 231.441713 -246.001229)
					(end 227.431854 -243.964714)
				)
				(arc
					(start 227.431854 -243.964714)
					(mid 226.974528 -243.939092)
					(end 226.5172 -243.964714)
				)
				(arc
					(start 226.5172 -243.964714)
					(mid 226.060128 -243.93912)
					(end 225.603054 -243.964714)
				)
			)
		)
		(polygon
			(pts
				(arc
					(start 110.419388 -93.549216)
					(mid 106.421666 -90.396161)
					(end 102.44709 -93.578426)
				)
				(arc
					(start 102.44709 -93.578426)
					(mid 101.455986 -96.295967)
					(end 102.509574 -98.989896)
				)
				(arc
					(start 102.509574 -100.563934)
					(mid 103.395987 -104.429936)
					(end 107.143804 -105.728262)
				)
				(arc
					(start 107.143804 -105.728262)
					(mid 108.583203 -105.85268)
					(end 109.976158 -105.469182)
				)
				(arc
					(start 109.976158 -105.469182)
					(mid 110.61311 -105.307283)
					(end 111.215932 -105.04551)
				)
				(arc
					(start 111.215932 -105.04551)
					(mid 111.807706 -105.082119)
					(end 112.398556 -105.03281)
				)
				(arc
					(start 112.398556 -105.03281)
					(mid 117.060234 -101.716899)
					(end 113.851182 -96.98101)
				)
			)
		)
		(polygon
			(pts
				(arc
					(start 409.829 -219.96781)
					(mid 414.543668 -216.2426)
					(end 410.46146 -211.83346)
				)
				(arc
					(start 408.305508 -209.677508)
					(mid 405.02626 -205.53921)
					(end 400.397218 -208.079086)
				)
				(arc
					(start 400.397218 -208.079086)
					(mid 398.815361 -211.295713)
					(end 400.373596 -214.523828)
				)
				(arc
					(start 400.373596 -214.523828)
					(mid 399.983521 -218.232125)
					(end 402.763482 -220.71711)
				)
				(arc
					(start 402.763482 -220.71711)
					(mid 406.089635 -221.872057)
					(end 409.081478 -220.015816)
				)
				(arc
					(start 409.081478 -220.015816)
					(mid 409.456339 -220.008945)
					(end 409.829 -219.96781)
				)
			)
		)
		(polygon
			(pts
				(arc
					(start 287.893252 -374.636792)
					(mid 286.368706 -372.638084)
					(end 283.972 -371.879876)
				)
				(xy 278.782018 -371.879876) (xy 278.782018 -382.158494) (xy 280.591514 -383.96799) (xy 291.327078 -383.96799)
				(arc
					(start 291.327078 -380.157736)
					(mid 291.331253 -380.0516)
					(end 291.332666 -379.945392)
				)
				(arc
					(start 291.332666 -378.675392)
					(mid 290.356285 -376.023075)
					(end 287.893252 -374.636792)
				)
			)
		)
		(polygon
			(pts
				(arc
					(start 425.833794 -324.20179)
					(mid 425.833794 -332.38567)
					(end 425.833794 -324.20179)
				)
			)
		)
		(polygon
			(pts
				(arc
					(start 293.5224 -268.83106)
					(mid 293.5224 -277.01494)
					(end 293.5224 -268.83106)
				)
			)
		)
		(polygon
			(pts
				(arc
					(start 212.586062 -255.87706)
					(mid 212.586062 -264.06094)
					(end 212.586062 -255.87706)
				)
			)
		)
		(polygon
			(pts
				(arc
					(start 77.914246 -212.220302)
					(mid 76.657973 -205.897243)
					(end 70.82409 -208.640426)
				)
				(arc
					(start 70.82409 -208.640426)
					(mid 69.851575 -211.703172)
					(end 71.391018 -214.523828)
				)
				(arc
					(start 71.391018 -214.523828)
					(mid 71.417905 -219.034925)
					(end 75.577954 -220.779848)
				)
				(arc
					(start 75.577954 -220.779848)
					(mid 77.26985 -220.849088)
					(end 78.844902 -220.227398)
				)
				(arc
					(start 78.844902 -220.227398)
					(mid 79.178584 -220.111155)
					(end 79.500984 -219.96654)
				)
				(arc
					(start 79.500984 -219.96654)
					(mid 80.139745 -220.017353)
					(end 80.778604 -219.96781)
				)
				(arc
					(start 80.778604 -219.96781)
					(mid 85.505291 -215.925275)
					(end 80.77835 -211.88299)
				)
				(arc
					(start 80.77835 -211.88299)
					(mid 79.513975 -211.882269)
					(end 78.309724 -212.267546)
				)
				(arc
					(start 78.309724 -212.267546)
					(mid 78.112133 -212.241006)
					(end 77.913484 -212.224112)
				)
			)
		)
		(polygon
			(pts
				(arc
					(start 109.496098 -212.03793)
					(mid 108.102663 -205.706158)
					(end 102.336092 -208.668874)
				)
				(arc
					(start 102.336092 -208.668874)
					(mid 101.399264 -211.700177)
					(end 102.91064 -214.489792)
				)
				(arc
					(start 102.91064 -214.489792)
					(mid 102.962469 -218.955453)
					(end 107.067604 -220.714062)
				)
				(arc
					(start 107.067604 -220.714062)
					(mid 108.787218 -220.802944)
					(end 110.391194 -220.176598)
				)
				(arc
					(start 110.391194 -220.176598)
					(mid 110.696023 -220.07172)
					(end 110.99165 -219.943172)
				)
				(arc
					(start 110.99165 -219.943172)
					(mid 111.69543 -220.016651)
					(end 112.40135 -219.96781)
				)
				(arc
					(start 112.40135 -219.96781)
					(mid 117.128624 -215.925651)
					(end 112.401858 -211.88299)
				)
				(arc
					(start 112.401858 -211.88299)
					(mid 111.168016 -211.877398)
					(end 109.988604 -212.23986)
				)
				(arc
					(start 109.988604 -212.23986)
					(mid 109.729693 -212.198511)
					(end 109.468666 -212.17382)
				)
				(arc
					(start 109.468666 -212.17382)
					(mid 109.482957 -212.105991)
					(end 109.496098 -212.03793)
				)
			)
		)
		(polygon
			(pts
				(arc
					(start 18.722848 -96.06661)
					(mid 16.115564 -90.664898)
					(end 10.922508 -93.66631)
				)
				(arc
					(start 10.922508 -93.66631)
					(mid 9.931132 -96.333733)
					(end 10.918698 -99.002596)
				)
				(arc
					(start 10.918698 -99.002596)
					(mid 11.381847 -101.935563)
					(end 13.706348 -103.78313)
				)
				(arc
					(start 13.706348 -103.78313)
					(mid 17.038775 -107.292031)
					(end 21.387308 -105.169208)
				)
				(arc
					(start 21.387308 -105.169208)
					(mid 25.566423 -100.807823)
					(end 20.848574 -97.035874)
				)
				(arc
					(start 20.848574 -97.035874)
					(mid 20.34322 -96.988421)
					(end 19.835876 -97.00387)
				)
				(arc
					(start 19.835876 -97.00387)
					(mid 19.321358 -96.485369)
					(end 18.722848 -96.06661)
				)
			)
		)
		(polygon
			(pts
				(arc
					(start 410.4894 -47.669704)
					(mid 410.4894 -55.853584)
					(end 410.4894 -47.669704)
				)
			)
		)
	)
	(zone
		(net "GND")
		(layer "B.Cu")
		(hatch none 0.5)
		(connect_pads
			(clearance 0.5)
		)
		(min_thickness 0.25)
		(fill yes
			(thermal_gap 0.5)
			(thermal_bridge_width 0.5)
			(island_removal_mode 0)
		)
		(polygon
			(pts
				(xy 68.85686 -117.421406) (xy 68.60286 -117.675406) (xy 68.60286 -119.453406) (xy 68.98386 -119.834406)
				(xy 74.19086 -119.834406) (xy 74.44486 -119.580406) (xy 74.44486 -117.548406) (xy 74.31786 -117.421406)
			)
		)
	)
	(zone
		(layer "B.Cu")
		(hatch none 0.5)
		(connect_pads
			(clearance 0)
		)
		(min_thickness 0.25)
		(keepout
			(tracks not_allowed)
			(vias allowed)
			(pads allowed)
			(copperpour not_allowed)
			(footprints allowed)
		)
		(placement
			(enabled no)
			(sheetname "")
		)
		(fill
			(thermal_gap 0.5)
			(thermal_bridge_width 0.5)
			(island_removal_mode 0)
		)
		(polygon
			(pts
				(arc
					(start 278.23668 -229.145846)
					(mid 277.68804 -229.694486)
					(end 278.23668 -230.243126)
				)
				(arc
					(start 279.636728 -230.243126)
					(mid 280.185368 -229.694486)
					(end 279.636728 -229.145846)
				)
				(arc
					(start 279.141936 -229.145846)
					(mid 279.152757 -229.207852)
					(end 279.158192 -229.27056)
				)
				(xy 279.158954 -229.271322)
				(arc
					(start 279.158954 -229.480618)
					(mid 279.184566 -229.560675)
					(end 279.251918 -229.61092)
				)
				(arc
					(start 279.251918 -229.61092)
					(mid 280.030466 -229.700189)
					(end 279.249632 -229.766876)
				)
				(arc
					(start 279.249632 -229.766876)
					(mid 279.086753 -229.680884)
					(end 279.008586 -229.514146)
				)
				(xy 279.006554 -229.512114)
				(arc
					(start 279.006554 -229.302818)
					(mid 279.001028 -229.223582)
					(end 278.98471 -229.145846)
				)
				(arc
					(start 278.837898 -229.145846)
					(mid 278.856274 -229.206939)
					(end 278.865584 -229.270052)
				)
				(xy 278.866854 -229.271322) (xy 278.866854 -229.512114)
				(arc
					(start 278.864822 -229.514146)
					(mid 278.786577 -229.680809)
					(end 278.623776 -229.766876)
				)
				(arc
					(start 278.623776 -229.766876)
					(mid 277.842915 -229.70019)
					(end 278.62149 -229.61092)
				)
				(arc
					(start 278.62149 -229.61092)
					(mid 278.688775 -229.560627)
					(end 278.714454 -229.480618)
				)
				(arc
					(start 278.714454 -229.302818)
					(mid 278.702457 -229.220889)
					(end 278.667464 -229.145846)
				)
			)
		)
	)
	(zone
		(net "GND")
		(layer "B.Cu")
		(hatch none 0.5)
		(connect_pads
			(clearance 0.5)
		)
		(min_thickness 0.25)
		(fill yes
			(thermal_gap 0.5)
			(thermal_bridge_width 0.5)
			(island_removal_mode 0)
		)
		(polygon
			(pts
				(xy 240.363502 -274.066) (xy 239.135666 -275.293836) (xy 239.135666 -278.922734) (xy 237.8837 -280.1747)
				(xy 237.8837 -281.9527) (xy 238.5568 -282.6258) (xy 240.4872 -282.6258) (xy 240.4872 -277.0886)
				(xy 240.7539 -276.8219) (xy 240.7539 -275.7551) (xy 241.427 -275.082) (xy 242.316 -275.082) (xy 243.078 -275.844)
				(xy 244.348 -275.844) (xy 244.602 -275.59) (xy 244.602 -274.32) (xy 244.348 -274.066)
			)
		)
		(polygon
			(pts
				(xy 240.235994 -276.465792) (xy 240.032794 -276.465792) (xy 240.032794 -276.668992) (xy 240.235994 -276.668992)
			)
		)
		(polygon
			(pts
				(xy 240.235994 -275.856192) (xy 240.032794 -275.856192) (xy 240.032794 -276.059392) (xy 240.235994 -276.059392)
			)
		)
	)
	(zone
		(net "P3V3_IN")
		(layer "B.Cu")
		(hatch none 0.5)
		(connect_pads
			(clearance 0.5)
		)
		(min_thickness 0.25)
		(fill yes
			(thermal_gap 0.5)
			(thermal_bridge_width 0.5)
			(island_removal_mode 0)
		)
		(polygon
			(pts
				(xy 272.215102 -327.9648) (xy 271.654778 -328.525124) (xy 271.654778 -332.63713) (xy 273.586702 -334.569054)
				(xy 279.018746 -334.569054) (xy 280.035 -333.5528) (xy 285.115 -333.5528) (xy 285.369 -333.2988)
				(xy 285.369 -332.0288) (xy 284.988 -331.6478) (xy 278.257 -331.6478) (xy 276.67204 -333.23276) (xy 274.616926 -333.23276)
				(xy 274.233132 -332.848966) (xy 274.233132 -328.14133) (xy 274.056602 -327.9648)
			)
		)
	)
	(zone
		(layer "B.Cu")
		(hatch none 0.5)
		(connect_pads
			(clearance 0)
		)
		(min_thickness 0.25)
		(keepout
			(tracks not_allowed)
			(vias allowed)
			(pads allowed)
			(copperpour not_allowed)
			(footprints allowed)
		)
		(placement
			(enabled no)
			(sheetname "")
		)
		(fill
			(thermal_gap 0.5)
			(thermal_bridge_width 0.5)
			(island_removal_mode 0)
		)
		(polygon
			(pts
				(arc
					(start 103.324914 -293.800022)
					(mid 96.324928 -286.800036)
					(end 89.324942 -293.800022)
				)
				(arc
					(start 89.324942 -299.80001)
					(mid 96.324928 -306.799996)
					(end 103.324914 -299.80001)
				)
			)
		)
	)
	(zone
		(layer "B.Cu")
		(hatch none 0.5)
		(connect_pads
			(clearance 0)
		)
		(min_thickness 0.25)
		(keepout
			(tracks not_allowed)
			(vias allowed)
			(pads allowed)
			(copperpour not_allowed)
			(footprints allowed)
		)
		(placement
			(enabled no)
			(sheetname "")
		)
		(fill
			(thermal_gap 0.5)
			(thermal_bridge_width 0.5)
			(island_removal_mode 0)
		)
		(polygon
			(pts
				(arc
					(start 284.299914 -295.209976)
					(mid 280.550112 -291.460174)
					(end 276.800056 -295.209976)
				)
				(arc
					(start 276.800056 -295.209976)
					(mid 280.550112 -298.960032)
					(end 284.299914 -295.209976)
				)
			)
		)
	)
	(zone
		(net "GND")
		(layer "B.Cu")
		(hatch none 0.5)
		(connect_pads
			(clearance 0.5)
		)
		(min_thickness 0.25)
		(fill yes
			(thermal_gap 0.5)
			(thermal_bridge_width 0.5)
			(island_removal_mode 0)
		)
		(polygon
			(pts
				(xy 303.88433 -346.168726) (xy 303.283112 -346.769944)
				(arc
					(start 303.283112 -347.3704)
					(mid 303.482896 -348.609953)
					(end 303.297336 -349.851726)
				)
				(xy 303.297336 -351.12071) (xy 304.167286 -351.99066) (xy 307.207666 -351.99066) (xy 308.362604 -350.835722)
				(xy 308.362604 -346.863416) (xy 307.667914 -346.168726)
			)
		)
	)
	(zone
		(net "GND")
		(layer "B.Cu")
		(hatch none 0.5)
		(connect_pads
			(clearance 0.5)
		)
		(min_thickness 0.25)
		(fill yes
			(thermal_gap 0.5)
			(thermal_bridge_width 0.5)
			(island_removal_mode 0)
		)
		(polygon
			(pts
				(xy 455.702416 -221.833694) (xy 455.5236 -222.01251) (xy 455.5236 -227.71735) (xy 455.791824 -227.985574)
				(xy 455.791824 -228.833172) (xy 456.276202 -229.31755) (xy 457.130404 -229.31755) (xy 457.139802 -229.326948)
				(xy 458.8256 -227.64115) (xy 458.8256 -222.015304) (xy 458.64399 -221.833694)
			)
		)
	)
	(zone
		(layer "B.Cu")
		(hatch none 0.5)
		(connect_pads
			(clearance 0)
		)
		(min_thickness 0.25)
		(keepout
			(tracks allowed)
			(vias allowed)
			(pads allowed)
			(copperpour allowed)
			(footprints not_allowed)
		)
		(placement
			(enabled no)
			(sheetname "")
		)
		(fill
			(thermal_gap 0.5)
			(thermal_bridge_width 0.5)
			(island_removal_mode 0)
		)
		(polygon
			(pts
				(arc
					(start 417.065714 -39.99992)
					(mid 405.398648 -46.978389)
					(end 398.393666 -58.62955)
				)
				(arc
					(start 398.393666 -58.62955)
					(mid 400.079385 -60.974288)
					(end 400.675094 -63.799974)
				)
				(arc
					(start 400.675094 -69.799962)
					(mid 400.079394 -72.625776)
					(end 398.393666 -74.97064)
				)
				(arc
					(start 398.393666 -74.97064)
					(mid 425.175135 -94.800128)
					(end 451.956424 -74.97064)
				)
				(arc
					(start 451.956424 -74.97064)
					(mid 450.270654 -72.625786)
					(end 449.674996 -69.799962)
				)
				(arc
					(start 449.674996 -63.799974)
					(mid 450.270764 -60.974314)
					(end 451.956424 -58.62955)
				)
				(arc
					(start 451.956424 -58.62955)
					(mid 444.951428 -46.978403)
					(end 433.284376 -39.99992)
				)
			)
		)
	)
	(zone
		(net "P5V_B_4_LL")
		(layer "B.Cu")
		(hatch none 0.5)
		(connect_pads
			(clearance 0.5)
		)
		(min_thickness 0.25)
		(fill yes
			(thermal_gap 0.5)
			(thermal_bridge_width 0.5)
			(island_removal_mode 0)
		)
		(polygon
			(pts
				(xy 443.373764 -108.966) (xy 440.400186 -111.939578) (xy 440.400186 -114.606578) (xy 440.571636 -114.778028)
				(xy 446.153286 -114.778028) (xy 446.623186 -114.308128) (xy 446.623186 -110.288578) (xy 445.300608 -108.966)
			)
		)
	)
	(zone
		(layer "B.Cu")
		(hatch none 0.5)
		(connect_pads
			(clearance 0)
		)
		(min_thickness 0.25)
		(keepout
			(tracks not_allowed)
			(vias allowed)
			(pads allowed)
			(copperpour not_allowed)
			(footprints allowed)
		)
		(placement
			(enabled no)
			(sheetname "")
		)
		(fill
			(thermal_gap 0.5)
			(thermal_bridge_width 0.5)
			(island_removal_mode 0)
		)
		(polygon
			(pts
				(arc
					(start 278.23668 -175.145954)
					(mid 277.68804 -175.694594)
					(end 278.23668 -176.243234)
				)
				(arc
					(start 279.636728 -176.243234)
					(mid 280.185368 -175.694594)
					(end 279.636728 -175.145954)
				)
				(arc
					(start 279.174956 -175.145954)
					(mid 279.162993 -175.185296)
					(end 279.158954 -175.226218)
				)
				(arc
					(start 279.158954 -175.505618)
					(mid 279.184928 -175.577617)
					(end 279.250902 -175.616362)
				)
				(arc
					(start 279.250902 -175.616362)
					(mid 280.030454 -175.696143)
					(end 279.250394 -175.770794)
				)
				(xy 279.240234 -175.770794)
				(arc
					(start 279.237948 -175.768762)
					(mid 279.084132 -175.693216)
					(end 279.008586 -175.5394)
				)
				(xy 279.006554 -175.537114) (xy 279.006554 -175.194722)
				(arc
					(start 279.008078 -175.193198)
					(mid 279.011103 -175.169449)
					(end 279.015698 -175.145954)
				)
				(arc
					(start 278.873204 -175.145954)
					(mid 278.868419 -175.185958)
					(end 278.866854 -175.226218)
				)
				(xy 278.866854 -175.537114)
				(arc
					(start 278.864822 -175.5394)
					(mid 278.789276 -175.693216)
					(end 278.63546 -175.768762)
				)
				(xy 278.633174 -175.770794)
				(arc
					(start 278.623014 -175.770794)
					(mid 277.842954 -175.696143)
					(end 278.622506 -175.616362)
				)
				(arc
					(start 278.622506 -175.616362)
					(mid 278.688411 -175.577559)
					(end 278.714454 -175.505618)
				)
				(xy 278.714454 -175.194722) (xy 278.715216 -175.19396) (xy 278.71928 -175.145954)
			)
		)
	)
	(zone
		(layer "B.Cu")
		(hatch none 0.5)
		(connect_pads
			(clearance 0)
		)
		(min_thickness 0.25)
		(keepout
			(tracks not_allowed)
			(vias allowed)
			(pads allowed)
			(copperpour not_allowed)
			(footprints allowed)
		)
		(placement
			(enabled no)
			(sheetname "")
		)
		(fill
			(thermal_gap 0.5)
			(thermal_bridge_width 0.5)
			(island_removal_mode 0)
		)
		(polygon
			(pts
				(arc
					(start 278.23668 -232.745788)
					(mid 277.68804 -233.294428)
					(end 278.23668 -233.843068)
				)
				(arc
					(start 279.636728 -233.843068)
					(mid 280.185368 -233.294428)
					(end 279.636728 -232.745788)
				)
				(arc
					(start 279.141936 -232.745788)
					(mid 279.152757 -232.807794)
					(end 279.158192 -232.870502)
				)
				(xy 279.158954 -232.871264)
				(arc
					(start 279.158954 -233.08056)
					(mid 279.184566 -233.160617)
					(end 279.251918 -233.210862)
				)
				(arc
					(start 279.251918 -233.210862)
					(mid 280.030466 -233.300131)
					(end 279.249632 -233.366818)
				)
				(arc
					(start 279.249632 -233.366818)
					(mid 279.086753 -233.280826)
					(end 279.008586 -233.114088)
				)
				(xy 279.006554 -233.112056)
				(arc
					(start 279.006554 -232.90276)
					(mid 279.001028 -232.823524)
					(end 278.98471 -232.745788)
				)
				(arc
					(start 278.837898 -232.745788)
					(mid 278.856274 -232.806881)
					(end 278.865584 -232.869994)
				)
				(xy 278.866854 -232.871264) (xy 278.866854 -233.112056)
				(arc
					(start 278.864822 -233.114088)
					(mid 278.786577 -233.280751)
					(end 278.623776 -233.366818)
				)
				(arc
					(start 278.623776 -233.366818)
					(mid 277.842915 -233.300132)
					(end 278.62149 -233.210862)
				)
				(arc
					(start 278.62149 -233.210862)
					(mid 278.688775 -233.160569)
					(end 278.714454 -233.08056)
				)
				(arc
					(start 278.714454 -232.90276)
					(mid 278.702457 -232.820831)
					(end 278.667464 -232.745788)
				)
			)
		)
	)
	(zone
		(net "GND")
		(layer "B.Cu")
		(hatch none 0.5)
		(connect_pads
			(clearance 0.5)
		)
		(min_thickness 0.25)
		(fill yes
			(thermal_gap 0.5)
			(thermal_bridge_width 0.5)
			(island_removal_mode 0)
		)
		(polygon
			(pts
				(xy 312.285888 -247.394984) (xy 311.020968 -248.659904) (xy 311.020968 -255.935988) (xy 313.999118 -258.914138)
				(xy 316.261242 -258.914138)
				(arc
					(start 317.44793 -257.727196)
					(mid 317.902546 -257.242447)
					(end 318.42964 -256.837688)
				)
				(arc
					(start 318.42964 -256.108708)
					(mid 316.231919 -253.841375)
					(end 316.303914 -250.684538)
				)
				(arc
					(start 316.303914 -249.103896)
					(mid 316.016651 -248.722421)
					(end 315.776102 -248.309892)
				)
				(xy 314.203842 -247.394984)
			)
		)
	)
	(zone
		(layer "B.Cu")
		(hatch none 0.5)
		(connect_pads
			(clearance 0)
		)
		(min_thickness 0.25)
		(keepout
			(tracks allowed)
			(vias allowed)
			(pads allowed)
			(copperpour allowed)
			(footprints not_allowed)
		)
		(placement
			(enabled no)
			(sheetname "")
		)
		(fill
			(thermal_gap 0.5)
			(thermal_bridge_width 0.5)
			(island_removal_mode 0)
		)
		(polygon
			(pts
				(arc
					(start 89.324942 -184.799986)
					(mid 93.499282 -191.204488)
					(end 101.04374 -189.970664)
				)
				(arc
					(start 101.04374 -189.970664)
					(mid 127.825209 -209.800152)
					(end 154.606498 -189.970664)
				)
				(arc
					(start 154.606498 -189.970664)
					(mid 162.15088 -191.204314)
					(end 166.325042 -184.799986)
				)
				(arc
					(start 166.325042 -178.799998)
					(mid 162.150775 -172.395694)
					(end 154.606498 -173.629574)
				)
				(arc
					(start 154.606498 -173.629574)
					(mid 127.825209 -153.800149)
					(end 101.04374 -173.629574)
				)
				(arc
					(start 101.04374 -173.629574)
					(mid 93.499275 -172.395612)
					(end 89.324942 -178.799998)
				)
			)
		)
	)
	(zone
		(layer "B.Cu")
		(hatch none 0.5)
		(connect_pads
			(clearance 0)
		)
		(min_thickness 0.25)
		(keepout
			(tracks not_allowed)
			(vias allowed)
			(pads allowed)
			(copperpour not_allowed)
			(footprints allowed)
		)
		(placement
			(enabled no)
			(sheetname "")
		)
		(fill
			(thermal_gap 0.5)
			(thermal_bridge_width 0.5)
			(island_removal_mode 0)
		)
		(polygon
			(pts
				(arc
					(start 278.23668 -185.94578)
					(mid 277.68804 -186.49442)
					(end 278.23668 -187.04306)
				)
				(arc
					(start 279.636728 -187.04306)
					(mid 280.185368 -186.49442)
					(end 279.636728 -185.94578)
				)
				(arc
					(start 279.141936 -185.94578)
					(mid 279.152757 -186.007786)
					(end 279.158192 -186.070494)
				)
				(xy 279.158954 -186.071256)
				(arc
					(start 279.158954 -186.280552)
					(mid 279.184566 -186.360609)
					(end 279.251918 -186.410854)
				)
				(arc
					(start 279.251918 -186.410854)
					(mid 280.030466 -186.500123)
					(end 279.249632 -186.56681)
				)
				(arc
					(start 279.249632 -186.56681)
					(mid 279.086753 -186.480818)
					(end 279.008586 -186.31408)
				)
				(xy 279.006554 -186.312048)
				(arc
					(start 279.006554 -186.102752)
					(mid 279.001028 -186.023516)
					(end 278.98471 -185.94578)
				)
				(arc
					(start 278.837898 -185.94578)
					(mid 278.856274 -186.006873)
					(end 278.865584 -186.069986)
				)
				(xy 278.866854 -186.071256) (xy 278.866854 -186.312048)
				(arc
					(start 278.864822 -186.31408)
					(mid 278.786577 -186.480743)
					(end 278.623776 -186.56681)
				)
				(arc
					(start 278.623776 -186.56681)
					(mid 277.842915 -186.500124)
					(end 278.62149 -186.410854)
				)
				(arc
					(start 278.62149 -186.410854)
					(mid 278.688775 -186.360561)
					(end 278.714454 -186.280552)
				)
				(arc
					(start 278.714454 -186.102752)
					(mid 278.702457 -186.020823)
					(end 278.667464 -185.94578)
				)
			)
		)
	)
	(zone
		(layer "B.Cu")
		(hatch none 0.5)
		(connect_pads
			(clearance 0)
		)
		(min_thickness 0.25)
		(keepout
			(tracks not_allowed)
			(vias allowed)
			(pads allowed)
			(copperpour not_allowed)
			(footprints allowed)
		)
		(placement
			(enabled no)
			(sheetname "")
		)
		(fill
			(thermal_gap 0.5)
			(thermal_bridge_width 0.5)
			(island_removal_mode 0)
		)
		(polygon
			(pts
				(arc
					(start 336.55 -13.999972)
					(mid 341.300054 -18.750026)
					(end 346.050108 -13.999972)
				)
				(arc
					(start 346.050108 -13.999972)
					(mid 341.300054 -9.249918)
					(end 336.55 -13.999972)
				)
			)
		)
	)
	(zone
		(net "GND")
		(layer "B.Cu")
		(hatch none 0.5)
		(connect_pads
			(clearance 0.5)
		)
		(min_thickness 0.25)
		(fill yes
			(thermal_gap 0.5)
			(thermal_bridge_width 0.5)
			(island_removal_mode 0)
		)
		(polygon
			(pts
				(xy 341.092282 -55.63743) (xy 343.96045 -36.950142) (xy 343.96045 -36.706556) (xy 343.35212 -36.098226)
				(arc
					(start 342.421464 -36.098226)
					(mid 338.848675 -35.608744)
					(end 336.445606 -32.919924)
				)
				(arc
					(start 334.645 -32.919924)
					(mid 330.554076 -28.829)
					(end 334.645 -24.738076)
				)
				(arc
					(start 337.058 -24.738076)
					(mid 337.60077 -24.77424)
					(end 338.133944 -24.882094)
				)
				(xy 344.79484 -24.882094) (xy 345.57843 -24.098504) (xy 345.57843 -22.827742) (xy 345.100656 -22.349968)
				(arc
					(start 343.243662 -22.349968)
					(mid 341.253317 -22.57312)
					(end 339.265514 -22.328378)
				)
				(arc
					(start 336.77098 -22.328378)
					(mid 335.445453 -23.211796)
					(end 333.883 -23.521924)
				)
				(xy 331.173328 -23.521924) (xy 329.400662 -25.29459)
				(arc
					(start 329.400662 -29.170376)
					(mid 329.658616 -29.974785)
					(end 329.745848 -30.815026)
				)
				(xy 329.745848 -33.355026) (xy 329.744578 -33.458658)
				(arc
					(start 330.803758 -34.517838)
					(mid 331.306438 -34.544978)
					(end 331.801978 -34.633662)
				)
				(arc
					(start 331.801978 -34.633662)
					(mid 336.723735 -35.412248)
					(end 337.24088 -40.36822)
				)
				(arc
					(start 337.24088 -45.456856)
					(mid 336.931778 -49.346782)
					(end 333.502 -51.207924)
				)
				(xy 331.994764 -51.207924) (xy 331.724762 -51.477926) (xy 331.724762 -52.574698)
				(arc
					(start 332.242922 -53.092858)
					(mid 336.394216 -54.613438)
					(end 339.590888 -57.667398)
				)
				(xy 340.162388 -57.667398) (xy 340.576916 -57.25287)
			)
		)
	)
	(zone
		(net "GND")
		(layer "B.Cu")
		(hatch none 0.5)
		(connect_pads
			(clearance 0.5)
		)
		(min_thickness 0.25)
		(fill yes
			(thermal_gap 0.5)
			(thermal_bridge_width 0.5)
			(island_removal_mode 0)
		)
		(polygon
			(pts
				(xy 166.298372 -53.079396) (xy 162.585146 -35.610038) (xy 161.672524 -34.697416) (xy 158.968186 -34.697416)
				(xy 158.21914 -35.446462)
				(arc
					(start 158.21914 -36.720526)
					(mid 158.500543 -37.557332)
					(end 158.595822 -38.435026)
				)
				(arc
					(start 158.595822 -40.975026)
					(mid 158.550235 -41.58405)
					(end 158.414466 -42.179494)
				)
				(arc
					(start 158.414466 -45.787564)
					(mid 158.746067 -46.681839)
					(end 158.881064 -47.626016)
				)
				(arc
					(start 158.881064 -47.626016)
					(mid 159.985816 -49.047737)
					(end 160.37306 -50.806096)
				)
				(arc
					(start 163.303966 -53.737002)
					(mid 164.413657 -54.250097)
					(end 165.458394 -54.885082)
				)
				(xy 165.918388 -54.885082) (xy 166.298372 -54.505098)
			)
		)
	)
	(zone
		(layer "B.Cu")
		(hatch none 0.5)
		(connect_pads
			(clearance 0)
		)
		(min_thickness 0.25)
		(keepout
			(tracks not_allowed)
			(vias allowed)
			(pads allowed)
			(copperpour not_allowed)
			(footprints allowed)
		)
		(placement
			(enabled no)
			(sheetname "")
		)
		(fill
			(thermal_gap 0.5)
			(thermal_bridge_width 0.5)
			(island_removal_mode 0)
		)
		(polygon
			(pts
				(arc
					(start 278.23668 -178.745896)
					(mid 277.68804 -179.294536)
					(end 278.23668 -179.843176)
				)
				(arc
					(start 279.636728 -179.843176)
					(mid 280.185368 -179.294536)
					(end 279.636728 -178.745896)
				)
				(arc
					(start 279.174956 -178.745896)
					(mid 279.162993 -178.785238)
					(end 279.158954 -178.82616)
				)
				(arc
					(start 279.158954 -179.10556)
					(mid 279.184928 -179.177559)
					(end 279.250902 -179.216304)
				)
				(arc
					(start 279.250902 -179.216304)
					(mid 280.030454 -179.296085)
					(end 279.250394 -179.370736)
				)
				(xy 279.240234 -179.370736)
				(arc
					(start 279.237948 -179.368704)
					(mid 279.084132 -179.293158)
					(end 279.008586 -179.139342)
				)
				(xy 279.006554 -179.137056) (xy 279.006554 -178.794664)
				(arc
					(start 279.008078 -178.79314)
					(mid 279.011103 -178.769391)
					(end 279.015698 -178.745896)
				)
				(arc
					(start 278.873204 -178.745896)
					(mid 278.868419 -178.7859)
					(end 278.866854 -178.82616)
				)
				(xy 278.866854 -179.137056)
				(arc
					(start 278.864822 -179.139342)
					(mid 278.789276 -179.293158)
					(end 278.63546 -179.368704)
				)
				(xy 278.633174 -179.370736)
				(arc
					(start 278.623014 -179.370736)
					(mid 277.842954 -179.296085)
					(end 278.622506 -179.216304)
				)
				(arc
					(start 278.622506 -179.216304)
					(mid 278.688411 -179.177501)
					(end 278.714454 -179.10556)
				)
				(xy 278.714454 -178.794664) (xy 278.715216 -178.793902) (xy 278.71928 -178.745896)
			)
		)
	)
	(zone
		(net "GND")
		(layer "B.Cu")
		(hatch none 0.5)
		(connect_pads
			(clearance 0.5)
		)
		(min_thickness 0.25)
		(fill yes
			(thermal_gap 0.5)
			(thermal_bridge_width 0.5)
			(island_removal_mode 0)
		)
		(polygon
			(pts
				(arc
					(start 33.393634 -239.43691)
					(mid 35.324201 -239.472592)
					(end 37.0205 -240.394998)
				)
				(xy 37.465 -240.28146) (xy 37.465 -239.401604) (xy 37.442394 -239.401604) (xy 36.086542 -238.045752)
				(xy 36.079938 -238.045752) (xy 36.079938 -238.039148) (xy 34.864548 -236.823758) (xy 34.864548 -235.620052)
				(arc
					(start 34.118042 -236.366304)
					(mid 34.063803 -237.974258)
					(end 33.393634 -239.43691)
				)
			)
		)
	)
	(zone
		(net "GND")
		(layer "B.Cu")
		(hatch none 0.5)
		(connect_pads
			(clearance 0.5)
		)
		(min_thickness 0.25)
		(fill yes
			(thermal_gap 0.5)
			(thermal_bridge_width 0.5)
			(island_removal_mode 0)
		)
		(polygon
			(pts
				(xy 426.355764 -113.03) (xy 426.176186 -113.209578) (xy 426.176186 -114.987578) (xy 428.716186 -117.527578)
				(xy 431.764186 -117.527578) (xy 431.891186 -117.400578) (xy 431.891186 -116.003578) (xy 432.399186 -115.495324)
				(xy 432.399186 -114.352578) (xy 432.907186 -113.844578) (xy 432.907186 -113.209578) (xy 432.727608 -113.03)
			)
		)
		(polygon
			(pts
				(xy 431.611786 -115.444778) (xy 431.408586 -115.444778) (xy 431.408586 -115.647978) (xy 431.611786 -115.647978)
			)
		)
		(polygon
			(pts
				(xy 431.611786 -114.581178) (xy 431.408586 -114.581178) (xy 431.408586 -114.784378) (xy 431.611786 -114.784378)
			)
		)
		(polygon
			(pts
				(xy 432.322986 -113.615978) (xy 432.119786 -113.615978) (xy 432.119786 -113.819178) (xy 432.322986 -113.819178)
			)
		)
	)
	(zone
		(net "GND")
		(layer "B.Cu")
		(hatch none 0.5)
		(connect_pads
			(clearance 0.5)
		)
		(min_thickness 0.25)
		(fill yes
			(thermal_gap 0.5)
			(thermal_bridge_width 0.5)
			(island_removal_mode 0)
		)
		(polygon
			(pts
				(arc
					(start 293.024306 -209.414872)
					(mid 292.994701 -210.581899)
					(end 292.640512 -211.694268)
				)
				(arc
					(start 292.640512 -211.694268)
					(mid 293.052237 -213.494366)
					(end 292.640512 -215.294464)
				)
				(arc
					(start 292.640512 -215.294464)
					(mid 292.791502 -215.648393)
					(end 292.90899 -216.014808)
				)
				(xy 298.779184 -216.562178) (xy 302.987202 -216.562178) (xy 304.11674 -215.43264) (xy 304.11674 -211.990432)
				(xy 301.54118 -209.414872)
			)
		)
	)
	(zone
		(layer "B.Cu")
		(hatch none 0.5)
		(connect_pads
			(clearance 0)
		)
		(min_thickness 0.25)
		(keepout
			(tracks allowed)
			(vias allowed)
			(pads allowed)
			(copperpour allowed)
			(footprints not_allowed)
		)
		(placement
			(enabled no)
			(sheetname "")
		)
		(fill
			(thermal_gap 0.5)
			(thermal_bridge_width 0.5)
			(island_removal_mode 0)
		)
		(polygon
			(pts
				(arc
					(start 276.800056 -295.209976)
					(mid 280.550112 -298.960032)
					(end 284.299914 -295.209976)
				)
				(arc
					(start 284.299914 -295.209976)
					(mid 280.550112 -291.460174)
					(end 276.800056 -295.209976)
				)
			)
		)
	)
	(zone
		(net "P5V_B_2_LL_R")
		(layer "B.Cu")
		(hatch none 0.5)
		(connect_pads
			(clearance 0.5)
		)
		(min_thickness 0.25)
		(fill yes
			(thermal_gap 0.5)
			(thermal_bridge_width 0.5)
			(island_removal_mode 0)
		)
		(polygon
			(pts
				(xy 55.44566 -118.107206) (xy 55.26786 -118.285006) (xy 55.26786 -119.826532) (xy 55.481982 -120.040654)
				(xy 56.12003 -120.040654) (xy 56.251348 -120.171972) (xy 56.251348 -121.198894) (xy 56.53786 -121.485406)
				(xy 57.273698 -121.485406) (xy 57.527698 -121.231406) (xy 57.527698 -118.284244) (xy 57.35066 -118.107206)
			)
		)
		(polygon
			(pts
				(xy 57.018682 -119.92991) (xy 56.815482 -119.92991) (xy 56.815482 -120.13311) (xy 57.018682 -120.13311)
			)
		)
		(polygon
			(pts
				(xy 57.018682 -119.32031) (xy 56.815482 -119.32031) (xy 56.815482 -119.52351) (xy 57.018682 -119.52351)
			)
		)
		(polygon
			(pts
				(xy 56.811672 -118.950232) (xy 56.608472 -118.950232) (xy 56.608472 -119.153432) (xy 56.811672 -119.153432)
			)
		)
		(polygon
			(pts
				(xy 56.150002 -118.526052) (xy 55.946802 -118.526052) (xy 55.946802 -118.729252) (xy 56.150002 -118.729252)
			)
		)
		(polygon
			(pts
				(xy 55.591202 -118.526052) (xy 55.388002 -118.526052) (xy 55.388002 -118.729252) (xy 55.591202 -118.729252)
			)
		)
	)
	(zone
		(layer "B.Cu")
		(hatch none 0.5)
		(connect_pads
			(clearance 0)
		)
		(min_thickness 0.25)
		(keepout
			(tracks allowed)
			(vias allowed)
			(pads allowed)
			(copperpour allowed)
			(footprints allowed)
		)
		(placement
			(enabled no)
			(sheetname "")
		)
		(fill
			(thermal_gap 0.5)
			(thermal_bridge_width 0.5)
			(island_removal_mode 0)
		)
		(polygon
			(pts
				(xy 458.978 -225.2218) (xy 460.9084 -225.2218) (xy 460.9084 -227.2284) (xy 458.978 -227.2284)
			)
		)
	)
	(zone
		(layer "B.Cu")
		(hatch none 0.5)
		(connect_pads
			(clearance 0)
		)
		(min_thickness 0.25)
		(keepout
			(tracks not_allowed)
			(vias allowed)
			(pads allowed)
			(copperpour not_allowed)
			(footprints allowed)
		)
		(placement
			(enabled no)
			(sheetname "")
		)
		(fill
			(thermal_gap 0.5)
			(thermal_bridge_width 0.5)
			(island_removal_mode 0)
		)
		(polygon
			(pts
				(arc
					(start 219.54871 -76.399898)
					(mid 219.00007 -75.851258)
					(end 218.45143 -76.399898)
				)
				(arc
					(start 218.45143 -77.799692)
					(mid 218.999943 -78.348586)
					(end 219.54871 -77.799946)
				)
				(arc
					(start 219.54871 -77.380338)
					(mid 219.485635 -77.351221)
					(end 219.416884 -77.341222)
				)
				(arc
					(start 219.188284 -77.341222)
					(mid 219.128398 -77.363003)
					(end 219.09659 -77.418184)
				)
				(arc
					(start 219.09659 -77.418184)
					(mid 218.999924 -78.193658)
					(end 218.90482 -77.41793)
				)
				(xy 218.90482 -77.394816)
				(arc
					(start 218.908122 -77.391514)
					(mid 218.987895 -77.233797)
					(end 219.145612 -77.154024)
				)
				(xy 219.148914 -77.150722) (xy 219.456254 -77.150722)
				(arc
					(start 219.458286 -77.152754)
					(mid 219.503994 -77.159607)
					(end 219.54871 -77.171296)
				)
				(arc
					(start 219.54871 -77.065632)
					(mid 219.483313 -77.053251)
					(end 219.416884 -77.049122)
				)
				(xy 219.148914 -77.049122)
				(arc
					(start 219.145612 -77.04582)
					(mid 218.987895 -76.966047)
					(end 218.908122 -76.80833)
				)
				(xy 218.90482 -76.805028)
				(arc
					(start 218.90482 -76.781914)
					(mid 218.999924 -76.006125)
					(end 219.09659 -76.78166)
				)
				(arc
					(start 219.09659 -76.78166)
					(mid 219.128458 -76.836769)
					(end 219.188284 -76.858622)
				)
				(xy 219.456254 -76.858622)
				(arc
					(start 219.457524 -76.859638)
					(mid 219.503294 -76.863783)
					(end 219.54871 -76.870814)
				)
			)
		)
	)
	(zone
		(layer "B.Cu")
		(hatch none 0.5)
		(connect_pads
			(clearance 0)
		)
		(min_thickness 0.25)
		(keepout
			(tracks allowed)
			(vias allowed)
			(pads allowed)
			(copperpour allowed)
			(footprints not_allowed)
		)
		(placement
			(enabled no)
			(sheetname "")
		)
		(fill
			(thermal_gap 0.5)
			(thermal_bridge_width 0.5)
			(island_removal_mode 0)
		)
		(polygon
			(pts
				(arc
					(start 67.69989 -339.39988)
					(mid 71.699882 -335.399888)
					(end 67.69989 -331.399896)
				)
				(arc
					(start 62.61989 -331.399896)
					(mid 58.619898 -335.399888)
					(end 62.61989 -339.39988)
				)
			)
		)
	)
	(zone
		(layer "B.Cu")
		(hatch none 0.5)
		(connect_pads
			(clearance 0)
		)
		(min_thickness 0.25)
		(keepout
			(tracks not_allowed)
			(vias allowed)
			(pads allowed)
			(copperpour not_allowed)
			(footprints allowed)
		)
		(placement
			(enabled no)
			(sheetname "")
		)
		(fill
			(thermal_gap 0.5)
			(thermal_bridge_width 0.5)
			(island_removal_mode 0)
		)
		(polygon
			(pts
				(arc
					(start 278.23668 -225.545904)
					(mid 277.68804 -226.094544)
					(end 278.23668 -226.643184)
				)
				(arc
					(start 278.726138 -226.643184)
					(mid 278.719064 -226.596509)
					(end 278.715216 -226.549458)
				)
				(xy 278.714454 -226.548696)
				(arc
					(start 278.714454 -226.3394)
					(mid 278.688665 -226.249768)
					(end 278.619204 -226.187508)
				)
				(arc
					(start 278.619204 -226.187508)
					(mid 277.843206 -226.080416)
					(end 278.624792 -226.02825)
				)
				(arc
					(start 278.624792 -226.02825)
					(mid 278.788618 -226.129417)
					(end 278.865076 -226.306126)
				)
				(xy 278.866854 -226.307904)
				(arc
					(start 278.866854 -226.5172)
					(mid 278.8706 -226.580637)
					(end 278.88184 -226.643184)
				)
				(arc
					(start 279.027128 -226.643184)
					(mid 279.014672 -226.597284)
					(end 279.007824 -226.55022)
				)
				(xy 279.006554 -226.548696) (xy 279.006554 -226.307904)
				(arc
					(start 279.008332 -226.306126)
					(mid 279.084801 -226.129426)
					(end 279.248616 -226.02825)
				)
				(arc
					(start 279.248616 -226.02825)
					(mid 280.030174 -226.080417)
					(end 279.254204 -226.187508)
				)
				(arc
					(start 279.254204 -226.187508)
					(mid 279.184706 -226.249745)
					(end 279.158954 -226.3394)
				)
				(arc
					(start 279.158954 -226.5172)
					(mid 279.167951 -226.582617)
					(end 279.19426 -226.643184)
				)
				(arc
					(start 279.636728 -226.643184)
					(mid 280.185368 -226.094544)
					(end 279.636728 -225.545904)
				)
			)
		)
	)
	(zone
		(layer "B.Cu")
		(hatch none 0.5)
		(connect_pads
			(clearance 0)
		)
		(min_thickness 0.25)
		(keepout
			(tracks not_allowed)
			(vias allowed)
			(pads allowed)
			(copperpour not_allowed)
			(footprints allowed)
		)
		(placement
			(enabled no)
			(sheetname "")
		)
		(fill
			(thermal_gap 0.5)
			(thermal_bridge_width 0.5)
			(island_removal_mode 0)
		)
		(polygon
			(pts
				(arc
					(start 337.674966 -63.799974)
					(mid 330.67498 -56.799988)
					(end 323.674994 -63.799974)
				)
				(arc
					(start 323.674994 -69.799962)
					(mid 330.67498 -76.799948)
					(end 337.674966 -69.799962)
				)
			)
		)
	)
	(zone
		(layer "B.Cu")
		(hatch none 0.5)
		(connect_pads
			(clearance 0)
		)
		(min_thickness 0.25)
		(keepout
			(tracks not_allowed)
			(vias allowed)
			(pads allowed)
			(copperpour not_allowed)
			(footprints allowed)
		)
		(placement
			(enabled no)
			(sheetname "")
		)
		(fill
			(thermal_gap 0.5)
			(thermal_bridge_width 0.5)
			(island_removal_mode 0)
		)
		(polygon
			(pts
				(arc
					(start 66.32067 -244.419374)
					(mid 65.83553 -243.934234)
					(end 65.35039 -244.419374)
				)
				(arc
					(start 65.35039 -245.56212)
					(mid 65.835403 -246.047514)
					(end 66.32067 -245.562374)
				)
				(xy 66.32067 -245.213124)
				(arc
					(start 65.979802 -245.213124)
					(mid 65.931668 -245.233062)
					(end 65.91173 -245.281196)
				)
				(arc
					(start 65.91173 -245.30685)
					(mid 65.83553 -245.829018)
					(end 65.75933 -245.30685)
				)
				(xy 65.75933 -245.2497)
				(arc
					(start 65.762124 -245.246906)
					(mid 65.823982 -245.125376)
					(end 65.945512 -245.063518)
				)
				(xy 65.948306 -245.060724) (xy 66.32067 -245.060724) (xy 66.32067 -244.921024) (xy 65.938654 -244.921024)
				(arc
					(start 65.93586 -244.91823)
					(mid 65.821068 -244.859286)
					(end 65.762124 -244.744494)
				)
				(xy 65.75933 -244.7417)
				(arc
					(start 65.75933 -244.674898)
					(mid 65.83553 -244.15273)
					(end 65.91173 -244.674898)
				)
				(arc
					(start 65.91173 -244.710204)
					(mid 65.928841 -244.751513)
					(end 65.97015 -244.768624)
				)
				(xy 66.32067 -244.768624)
			)
		)
	)
	(zone
		(layer "B.Cu")
		(hatch none 0.5)
		(connect_pads
			(clearance 0)
		)
		(min_thickness 0.25)
		(keepout
			(tracks not_allowed)
			(vias allowed)
			(pads allowed)
			(copperpour not_allowed)
			(footprints allowed)
		)
		(placement
			(enabled no)
			(sheetname "")
		)
		(fill
			(thermal_gap 0.5)
			(thermal_bridge_width 0.5)
			(island_removal_mode 0)
		)
		(polygon
			(pts
				(arc
					(start 165.450012 -13.999972)
					(mid 170.200066 -18.750026)
					(end 174.95012 -13.999972)
				)
				(arc
					(start 174.95012 -13.999972)
					(mid 170.200066 -9.249918)
					(end 165.450012 -13.999972)
				)
			)
		)
	)
	(zone
		(layer "B.Cu")
		(hatch none 0.5)
		(connect_pads
			(clearance 0)
		)
		(min_thickness 0.25)
		(keepout
			(tracks allowed)
			(vias allowed)
			(pads allowed)
			(copperpour allowed)
			(footprints not_allowed)
		)
		(placement
			(enabled no)
			(sheetname "")
		)
		(fill
			(thermal_gap 0.5)
			(thermal_bridge_width 0.5)
			(island_removal_mode 0)
		)
		(polygon
			(pts
				(arc
					(start 395.48054 -39.99992)
					(mid 425.175257 -106.80014)
					(end 454.86955 -39.99992)
				)
				(arc
					(start 433.284376 -39.99992)
					(mid 444.951442 -46.978389)
					(end 451.956424 -58.62955)
				)
				(arc
					(start 451.956424 -58.62955)
					(mid 459.500652 -57.395783)
					(end 463.674968 -63.799974)
				)
				(arc
					(start 463.674968 -69.799962)
					(mid 459.50078 -76.204232)
					(end 451.956424 -74.97064)
				)
				(arc
					(start 451.956424 -74.97064)
					(mid 425.175135 -94.799885)
					(end 398.393666 -74.97064)
				)
				(arc
					(start 398.393666 -74.97064)
					(mid 390.849284 -76.20429)
					(end 386.675122 -69.799962)
				)
				(arc
					(start 386.675122 -63.799974)
					(mid 390.849389 -57.39567)
					(end 398.393666 -58.62955)
				)
				(arc
					(start 398.393666 -58.62955)
					(mid 405.398662 -46.978403)
					(end 417.065714 -39.99992)
				)
			)
		)
	)
	(zone
		(net "GND")
		(layer "B.Cu")
		(hatch none 0.5)
		(connect_pads
			(clearance 0.5)
		)
		(min_thickness 0.25)
		(fill yes
			(thermal_gap 0.5)
			(thermal_bridge_width 0.5)
			(island_removal_mode 0)
		)
		(polygon
			(pts
				(xy 168.725342 -24.21255) (xy 168.47566 -24.462232) (xy 168.47566 -24.64943) (xy 168.615614 -25.307798)
				(arc
					(start 169.186606 -25.87879)
					(mid 171.463395 -25.934639)
					(end 173.49978 -26.95448)
				)
				(arc
					(start 174.562516 -26.95448)
					(mid 179.230678 -27.651916)
					(end 180.133244 -32.284924)
				)
				(arc
					(start 180.133244 -32.284924)
					(mid 179.500936 -36.36175)
					(end 175.639476 -37.813996)
				)
				(xy 174.160688 -37.813996) (xy 171.90212 -40.072564) (xy 171.90212 -40.770302) (xy 181.02961 -83.71205)
				(xy 182.046626 -84.729066)
				(arc
					(start 184.21858 -84.729066)
					(mid 187.88088 -83.350215)
					(end 191.79413 -83.36407)
				)
				(xy 192.247774 -83.36407) (xy 192.74155 -82.870294) (xy 192.74155 -82.025744) (xy 188.156088 -60.453524)
				(arc
					(start 184.18556 -56.482996)
					(mid 182.444238 -54.899697)
					(end 181.863746 -52.618894)
				)
				(arc
					(start 180.132482 -50.88763)
					(mid 178.264589 -48.930414)
					(end 178.027076 -46.235366)
				)
				(arc
					(start 178.027076 -44.64558)
					(mid 176.629048 -39.781023)
					(end 181.030626 -37.28212)
				)
				(xy 181.54523 -37.28212) (xy 182.088282 -36.739068)
				(arc
					(start 182.088282 -34.355278)
					(mid 181.995243 -33.858993)
					(end 181.964076 -33.355026)
				)
				(arc
					(start 181.964076 -30.814772)
					(mid 181.978847 -30.467699)
					(end 182.023004 -30.12313)
				)
				(arc
					(start 182.023004 -29.125418)
					(mid 181.409287 -28.341852)
					(end 181.00294 -27.43327)
				)
				(xy 179.885594 -26.315924)
				(arc
					(start 176.403 -26.315924)
					(mid 174.460537 -25.825382)
					(end 172.983906 -24.471376)
				)
				(arc
					(start 172.983906 -24.471376)
					(mid 172.495753 -24.458497)
					(end 172.01261 -24.387556)
				)
				(arc
					(start 172.01261 -24.387556)
					(mid 171.795117 -24.40505)
					(end 171.577 -24.410924)
				)
				(arc
					(start 170.307 -24.410924)
					(mid 169.670077 -24.360998)
					(end 169.048684 -24.21255)
				)
			)
		)
	)
	(zone
		(layer "B.Cu")
		(hatch none 0.5)
		(connect_pads
			(clearance 0)
		)
		(min_thickness 0.25)
		(keepout
			(tracks allowed)
			(vias allowed)
			(pads allowed)
			(copperpour allowed)
			(footprints allowed)
		)
		(placement
			(enabled no)
			(sheetname "")
		)
		(fill
			(thermal_gap 0.5)
			(thermal_bridge_width 0.5)
			(island_removal_mode 0)
		)
		(polygon
			(pts
				(xy 435.796182 -111.212122) (xy 437.947054 -111.212122) (xy 437.947054 -115.985798) (xy 435.796182 -115.985798)
			)
		)
	)
	(zone
		(layer "B.Cu")
		(hatch none 0.5)
		(connect_pads
			(clearance 0)
		)
		(min_thickness 0.25)
		(keepout
			(tracks not_allowed)
			(vias allowed)
			(pads allowed)
			(copperpour not_allowed)
			(footprints allowed)
		)
		(placement
			(enabled no)
			(sheetname "")
		)
		(fill
			(thermal_gap 0.5)
			(thermal_bridge_width 0.5)
			(island_removal_mode 0)
		)
		(polygon
			(pts
				(arc
					(start 400.675094 -293.800022)
					(mid 393.675108 -286.800036)
					(end 386.675122 -293.800022)
				)
				(arc
					(start 386.675122 -299.80001)
					(mid 393.675108 -306.799996)
					(end 400.675094 -299.80001)
				)
			)
		)
	)
	(zone
		(layer "B.Cu")
		(hatch none 0.5)
		(connect_pads
			(clearance 0)
		)
		(min_thickness 0.25)
		(keepout
			(tracks not_allowed)
			(vias allowed)
			(pads allowed)
			(copperpour not_allowed)
			(footprints allowed)
		)
		(placement
			(enabled no)
			(sheetname "")
		)
		(fill
			(thermal_gap 0.5)
			(thermal_bridge_width 0.5)
			(island_removal_mode 0)
		)
		(polygon
			(pts
				(arc
					(start 278.23668 -182.345838)
					(mid 277.68804 -182.894478)
					(end 278.23668 -183.443118)
				)
				(arc
					(start 279.636728 -183.443118)
					(mid 280.185368 -182.894478)
					(end 279.636728 -182.345838)
				)
				(arc
					(start 279.174956 -182.345838)
					(mid 279.162993 -182.38518)
					(end 279.158954 -182.426102)
				)
				(arc
					(start 279.158954 -182.705502)
					(mid 279.184928 -182.777501)
					(end 279.250902 -182.816246)
				)
				(arc
					(start 279.250902 -182.816246)
					(mid 280.030454 -182.896027)
					(end 279.250394 -182.970678)
				)
				(xy 279.240234 -182.970678)
				(arc
					(start 279.237948 -182.968646)
					(mid 279.084132 -182.8931)
					(end 279.008586 -182.739284)
				)
				(xy 279.006554 -182.736998) (xy 279.006554 -182.394606)
				(arc
					(start 279.008078 -182.393082)
					(mid 279.011103 -182.369333)
					(end 279.015698 -182.345838)
				)
				(arc
					(start 278.873204 -182.345838)
					(mid 278.868419 -182.385842)
					(end 278.866854 -182.426102)
				)
				(xy 278.866854 -182.736998)
				(arc
					(start 278.864822 -182.739284)
					(mid 278.789276 -182.8931)
					(end 278.63546 -182.968646)
				)
				(xy 278.633174 -182.970678)
				(arc
					(start 278.623014 -182.970678)
					(mid 277.842954 -182.896027)
					(end 278.622506 -182.816246)
				)
				(arc
					(start 278.622506 -182.816246)
					(mid 278.688411 -182.777443)
					(end 278.714454 -182.705502)
				)
				(xy 278.714454 -182.394606) (xy 278.715216 -182.393844) (xy 278.71928 -182.345838)
			)
		)
	)
	(zone
		(layer "B.Cu")
		(hatch none 0.5)
		(connect_pads
			(clearance 0)
		)
		(min_thickness 0.25)
		(keepout
			(tracks not_allowed)
			(vias allowed)
			(pads allowed)
			(copperpour not_allowed)
			(footprints allowed)
		)
		(placement
			(enabled no)
			(sheetname "")
		)
		(fill
			(thermal_gap 0.5)
			(thermal_bridge_width 0.5)
			(island_removal_mode 0)
		)
		(polygon
			(pts
				(arc
					(start 476.964756 -128.141984)
					(mid 476.479362 -128.626997)
					(end 476.964502 -129.112264)
				)
				(xy 477.313752 -129.112264)
				(arc
					(start 477.313752 -128.774952)
					(mid 477.292773 -128.724303)
					(end 477.242124 -128.703324)
				)
				(arc
					(start 477.220026 -128.703324)
					(mid 476.697858 -128.627124)
					(end 477.220026 -128.550924)
				)
				(xy 477.27362 -128.550924)
				(arc
					(start 477.276414 -128.553464)
					(mid 477.400605 -128.616471)
					(end 477.463612 -128.740662)
				)
				(xy 477.466152 -128.743456) (xy 477.466152 -129.112264) (xy 477.605852 -129.112264) (xy 477.605852 -128.736852)
				(arc
					(start 477.609916 -128.732788)
					(mid 477.67437 -128.613774)
					(end 477.79559 -128.553464)
				)
				(xy 477.798384 -128.550924)
				(arc
					(start 477.851978 -128.550924)
					(mid 478.374146 -128.627124)
					(end 477.851978 -128.703324)
				)
				(arc
					(start 477.82988 -128.703324)
					(mid 477.779231 -128.724303)
					(end 477.758252 -128.774952)
				)
				(xy 477.758252 -129.112264)
				(arc
					(start 478.107502 -129.112264)
					(mid 478.592642 -128.627124)
					(end 478.107502 -128.141984)
				)
			)
		)
	)
	(zone
		(layer "B.Cu")
		(hatch none 0.5)
		(connect_pads
			(clearance 0)
		)
		(min_thickness 0.25)
		(keepout
			(tracks not_allowed)
			(vias allowed)
			(pads allowed)
			(copperpour not_allowed)
			(footprints allowed)
		)
		(placement
			(enabled no)
			(sheetname "")
		)
		(fill
			(thermal_gap 0.5)
			(thermal_bridge_width 0.5)
			(island_removal_mode 0)
		)
		(polygon
			(pts
				(arc
					(start 34.770822 -129.419604)
					(mid 34.285809 -128.93421)
					(end 33.800542 -129.41935)
				)
				(arc
					(start 33.800542 -130.56235)
					(mid 34.285682 -131.04749)
					(end 34.770822 -130.56235)
				)
				(xy 34.770822 -130.2131)
				(arc
					(start 34.429954 -130.2131)
					(mid 34.38182 -130.233038)
					(end 34.361882 -130.281172)
				)
				(arc
					(start 34.361882 -130.306826)
					(mid 34.285682 -130.828994)
					(end 34.209482 -130.306826)
				)
				(xy 34.209482 -130.249676)
				(arc
					(start 34.212276 -130.246882)
					(mid 34.274134 -130.125352)
					(end 34.395664 -130.063494)
				)
				(xy 34.398458 -130.0607) (xy 34.770822 -130.0607) (xy 34.770822 -129.921) (xy 34.388806 -129.921)
				(arc
					(start 34.386012 -129.918206)
					(mid 34.27122 -129.859262)
					(end 34.212276 -129.74447)
				)
				(xy 34.209482 -129.741676)
				(arc
					(start 34.209482 -129.674874)
					(mid 34.285682 -129.152706)
					(end 34.361882 -129.674874)
				)
				(arc
					(start 34.361882 -129.71018)
					(mid 34.378993 -129.751489)
					(end 34.420302 -129.7686)
				)
				(xy 34.770822 -129.7686)
			)
		)
	)
	(zone
		(net "P5V_B_2_LL")
		(layer "B.Cu")
		(hatch none 0.5)
		(connect_pads
			(clearance 0.5)
		)
		(min_thickness 0.25)
		(fill yes
			(thermal_gap 0.5)
			(thermal_bridge_width 0.5)
			(island_removal_mode 0)
		)
		(polygon
			(pts
				(xy 51.529234 -107.825032) (xy 48.28286 -111.071406) (xy 48.28286 -113.738406) (xy 48.45431 -113.909856)
				(xy 54.03596 -113.909856) (xy 54.50586 -113.439956) (xy 54.50586 -109.420406) (xy 54.496716 -109.411262)
				(xy 54.496716 -108.296964) (xy 54.024784 -107.825032)
			)
		)
	)
	(zone
		(net "MB3_CM_GATE")
		(layer "B.Cu")
		(hatch none 0.5)
		(connect_pads
			(clearance 0.5)
		)
		(min_thickness 0.25)
		(fill yes
			(thermal_gap 0.5)
			(thermal_bridge_width 0.5)
			(island_removal_mode 0)
		)
		(polygon
			(pts
				(xy 260.8199 -354.5205) (xy 260.096 -355.2444) (xy 260.096 -356.7938) (xy 260.7818 -357.4796) (xy 262.8392 -357.4796)
				(xy 263.7282 -356.5906) (xy 263.7282 -354.7237) (xy 263.525 -354.5205)
			)
		)
	)
	(zone
		(net "GND")
		(layer "B.Cu")
		(hatch none 0.5)
		(connect_pads
			(clearance 0.5)
		)
		(min_thickness 0.25)
		(fill yes
			(thermal_gap 0.5)
			(thermal_bridge_width 0.5)
			(island_removal_mode 0)
		)
		(polygon
			(pts
				(xy 391.886948 -24.38273) (xy 391.702798 -24.56688)
				(arc
					(start 391.702798 -26.230072)
					(mid 391.680895 -26.652832)
					(end 391.615422 -27.071066)
				)
				(arc
					(start 391.615422 -27.89047)
					(mid 392.525688 -29.228608)
					(end 392.845798 -30.815026)
				)
				(xy 392.845798 -32.566102) (xy 394.576808 -34.297112)
				(arc
					(start 395.741398 -34.297112)
					(mid 397.046006 -34.140457)
					(end 398.33296 -34.40557)
				)
				(xy 399.20291 -34.40557) (xy 399.73504 -33.87344)
				(arc
					(start 399.73504 -31.192724)
					(mid 397.15685 -28.586299)
					(end 395.903196 -25.141174)
				)
				(xy 395.144752 -24.38273)
			)
		)
	)
	(zone
		(net "GND")
		(layer "B.Cu")
		(hatch none 0.5)
		(connect_pads
			(clearance 0.5)
		)
		(min_thickness 0.25)
		(fill yes
			(thermal_gap 0.5)
			(thermal_bridge_width 0.5)
			(island_removal_mode 0)
		)
		(polygon
			(pts
				(arc
					(start 149.271482 -26.293572)
					(mid 149.058414 -26.310319)
					(end 148.844762 -26.315924)
				)
				(xy 146.845782 -26.315924) (xy 146.708368 -26.453338)
				(arc
					(start 146.708368 -26.934922)
					(mid 148.771283 -29.266701)
					(end 148.595334 -32.375094)
				)
				(arc
					(start 148.595334 -32.375094)
					(mid 147.665148 -36.655905)
					(end 143.396462 -37.64026)
				)
				(xy 142.5702 -37.64026)
				(arc
					(start 142.121636 -38.088824)
					(mid 141.566825 -38.709333)
					(end 140.897864 -39.204646)
				)
				(xy 140.897864 -40.37838) (xy 146.642582 -67.40652) (xy 147.214844 -68.287646) (xy 147.893532 -68.287646)
				(xy 148.50364 -67.677538)
				(arc
					(start 148.50364 -63.799974)
					(mid 148.667247 -61.925433)
					(end 149.153118 -60.107576)
				)
				(xy 149.153118 -51.496976)
				(arc
					(start 148.432012 -50.77587)
					(mid 146.810244 -49.019557)
					(end 146.447256 -46.656752)
				)
				(arc
					(start 146.447256 -44.640246)
					(mid 145.044014 -39.812277)
					(end 149.38248 -37.271198)
				)
				(xy 149.68347 -37.271198) (xy 150.606506 -36.348162)
				(arc
					(start 150.606506 -34.595054)
					(mid 150.462404 -33.982467)
					(end 150.413974 -33.355026)
				)
				(arc
					(start 150.413974 -30.815026)
					(mid 150.437796 -30.374184)
					(end 150.50897 -29.938472)
				)
				(arc
					(start 150.50897 -29.161994)
					(mid 149.60565 -27.850556)
					(end 149.271482 -26.293572)
				)
			)
		)
	)
	(zone
		(net "GND")
		(layer "B.Cu")
		(hatch none 0.5)
		(connect_pads
			(clearance 0.5)
		)
		(min_thickness 0.25)
		(fill yes
			(thermal_gap 0.5)
			(thermal_bridge_width 0.5)
			(island_removal_mode 0)
		)
		(polygon
			(pts
				(xy 474.7514 -214.8586) (xy 474.107002 -215.502998) (xy 474.107002 -217.678) (xy 474.589602 -218.1606)
				(xy 478.679002 -218.1606) (xy 478.933002 -217.9066) (xy 478.933002 -215.535002) (xy 478.2566 -214.8586)
			)
		)
	)
	(zone
		(net "P5V_B_3_LL_R")
		(layer "B.Cu")
		(hatch none 0.5)
		(connect_pads
			(clearance 0.5)
		)
		(min_thickness 0.25)
		(fill yes
			(thermal_gap 0.5)
			(thermal_bridge_width 0.5)
			(island_removal_mode 0)
		)
		(polygon
			(pts
				(xy 466.248496 -229.251256) (xy 466.029802 -229.46995) (xy 466.029802 -230.06177) (xy 466.180932 -230.2129)
				(xy 466.93201 -230.2129) (xy 467.069678 -230.350568) (xy 467.069678 -232.440226) (xy 467.299802 -232.67035)
				(xy 468.03564 -232.67035) (xy 468.357712 -232.348278) (xy 468.357712 -229.44963) (xy 468.159338 -229.251256)
			)
		)
		(polygon
			(pts
				(xy 467.780624 -231.114854) (xy 467.577424 -231.114854) (xy 467.577424 -231.318054) (xy 467.780624 -231.318054)
			)
		)
		(polygon
			(pts
				(xy 467.780624 -230.505254) (xy 467.577424 -230.505254) (xy 467.577424 -230.708454) (xy 467.780624 -230.708454)
			)
		)
		(polygon
			(pts
				(xy 467.573614 -230.135176) (xy 467.370414 -230.135176) (xy 467.370414 -230.338376) (xy 467.573614 -230.338376)
			)
		)
		(polygon
			(pts
				(xy 466.911944 -229.710996) (xy 466.708744 -229.710996) (xy 466.708744 -229.914196) (xy 466.911944 -229.914196)
			)
		)
		(polygon
			(pts
				(xy 466.353144 -229.710996) (xy 466.149944 -229.710996) (xy 466.149944 -229.914196) (xy 466.353144 -229.914196)
			)
		)
	)
	(zone
		(net "P5V_B_1_LL")
		(layer "B.Cu")
		(hatch none 0.5)
		(connect_pads
			(clearance 0.5)
		)
		(min_thickness 0.25)
		(fill yes
			(thermal_gap 0.5)
			(thermal_bridge_width 0.5)
			(island_removal_mode 0)
		)
		(polygon
			(pts
				(xy 26.460958 -219.230194) (xy 23.434802 -222.25635) (xy 23.434802 -224.92335) (xy 23.606252 -225.0948)
				(xy 29.187902 -225.0948) (xy 29.657802 -224.6249) (xy 29.657802 -219.499688) (xy 29.388308 -219.230194)
			)
		)
	)
	(zone
		(net "GND")
		(layer "B.Cu")
		(hatch none 0.5)
		(connect_pads
			(clearance 0.5)
		)
		(min_thickness 0.25)
		(fill yes
			(thermal_gap 0.5)
			(thermal_bridge_width 0.5)
			(island_removal_mode 0)
		)
		(polygon
			(pts
				(xy 103.086916 -45.245528) (xy 100.345494 -41.024048) (xy 99.415346 -40.42029) (xy 97.915984 -40.42029)
				(xy 96.916748 -41.419526) (xy 96.916748 -42.539666) (xy 102.38486 -46.09084) (xy 102.685342 -46.09084)
				(xy 103.086916 -45.689266)
			)
		)
	)
	(zone
		(net "GND")
		(layer "B.Cu")
		(hatch none 0.5)
		(connect_pads
			(clearance 0.5)
		)
		(min_thickness 0.25)
		(fill yes
			(thermal_gap 0.5)
			(thermal_bridge_width 0.5)
			(island_removal_mode 0)
		)
		(polygon
			(pts
				(xy 455.744834 -121.464578) (xy 455.411586 -121.797826) (xy 455.411586 -125.03023) (xy 455.757534 -125.376178)
				(xy 459.758034 -125.376178) (xy 460.085186 -125.049026) (xy 460.085186 -121.85523) (xy 459.694534 -121.464578)
			)
		)
	)
	(zone
		(layer "B.Cu")
		(hatch none 0.5)
		(connect_pads
			(clearance 0)
		)
		(min_thickness 0.25)
		(keepout
			(tracks allowed)
			(vias allowed)
			(pads allowed)
			(copperpour allowed)
			(footprints not_allowed)
		)
		(placement
			(enabled no)
			(sheetname "")
		)
		(fill
			(thermal_gap 0.5)
			(thermal_bridge_width 0.5)
			(island_removal_mode 0)
		)
		(polygon
			(pts
				(arc
					(start 439.17489 -66.799968)
					(mid 425.174918 -52.799996)
					(end 411.174946 -66.799968)
				)
				(arc
					(start 411.174946 -66.799968)
					(mid 425.174918 -80.79994)
					(end 439.17489 -66.799968)
				)
			)
		)
	)
	(zone
		(net "P3V3_STBY_B")
		(layer "B.Cu")
		(hatch none 0.5)
		(connect_pads
			(clearance 0.5)
		)
		(min_thickness 0.25)
		(fill yes
			(thermal_gap 0.5)
			(thermal_bridge_width 0.5)
			(island_removal_mode 0)
		)
		(polygon
			(pts
				(xy 241.427 -275.59) (xy 241.071654 -275.945346) (xy 241.071654 -277.012654) (xy 240.919 -277.165308)
				(xy 240.919 -282.829) (xy 240.538 -283.21) (xy 239.395 -283.21) (xy 239.014 -283.591) (xy 239.014 -285.623)
				(xy 244.6782 -285.623) (xy 244.729 -285.5722) (xy 244.729 -285.3182) (xy 244.7798 -285.2674) (xy 245.618 -285.2674)
				(xy 245.872 -285.5214) (xy 245.872 -286.639) (xy 245.999 -286.766) (xy 246.761 -286.766) (xy 246.888 -286.639)
				(xy 246.888 -277.495) (xy 246.4054 -277.0124) (xy 243.6114 -277.0124) (xy 242.189 -275.59)
			)
		)
		(polygon
			(pts
				(xy 241.759994 -276.465792) (xy 241.556794 -276.465792) (xy 241.556794 -276.668992) (xy 241.759994 -276.668992)
			)
		)
		(polygon
			(pts
				(xy 241.759994 -275.856192) (xy 241.556794 -275.856192) (xy 241.556794 -276.059392) (xy 241.759994 -276.059392)
			)
		)
	)
	(zone
		(layers "B.Cu" "In2.Cu")
		(hatch none 0.5)
		(connect_pads
			(clearance 0)
		)
		(min_thickness 0.25)
		(keepout
			(tracks not_allowed)
			(vias allowed)
			(pads allowed)
			(copperpour not_allowed)
			(footprints allowed)
		)
		(placement
			(enabled no)
			(sheetname "")
		)
		(fill yes
			(thermal_gap 0.5)
			(thermal_bridge_width 0.5)
			(island_removal_mode 0)
		)
		(polygon
			(pts
				(arc
					(start 417.331906 -16.95196)
					(mid 416.846512 -17.436973)
					(end 417.331652 -17.92224)
				)
				(arc
					(start 418.601652 -17.92224)
					(mid 418.943799 -17.781043)
					(end 419.086792 -17.43964)
				)
				(arc
					(start 418.868352 -17.43964)
					(mid 418.601652 -17.703812)
					(end 418.334952 -17.43964)
				)
				(arc
					(start 417.598352 -17.43964)
					(mid 417.331652 -17.703812)
					(end 417.064952 -17.43964)
				)
				(arc
					(start 417.064952 -17.4371)
					(mid 417.331652 -17.1704)
					(end 417.598352 -17.4371)
				)
				(arc
					(start 418.334952 -17.4371)
					(mid 418.601652 -17.1704)
					(end 418.868352 -17.4371)
				)
				(arc
					(start 419.086792 -17.4371)
					(mid 418.944698 -17.094054)
					(end 418.601652 -16.95196)
				)
			)
		)
	)
	(zone
		(layers "B.Cu" "In2.Cu")
		(hatch none 0.5)
		(connect_pads
			(clearance 0)
		)
		(min_thickness 0.25)
		(keepout
			(tracks not_allowed)
			(vias allowed)
			(pads allowed)
			(copperpour not_allowed)
			(footprints allowed)
		)
		(placement
			(enabled no)
			(sheetname "")
		)
		(fill yes
			(thermal_gap 0.5)
			(thermal_bridge_width 0.5)
			(island_removal_mode 0)
		)
		(polygon
			(pts
				(arc
					(start 324.07479 -248.115074)
					(mid 323.58965 -247.629934)
					(end 323.10451 -248.115074)
				)
				(arc
					(start 323.10451 -249.385074)
					(mid 323.58838 -249.870212)
					(end 324.07479 -249.387614)
				)
				(arc
					(start 323.85635 -249.387614)
					(mid 323.58965 -249.651786)
					(end 323.32295 -249.387614)
				)
				(arc
					(start 323.32295 -249.385074)
					(mid 323.58965 -249.118374)
					(end 323.85635 -249.385074)
				)
				(xy 324.07479 -249.385074) (xy 324.07479 -248.117614)
				(arc
					(start 323.85635 -248.117614)
					(mid 323.58965 -248.381786)
					(end 323.32295 -248.117614)
				)
				(arc
					(start 323.32295 -248.115074)
					(mid 323.58965 -247.848374)
					(end 323.85635 -248.115074)
				)
			)
		)
	)
	(zone
		(layers "B.Cu" "In2.Cu")
		(hatch none 0.5)
		(connect_pads
			(clearance 0)
		)
		(min_thickness 0.25)
		(keepout
			(tracks not_allowed)
			(vias allowed)
			(pads allowed)
			(copperpour not_allowed)
			(footprints allowed)
		)
		(placement
			(enabled no)
			(sheetname "")
		)
		(fill yes
			(thermal_gap 0.5)
			(thermal_bridge_width 0.5)
			(island_removal_mode 0)
		)
		(polygon
			(pts
				(arc
					(start 96.094042 -248.115074)
					(mid 95.608902 -247.629934)
					(end 95.123762 -248.115074)
				)
				(arc
					(start 95.123762 -249.385074)
					(mid 95.607632 -249.870212)
					(end 96.094042 -249.387614)
				)
				(arc
					(start 95.875602 -249.387614)
					(mid 95.608902 -249.651786)
					(end 95.342202 -249.387614)
				)
				(arc
					(start 95.342202 -249.385074)
					(mid 95.608902 -249.118374)
					(end 95.875602 -249.385074)
				)
				(xy 96.094042 -249.385074) (xy 96.094042 -248.117614)
				(arc
					(start 95.875602 -248.117614)
					(mid 95.608902 -248.381786)
					(end 95.342202 -248.117614)
				)
				(arc
					(start 95.342202 -248.115074)
					(mid 95.608902 -247.848374)
					(end 95.875602 -248.115074)
				)
			)
		)
	)
	(zone
		(layers "B.Cu" "In2.Cu")
		(hatch none 0.5)
		(connect_pads
			(clearance 0)
		)
		(min_thickness 0.25)
		(keepout
			(tracks not_allowed)
			(vias allowed)
			(pads allowed)
			(copperpour not_allowed)
			(footprints allowed)
		)
		(placement
			(enabled no)
			(sheetname "")
		)
		(fill yes
			(thermal_gap 0.5)
			(thermal_bridge_width 0.5)
			(island_removal_mode 0)
		)
		(polygon
			(pts
				(arc
					(start 64.54394 -133.11505)
					(mid 64.0588 -132.62991)
					(end 63.57366 -133.11505)
				)
				(arc
					(start 63.57366 -134.384796)
					(mid 64.057403 -134.870188)
					(end 64.54394 -134.38759)
				)
				(arc
					(start 64.3255 -134.38759)
					(mid 64.0588 -134.651762)
					(end 63.7921 -134.38759)
				)
				(arc
					(start 63.7921 -134.38505)
					(mid 64.0588 -134.11835)
					(end 64.3255 -134.38505)
				)
				(xy 64.54394 -134.38505) (xy 64.54394 -133.11759)
				(arc
					(start 64.3255 -133.11759)
					(mid 64.0588 -133.381762)
					(end 63.7921 -133.11759)
				)
				(arc
					(start 63.7921 -133.11505)
					(mid 64.0588 -132.84835)
					(end 64.3255 -133.11505)
				)
			)
		)
	)
	(zone
		(layers "B.Cu" "In2.Cu")
		(hatch none 0.5)
		(connect_pads
			(clearance 0)
		)
		(min_thickness 0.25)
		(keepout
			(tracks not_allowed)
			(vias allowed)
			(pads allowed)
			(copperpour not_allowed)
			(footprints allowed)
		)
		(placement
			(enabled no)
			(sheetname "")
		)
		(fill yes
			(thermal_gap 0.5)
			(thermal_bridge_width 0.5)
			(island_removal_mode 0)
		)
		(polygon
			(pts
				(arc
					(start 190.744094 -248.115074)
					(mid 190.258954 -247.629934)
					(end 189.773814 -248.115074)
				)
				(arc
					(start 189.773814 -249.385074)
					(mid 190.257684 -249.870212)
					(end 190.744094 -249.387614)
				)
				(arc
					(start 190.525654 -249.387614)
					(mid 190.258954 -249.651786)
					(end 189.992254 -249.387614)
				)
				(arc
					(start 189.992254 -249.385074)
					(mid 190.258954 -249.118374)
					(end 190.525654 -249.385074)
				)
				(xy 190.744094 -249.385074) (xy 190.744094 -248.117614)
				(arc
					(start 190.525654 -248.117614)
					(mid 190.258954 -248.381786)
					(end 189.992254 -248.117614)
				)
				(arc
					(start 189.992254 -248.115074)
					(mid 190.258954 -247.848374)
					(end 190.525654 -248.115074)
				)
			)
		)
	)
	(zone
		(layers "B.Cu" "In2.Cu")
		(hatch none 0.5)
		(connect_pads
			(clearance 0)
		)
		(min_thickness 0.25)
		(keepout
			(tracks not_allowed)
			(vias allowed)
			(pads allowed)
			(copperpour not_allowed)
			(footprints allowed)
		)
		(placement
			(enabled no)
			(sheetname "")
		)
		(fill yes
			(thermal_gap 0.5)
			(thermal_bridge_width 0.5)
			(island_removal_mode 0)
		)
		(polygon
			(pts
				(arc
					(start 448.8815 -16.95196)
					(mid 448.39636 -17.4371)
					(end 448.8815 -17.92224)
				)
				(arc
					(start 450.151246 -17.92224)
					(mid 450.493557 -17.781132)
					(end 450.63664 -17.43964)
				)
				(arc
					(start 450.4182 -17.43964)
					(mid 450.1515 -17.703812)
					(end 449.8848 -17.43964)
				)
				(arc
					(start 449.1482 -17.43964)
					(mid 448.8815 -17.703812)
					(end 448.6148 -17.43964)
				)
				(arc
					(start 448.6148 -17.4371)
					(mid 448.8815 -17.1704)
					(end 449.1482 -17.4371)
				)
				(arc
					(start 449.8848 -17.4371)
					(mid 450.1515 -17.1704)
					(end 450.4182 -17.4371)
				)
				(arc
					(start 450.63664 -17.4371)
					(mid 450.494546 -17.094054)
					(end 450.1515 -16.95196)
				)
			)
		)
	)
	(zone
		(layers "B.Cu" "In2.Cu")
		(hatch none 0.5)
		(connect_pads
			(clearance 0)
		)
		(min_thickness 0.25)
		(keepout
			(tracks not_allowed)
			(vias allowed)
			(pads allowed)
			(copperpour not_allowed)
			(footprints allowed)
		)
		(placement
			(enabled no)
			(sheetname "")
		)
		(fill yes
			(thermal_gap 0.5)
			(thermal_bridge_width 0.5)
			(island_removal_mode 0)
		)
		(polygon
			(pts
				(arc
					(start 322.6816 -131.951984)
					(mid 322.19646 -132.437124)
					(end 322.6816 -132.922264)
				)
				(arc
					(start 323.951346 -132.922264)
					(mid 324.293657 -132.781156)
					(end 324.43674 -132.439664)
				)
				(arc
					(start 324.2183 -132.439664)
					(mid 323.9516 -132.703836)
					(end 323.6849 -132.439664)
				)
				(arc
					(start 322.9483 -132.439664)
					(mid 322.6816 -132.703836)
					(end 322.4149 -132.439664)
				)
				(arc
					(start 322.4149 -132.437124)
					(mid 322.6816 -132.170424)
					(end 322.9483 -132.437124)
				)
				(arc
					(start 323.6849 -132.437124)
					(mid 323.9516 -132.170424)
					(end 324.2183 -132.437124)
				)
				(arc
					(start 324.43674 -132.437124)
					(mid 324.294646 -132.094078)
					(end 323.9516 -131.951984)
				)
			)
		)
	)
	(zone
		(layers "B.Cu" "In2.Cu")
		(hatch none 0.5)
		(connect_pads
			(clearance 0)
		)
		(min_thickness 0.25)
		(keepout
			(tracks not_allowed)
			(vias allowed)
			(pads allowed)
			(copperpour not_allowed)
			(footprints allowed)
		)
		(placement
			(enabled no)
			(sheetname "")
		)
		(fill yes
			(thermal_gap 0.5)
			(thermal_bridge_width 0.5)
			(island_removal_mode 0)
		)
		(polygon
			(pts
				(arc
					(start 32.994092 -133.11505)
					(mid 32.508952 -132.62991)
					(end 32.023812 -133.11505)
				)
				(arc
					(start 32.023812 -134.384796)
					(mid 32.507555 -134.870188)
					(end 32.994092 -134.38759)
				)
				(arc
					(start 32.775652 -134.38759)
					(mid 32.508952 -134.651762)
					(end 32.242252 -134.38759)
				)
				(arc
					(start 32.242252 -134.38505)
					(mid 32.508952 -134.11835)
					(end 32.775652 -134.38505)
				)
				(xy 32.994092 -134.38505) (xy 32.994092 -133.11759)
				(arc
					(start 32.775652 -133.11759)
					(mid 32.508952 -133.381762)
					(end 32.242252 -133.11759)
				)
				(arc
					(start 32.242252 -133.11505)
					(mid 32.508952 -132.84835)
					(end 32.775652 -133.11505)
				)
			)
		)
	)
	(zone
		(layers "B.Cu" "In2.Cu")
		(hatch none 0.5)
		(connect_pads
			(clearance 0)
		)
		(min_thickness 0.25)
		(keepout
			(tracks not_allowed)
			(vias allowed)
			(pads allowed)
			(copperpour not_allowed)
			(footprints allowed)
		)
		(placement
			(enabled no)
			(sheetname "")
		)
		(fill yes
			(thermal_gap 0.5)
			(thermal_bridge_width 0.5)
			(island_removal_mode 0)
		)
		(polygon
			(pts
				(arc
					(start 32.994092 -18.115026)
					(mid 32.508952 -17.629886)
					(end 32.023812 -18.115026)
				)
				(arc
					(start 32.023812 -19.385026)
					(mid 32.507682 -19.870164)
					(end 32.994092 -19.387566)
				)
				(arc
					(start 32.775652 -19.387566)
					(mid 32.508952 -19.651738)
					(end 32.242252 -19.387566)
				)
				(arc
					(start 32.242252 -19.385026)
					(mid 32.508952 -19.118326)
					(end 32.775652 -19.385026)
				)
				(xy 32.994092 -19.385026) (xy 32.994092 -18.117566)
				(arc
					(start 32.775652 -18.117566)
					(mid 32.508952 -18.381738)
					(end 32.242252 -18.117566)
				)
				(arc
					(start 32.242252 -18.115026)
					(mid 32.508952 -17.848326)
					(end 32.775652 -18.115026)
				)
			)
		)
	)
	(zone
		(layers "B.Cu" "In2.Cu")
		(hatch none 0.5)
		(connect_pads
			(clearance 0)
		)
		(min_thickness 0.25)
		(keepout
			(tracks not_allowed)
			(vias allowed)
			(pads allowed)
			(copperpour not_allowed)
			(footprints allowed)
		)
		(placement
			(enabled no)
			(sheetname "")
		)
		(fill yes
			(thermal_gap 0.5)
			(thermal_bridge_width 0.5)
			(island_removal_mode 0)
		)
		(polygon
			(pts
				(arc
					(start 481.824792 -248.115074)
					(mid 481.339652 -247.629934)
					(end 480.854512 -248.115074)
				)
				(arc
					(start 480.854512 -249.385074)
					(mid 481.338382 -249.870212)
					(end 481.824792 -249.387614)
				)
				(arc
					(start 481.606352 -249.387614)
					(mid 481.339652 -249.651786)
					(end 481.072952 -249.387614)
				)
				(arc
					(start 481.072952 -249.385074)
					(mid 481.339652 -249.118374)
					(end 481.606352 -249.385074)
				)
				(xy 481.824792 -249.385074) (xy 481.824792 -248.117614)
				(arc
					(start 481.606352 -248.117614)
					(mid 481.339652 -248.381786)
					(end 481.072952 -248.117614)
				)
				(arc
					(start 481.072952 -248.115074)
					(mid 481.339652 -247.848374)
					(end 481.606352 -248.115074)
				)
			)
		)
	)
	(zone
		(layers "B.Cu" "In2.Cu")
		(hatch none 0.5)
		(connect_pads
			(clearance 0)
		)
		(min_thickness 0.25)
		(keepout
			(tracks not_allowed)
			(vias allowed)
			(pads allowed)
			(copperpour not_allowed)
			(footprints allowed)
		)
		(placement
			(enabled no)
			(sheetname "")
		)
		(fill yes
			(thermal_gap 0.5)
			(thermal_bridge_width 0.5)
			(island_removal_mode 0)
		)
		(polygon
			(pts
				(arc
					(start 64.54394 -248.115074)
					(mid 64.0588 -247.629934)
					(end 63.57366 -248.115074)
				)
				(arc
					(start 63.57366 -249.385074)
					(mid 64.05753 -249.870212)
					(end 64.54394 -249.387614)
				)
				(arc
					(start 64.3255 -249.387614)
					(mid 64.0588 -249.651786)
					(end 63.7921 -249.387614)
				)
				(arc
					(start 63.7921 -249.385074)
					(mid 64.0588 -249.118374)
					(end 64.3255 -249.385074)
				)
				(xy 64.54394 -249.385074) (xy 64.54394 -248.117614)
				(arc
					(start 64.3255 -248.117614)
					(mid 64.0588 -248.381786)
					(end 63.7921 -248.117614)
				)
				(arc
					(start 63.7921 -248.115074)
					(mid 64.0588 -247.848374)
					(end 64.3255 -248.115074)
				)
			)
		)
	)
	(zone
		(layers "B.Cu" "In2.Cu")
		(hatch none 0.5)
		(connect_pads
			(clearance 0)
		)
		(min_thickness 0.25)
		(keepout
			(tracks not_allowed)
			(vias allowed)
			(pads allowed)
			(copperpour not_allowed)
			(footprints allowed)
		)
		(placement
			(enabled no)
			(sheetname "")
		)
		(fill yes
			(thermal_gap 0.5)
			(thermal_bridge_width 0.5)
			(island_removal_mode 0)
		)
		(polygon
			(pts
				(arc
					(start 96.094042 -133.11505)
					(mid 95.608902 -132.62991)
					(end 95.123762 -133.11505)
				)
				(arc
					(start 95.123762 -134.384796)
					(mid 95.607505 -134.870188)
					(end 96.094042 -134.38759)
				)
				(arc
					(start 95.875602 -134.38759)
					(mid 95.608902 -134.651762)
					(end 95.342202 -134.38759)
				)
				(arc
					(start 95.342202 -134.38505)
					(mid 95.608902 -134.11835)
					(end 95.875602 -134.38505)
				)
				(xy 96.094042 -134.38505) (xy 96.094042 -133.11759)
				(arc
					(start 95.875602 -133.11759)
					(mid 95.608902 -133.381762)
					(end 95.342202 -133.11759)
				)
				(arc
					(start 95.342202 -133.11505)
					(mid 95.608902 -132.84835)
					(end 95.875602 -133.11505)
				)
			)
		)
	)
	(zone
		(layers "B.Cu" "In2.Cu")
		(hatch none 0.5)
		(connect_pads
			(clearance 0)
		)
		(min_thickness 0.25)
		(keepout
			(tracks not_allowed)
			(vias allowed)
			(pads allowed)
			(copperpour not_allowed)
			(footprints allowed)
		)
		(placement
			(enabled no)
			(sheetname "")
		)
		(fill yes
			(thermal_gap 0.5)
			(thermal_bridge_width 0.5)
			(island_removal_mode 0)
		)
		(polygon
			(pts
				(arc
					(start 96.094042 -18.115026)
					(mid 95.608902 -17.629886)
					(end 95.123762 -18.115026)
				)
				(arc
					(start 95.123762 -19.385026)
					(mid 95.607632 -19.870164)
					(end 96.094042 -19.387566)
				)
				(arc
					(start 95.875602 -19.387566)
					(mid 95.608902 -19.651738)
					(end 95.342202 -19.387566)
				)
				(arc
					(start 95.342202 -19.385026)
					(mid 95.608902 -19.118326)
					(end 95.875602 -19.385026)
				)
				(xy 96.094042 -19.385026) (xy 96.094042 -18.117566)
				(arc
					(start 95.875602 -18.117566)
					(mid 95.608902 -18.381738)
					(end 95.342202 -18.117566)
				)
				(arc
					(start 95.342202 -18.115026)
					(mid 95.608902 -17.848326)
					(end 95.875602 -18.115026)
				)
			)
		)
	)
	(zone
		(layers "B.Cu" "In2.Cu")
		(hatch none 0.5)
		(connect_pads
			(clearance 0)
		)
		(min_thickness 0.25)
		(keepout
			(tracks not_allowed)
			(vias allowed)
			(pads allowed)
			(copperpour not_allowed)
			(footprints allowed)
		)
		(placement
			(enabled no)
			(sheetname "")
		)
		(fill yes
			(thermal_gap 0.5)
			(thermal_bridge_width 0.5)
			(island_removal_mode 0)
		)
		(polygon
			(pts
				(arc
					(start 355.624892 -248.115074)
					(mid 355.139752 -247.629934)
					(end 354.654612 -248.115074)
				)
				(arc
					(start 354.654612 -249.385074)
					(mid 355.138482 -249.870212)
					(end 355.624892 -249.387614)
				)
				(arc
					(start 355.406452 -249.387614)
					(mid 355.139752 -249.651786)
					(end 354.873052 -249.387614)
				)
				(arc
					(start 354.873052 -249.385074)
					(mid 355.139752 -249.118374)
					(end 355.406452 -249.385074)
				)
				(xy 355.624892 -249.385074) (xy 355.624892 -248.117614)
				(arc
					(start 355.406452 -248.117614)
					(mid 355.139752 -248.381786)
					(end 354.873052 -248.117614)
				)
				(arc
					(start 354.873052 -248.115074)
					(mid 355.139752 -247.848374)
					(end 355.406452 -248.115074)
				)
			)
		)
	)
	(zone
		(layers "B.Cu" "In2.Cu")
		(hatch none 0.5)
		(connect_pads
			(clearance 0)
		)
		(min_thickness 0.25)
		(keepout
			(tracks not_allowed)
			(vias allowed)
			(pads allowed)
			(copperpour not_allowed)
			(footprints allowed)
		)
		(placement
			(enabled no)
			(sheetname "")
		)
		(fill yes
			(thermal_gap 0.5)
			(thermal_bridge_width 0.5)
			(island_removal_mode 0)
		)
		(polygon
			(pts
				(arc
					(start 64.54394 -18.115026)
					(mid 64.0588 -17.629886)
					(end 63.57366 -18.115026)
				)
				(arc
					(start 63.57366 -19.385026)
					(mid 64.05753 -19.870164)
					(end 64.54394 -19.387566)
				)
				(arc
					(start 64.3255 -19.387566)
					(mid 64.0588 -19.651738)
					(end 63.7921 -19.387566)
				)
				(arc
					(start 63.7921 -19.385026)
					(mid 64.0588 -19.118326)
					(end 64.3255 -19.385026)
				)
				(xy 64.54394 -19.385026) (xy 64.54394 -18.117566)
				(arc
					(start 64.3255 -18.117566)
					(mid 64.0588 -18.381738)
					(end 63.7921 -18.117566)
				)
				(arc
					(start 63.7921 -18.115026)
					(mid 64.0588 -17.848326)
					(end 64.3255 -18.115026)
				)
			)
		)
	)
	(zone
		(layers "B.Cu" "In2.Cu")
		(hatch none 0.5)
		(connect_pads
			(clearance 0)
		)
		(min_thickness 0.25)
		(keepout
			(tracks not_allowed)
			(vias allowed)
			(pads allowed)
			(copperpour not_allowed)
			(footprints allowed)
		)
		(placement
			(enabled no)
			(sheetname "")
		)
		(fill yes
			(thermal_gap 0.5)
			(thermal_bridge_width 0.5)
			(island_removal_mode 0)
		)
		(polygon
			(pts
				(arc
					(start 387.17474 -248.115074)
					(mid 386.6896 -247.629934)
					(end 386.20446 -248.115074)
				)
				(arc
					(start 386.20446 -249.385074)
					(mid 386.68833 -249.870212)
					(end 387.17474 -249.387614)
				)
				(arc
					(start 386.9563 -249.387614)
					(mid 386.6896 -249.651786)
					(end 386.4229 -249.387614)
				)
				(arc
					(start 386.4229 -249.385074)
					(mid 386.6896 -249.118374)
					(end 386.9563 -249.385074)
				)
				(xy 387.17474 -249.385074) (xy 387.17474 -248.117614)
				(arc
					(start 386.9563 -248.117614)
					(mid 386.6896 -248.381786)
					(end 386.4229 -248.117614)
				)
				(arc
					(start 386.4229 -248.115074)
					(mid 386.6896 -247.848374)
					(end 386.9563 -248.115074)
				)
			)
		)
	)
	(zone
		(layers "B.Cu" "In2.Cu")
		(hatch none 0.5)
		(connect_pads
			(clearance 0)
		)
		(min_thickness 0.25)
		(keepout
			(tracks not_allowed)
			(vias allowed)
			(pads allowed)
			(copperpour not_allowed)
			(footprints allowed)
		)
		(placement
			(enabled no)
			(sheetname "")
		)
		(fill yes
			(thermal_gap 0.5)
			(thermal_bridge_width 0.5)
			(island_removal_mode 0)
		)
		(polygon
			(pts
				(arc
					(start 480.431856 -131.951984)
					(mid 479.946462 -132.436997)
					(end 480.431602 -132.922264)
				)
				(arc
					(start 481.701602 -132.922264)
					(mid 482.043749 -132.781067)
					(end 482.186742 -132.439664)
				)
				(arc
					(start 481.968302 -132.439664)
					(mid 481.701602 -132.703836)
					(end 481.434902 -132.439664)
				)
				(arc
					(start 480.698302 -132.439664)
					(mid 480.431602 -132.703836)
					(end 480.164902 -132.439664)
				)
				(arc
					(start 480.164902 -132.437124)
					(mid 480.431602 -132.170424)
					(end 480.698302 -132.437124)
				)
				(arc
					(start 481.434902 -132.437124)
					(mid 481.701602 -132.170424)
					(end 481.968302 -132.437124)
				)
				(arc
					(start 482.186742 -132.437124)
					(mid 482.044648 -132.094078)
					(end 481.701602 -131.951984)
				)
			)
		)
	)
	(zone
		(layers "B.Cu" "In2.Cu")
		(hatch none 0.5)
		(connect_pads
			(clearance 0)
		)
		(min_thickness 0.25)
		(keepout
			(tracks not_allowed)
			(vias allowed)
			(pads allowed)
			(copperpour not_allowed)
			(footprints allowed)
		)
		(placement
			(enabled no)
			(sheetname "")
		)
		(fill yes
			(thermal_gap 0.5)
			(thermal_bridge_width 0.5)
			(island_removal_mode 0)
		)
		(polygon
			(pts
				(arc
					(start 159.193992 -133.11505)
					(mid 158.708852 -132.62991)
					(end 158.223712 -133.11505)
				)
				(arc
					(start 158.223712 -134.384796)
					(mid 158.707455 -134.870188)
					(end 159.193992 -134.38759)
				)
				(arc
					(start 158.975552 -134.38759)
					(mid 158.708852 -134.651762)
					(end 158.442152 -134.38759)
				)
				(arc
					(start 158.442152 -134.38505)
					(mid 158.708852 -134.11835)
					(end 158.975552 -134.38505)
				)
				(xy 159.193992 -134.38505) (xy 159.193992 -133.11759)
				(arc
					(start 158.975552 -133.11759)
					(mid 158.708852 -133.381762)
					(end 158.442152 -133.11759)
				)
				(arc
					(start 158.442152 -133.11505)
					(mid 158.708852 -132.84835)
					(end 158.975552 -133.11505)
				)
			)
		)
	)
	(zone
		(layers "B.Cu" "In2.Cu")
		(hatch none 0.5)
		(connect_pads
			(clearance 0)
		)
		(min_thickness 0.25)
		(keepout
			(tracks not_allowed)
			(vias allowed)
			(pads allowed)
			(copperpour not_allowed)
			(footprints allowed)
		)
		(placement
			(enabled no)
			(sheetname "")
		)
		(fill yes
			(thermal_gap 0.5)
			(thermal_bridge_width 0.5)
			(island_removal_mode 0)
		)
		(polygon
			(pts
				(arc
					(start 417.331906 -131.951984)
					(mid 416.846512 -132.436997)
					(end 417.331652 -132.922264)
				)
				(arc
					(start 418.601652 -132.922264)
					(mid 418.943799 -132.781067)
					(end 419.086792 -132.439664)
				)
				(arc
					(start 418.868352 -132.439664)
					(mid 418.601652 -132.703836)
					(end 418.334952 -132.439664)
				)
				(arc
					(start 417.598352 -132.439664)
					(mid 417.331652 -132.703836)
					(end 417.064952 -132.439664)
				)
				(arc
					(start 417.064952 -132.437124)
					(mid 417.331652 -132.170424)
					(end 417.598352 -132.437124)
				)
				(arc
					(start 418.334952 -132.437124)
					(mid 418.601652 -132.170424)
					(end 418.868352 -132.437124)
				)
				(arc
					(start 419.086792 -132.437124)
					(mid 418.944698 -132.094078)
					(end 418.601652 -131.951984)
				)
			)
		)
	)
	(zone
		(layers "B.Cu" "In2.Cu")
		(hatch none 0.5)
		(connect_pads
			(clearance 0)
		)
		(min_thickness 0.25)
		(keepout
			(tracks not_allowed)
			(vias allowed)
			(pads allowed)
			(copperpour not_allowed)
			(footprints allowed)
		)
		(placement
			(enabled no)
			(sheetname "")
		)
		(fill yes
			(thermal_gap 0.5)
			(thermal_bridge_width 0.5)
			(island_removal_mode 0)
		)
		(polygon
			(pts
				(arc
					(start 354.231956 -131.951984)
					(mid 353.746562 -132.436997)
					(end 354.231702 -132.922264)
				)
				(arc
					(start 355.501702 -132.922264)
					(mid 355.843849 -132.781067)
					(end 355.986842 -132.439664)
				)
				(arc
					(start 355.768402 -132.439664)
					(mid 355.501702 -132.703836)
					(end 355.235002 -132.439664)
				)
				(arc
					(start 354.498402 -132.439664)
					(mid 354.231702 -132.703836)
					(end 353.965002 -132.439664)
				)
				(arc
					(start 353.965002 -132.437124)
					(mid 354.231702 -132.170424)
					(end 354.498402 -132.437124)
				)
				(arc
					(start 355.235002 -132.437124)
					(mid 355.501702 -132.170424)
					(end 355.768402 -132.437124)
				)
				(arc
					(start 355.986842 -132.437124)
					(mid 355.844748 -132.094078)
					(end 355.501702 -131.951984)
				)
			)
		)
	)
	(zone
		(layers "B.Cu" "In2.Cu")
		(hatch none 0.5)
		(connect_pads
			(clearance 0)
		)
		(min_thickness 0.25)
		(keepout
			(tracks not_allowed)
			(vias allowed)
			(pads allowed)
			(copperpour not_allowed)
			(footprints allowed)
		)
		(placement
			(enabled no)
			(sheetname "")
		)
		(fill yes
			(thermal_gap 0.5)
			(thermal_bridge_width 0.5)
			(island_removal_mode 0)
		)
		(polygon
			(pts
				(arc
					(start 159.193992 -18.115026)
					(mid 158.708852 -17.629886)
					(end 158.223712 -18.115026)
				)
				(arc
					(start 158.223712 -19.385026)
					(mid 158.707582 -19.870164)
					(end 159.193992 -19.387566)
				)
				(arc
					(start 158.975552 -19.387566)
					(mid 158.708852 -19.651738)
					(end 158.442152 -19.387566)
				)
				(arc
					(start 158.442152 -19.385026)
					(mid 158.708852 -19.118326)
					(end 158.975552 -19.385026)
				)
				(xy 159.193992 -19.385026) (xy 159.193992 -18.117566)
				(arc
					(start 158.975552 -18.117566)
					(mid 158.708852 -18.381738)
					(end 158.442152 -18.117566)
				)
				(arc
					(start 158.442152 -18.115026)
					(mid 158.708852 -17.848326)
					(end 158.975552 -18.115026)
				)
			)
		)
	)
	(zone
		(layers "B.Cu" "In2.Cu")
		(hatch none 0.5)
		(connect_pads
			(clearance 0)
		)
		(min_thickness 0.25)
		(keepout
			(tracks not_allowed)
			(vias allowed)
			(pads allowed)
			(copperpour not_allowed)
			(footprints allowed)
		)
		(placement
			(enabled no)
			(sheetname "")
		)
		(fill yes
			(thermal_gap 0.5)
			(thermal_bridge_width 0.5)
			(island_removal_mode 0)
		)
		(polygon
			(pts
				(arc
					(start 354.231956 -16.95196)
					(mid 353.746562 -17.436973)
					(end 354.231702 -17.92224)
				)
				(arc
					(start 355.501702 -17.92224)
					(mid 355.843849 -17.781043)
					(end 355.986842 -17.43964)
				)
				(arc
					(start 355.768402 -17.43964)
					(mid 355.501702 -17.703812)
					(end 355.235002 -17.43964)
				)
				(arc
					(start 354.498402 -17.43964)
					(mid 354.231702 -17.703812)
					(end 353.965002 -17.43964)
				)
				(arc
					(start 353.965002 -17.4371)
					(mid 354.231702 -17.1704)
					(end 354.498402 -17.4371)
				)
				(arc
					(start 355.235002 -17.4371)
					(mid 355.501702 -17.1704)
					(end 355.768402 -17.4371)
				)
				(arc
					(start 355.986842 -17.4371)
					(mid 355.844748 -17.094054)
					(end 355.501702 -16.95196)
				)
			)
		)
	)
	(zone
		(layers "B.Cu" "In2.Cu")
		(hatch none 0.5)
		(connect_pads
			(clearance 0)
		)
		(min_thickness 0.25)
		(keepout
			(tracks not_allowed)
			(vias allowed)
			(pads allowed)
			(copperpour not_allowed)
			(footprints allowed)
		)
		(placement
			(enabled no)
			(sheetname "")
		)
		(fill yes
			(thermal_gap 0.5)
			(thermal_bridge_width 0.5)
			(island_removal_mode 0)
		)
		(polygon
			(pts
				(arc
					(start 190.744094 -18.115026)
					(mid 190.258954 -17.629886)
					(end 189.773814 -18.115026)
				)
				(arc
					(start 189.773814 -19.385026)
					(mid 190.257684 -19.870164)
					(end 190.744094 -19.387566)
				)
				(arc
					(start 190.525654 -19.387566)
					(mid 190.258954 -19.651738)
					(end 189.992254 -19.387566)
				)
				(arc
					(start 189.992254 -19.385026)
					(mid 190.258954 -19.118326)
					(end 190.525654 -19.385026)
				)
				(xy 190.744094 -19.385026) (xy 190.744094 -18.117566)
				(arc
					(start 190.525654 -18.117566)
					(mid 190.258954 -18.381738)
					(end 189.992254 -18.117566)
				)
				(arc
					(start 189.992254 -18.115026)
					(mid 190.258954 -17.848326)
					(end 190.525654 -18.115026)
				)
			)
		)
	)
	(zone
		(layers "B.Cu" "In2.Cu")
		(hatch none 0.5)
		(connect_pads
			(clearance 0)
		)
		(min_thickness 0.25)
		(keepout
			(tracks not_allowed)
			(vias allowed)
			(pads allowed)
			(copperpour not_allowed)
			(footprints allowed)
		)
		(placement
			(enabled no)
			(sheetname "")
		)
		(fill yes
			(thermal_gap 0.5)
			(thermal_bridge_width 0.5)
			(island_removal_mode 0)
		)
		(polygon
			(pts
				(arc
					(start 418.724842 -248.115074)
					(mid 418.239702 -247.629934)
					(end 417.754562 -248.115074)
				)
				(arc
					(start 417.754562 -249.385074)
					(mid 418.238432 -249.870212)
					(end 418.724842 -249.387614)
				)
				(arc
					(start 418.506402 -249.387614)
					(mid 418.239702 -249.651786)
					(end 417.973002 -249.387614)
				)
				(arc
					(start 417.973002 -249.385074)
					(mid 418.239702 -249.118374)
					(end 418.506402 -249.385074)
				)
				(xy 418.724842 -249.385074) (xy 418.724842 -248.117614)
				(arc
					(start 418.506402 -248.117614)
					(mid 418.239702 -248.381786)
					(end 417.973002 -248.117614)
				)
				(arc
					(start 417.973002 -248.115074)
					(mid 418.239702 -247.848374)
					(end 418.506402 -248.115074)
				)
			)
		)
	)
	(zone
		(layers "B.Cu" "In2.Cu")
		(hatch none 0.5)
		(connect_pads
			(clearance 0)
		)
		(min_thickness 0.25)
		(keepout
			(tracks not_allowed)
			(vias allowed)
			(pads allowed)
			(copperpour not_allowed)
			(footprints allowed)
		)
		(placement
			(enabled no)
			(sheetname "")
		)
		(fill yes
			(thermal_gap 0.5)
			(thermal_bridge_width 0.5)
			(island_removal_mode 0)
		)
		(polygon
			(pts
				(arc
					(start 450.27469 -248.115074)
					(mid 449.78955 -247.629934)
					(end 449.30441 -248.115074)
				)
				(arc
					(start 449.30441 -249.385074)
					(mid 449.78828 -249.870212)
					(end 450.27469 -249.387614)
				)
				(arc
					(start 450.05625 -249.387614)
					(mid 449.78955 -249.651786)
					(end 449.52285 -249.387614)
				)
				(arc
					(start 449.52285 -249.385074)
					(mid 449.78955 -249.118374)
					(end 450.05625 -249.385074)
				)
				(xy 450.27469 -249.385074) (xy 450.27469 -248.117614)
				(arc
					(start 450.05625 -248.117614)
					(mid 449.78955 -248.381786)
					(end 449.52285 -248.117614)
				)
				(arc
					(start 449.52285 -248.115074)
					(mid 449.78955 -247.848374)
					(end 450.05625 -248.115074)
				)
			)
		)
	)
	(zone
		(layers "B.Cu" "In2.Cu")
		(hatch none 0.5)
		(connect_pads
			(clearance 0)
		)
		(min_thickness 0.25)
		(keepout
			(tracks not_allowed)
			(vias allowed)
			(pads allowed)
			(copperpour not_allowed)
			(footprints allowed)
		)
		(placement
			(enabled no)
			(sheetname "")
		)
		(fill yes
			(thermal_gap 0.5)
			(thermal_bridge_width 0.5)
			(island_removal_mode 0)
		)
		(polygon
			(pts
				(arc
					(start 127.64389 -248.115074)
					(mid 127.15875 -247.629934)
					(end 126.67361 -248.115074)
				)
				(arc
					(start 126.67361 -249.385074)
					(mid 127.15748 -249.870212)
					(end 127.64389 -249.387614)
				)
				(arc
					(start 127.42545 -249.387614)
					(mid 127.15875 -249.651786)
					(end 126.89205 -249.387614)
				)
				(arc
					(start 126.89205 -249.385074)
					(mid 127.15875 -249.118374)
					(end 127.42545 -249.385074)
				)
				(xy 127.64389 -249.385074) (xy 127.64389 -248.117614)
				(arc
					(start 127.42545 -248.117614)
					(mid 127.15875 -248.381786)
					(end 126.89205 -248.117614)
				)
				(arc
					(start 126.89205 -248.115074)
					(mid 127.15875 -247.848374)
					(end 127.42545 -248.115074)
				)
			)
		)
	)
	(zone
		(layers "B.Cu" "In2.Cu")
		(hatch none 0.5)
		(connect_pads
			(clearance 0)
		)
		(min_thickness 0.25)
		(keepout
			(tracks not_allowed)
			(vias allowed)
			(pads allowed)
			(copperpour not_allowed)
			(footprints allowed)
		)
		(placement
			(enabled no)
			(sheetname "")
		)
		(fill yes
			(thermal_gap 0.5)
			(thermal_bridge_width 0.5)
			(island_removal_mode 0)
		)
		(polygon
			(pts
				(arc
					(start 159.193992 -248.115074)
					(mid 158.708852 -247.629934)
					(end 158.223712 -248.115074)
				)
				(arc
					(start 158.223712 -249.38482)
					(mid 158.707455 -249.870212)
					(end 159.193992 -249.387614)
				)
				(arc
					(start 158.975552 -249.387614)
					(mid 158.708852 -249.651786)
					(end 158.442152 -249.387614)
				)
				(arc
					(start 158.442152 -249.385074)
					(mid 158.708852 -249.118374)
					(end 158.975552 -249.385074)
				)
				(xy 159.193992 -249.385074) (xy 159.193992 -248.117614)
				(arc
					(start 158.975552 -248.117614)
					(mid 158.708852 -248.381786)
					(end 158.442152 -248.117614)
				)
				(arc
					(start 158.442152 -248.115074)
					(mid 158.708852 -247.848374)
					(end 158.975552 -248.115074)
				)
			)
		)
	)
	(zone
		(layers "B.Cu" "In2.Cu")
		(hatch none 0.5)
		(connect_pads
			(clearance 0)
		)
		(min_thickness 0.25)
		(keepout
			(tracks not_allowed)
			(vias allowed)
			(pads allowed)
			(copperpour not_allowed)
			(footprints allowed)
		)
		(placement
			(enabled no)
			(sheetname "")
		)
		(fill yes
			(thermal_gap 0.5)
			(thermal_bridge_width 0.5)
			(island_removal_mode 0)
		)
		(polygon
			(pts
				(arc
					(start 480.431856 -16.95196)
					(mid 479.946462 -17.436973)
					(end 480.431602 -17.92224)
				)
				(arc
					(start 481.701602 -17.92224)
					(mid 482.043749 -17.781043)
					(end 482.186742 -17.43964)
				)
				(arc
					(start 481.968302 -17.43964)
					(mid 481.701602 -17.703812)
					(end 481.434902 -17.43964)
				)
				(arc
					(start 480.698302 -17.43964)
					(mid 480.431602 -17.703812)
					(end 480.164902 -17.43964)
				)
				(arc
					(start 480.164902 -17.4371)
					(mid 480.431602 -17.1704)
					(end 480.698302 -17.4371)
				)
				(arc
					(start 481.434902 -17.4371)
					(mid 481.701602 -17.1704)
					(end 481.968302 -17.4371)
				)
				(arc
					(start 482.186742 -17.4371)
					(mid 482.044648 -17.094054)
					(end 481.701602 -16.95196)
				)
			)
		)
	)
	(zone
		(layers "B.Cu" "In2.Cu")
		(hatch none 0.5)
		(connect_pads
			(clearance 0)
		)
		(min_thickness 0.25)
		(keepout
			(tracks not_allowed)
			(vias allowed)
			(pads allowed)
			(copperpour not_allowed)
			(footprints allowed)
		)
		(placement
			(enabled no)
			(sheetname "")
		)
		(fill yes
			(thermal_gap 0.5)
			(thermal_bridge_width 0.5)
			(island_removal_mode 0)
		)
		(polygon
			(pts
				(arc
					(start 322.6816 -16.95196)
					(mid 322.19646 -17.4371)
					(end 322.6816 -17.92224)
				)
				(arc
					(start 323.951346 -17.92224)
					(mid 324.293657 -17.781132)
					(end 324.43674 -17.43964)
				)
				(arc
					(start 324.2183 -17.43964)
					(mid 323.9516 -17.703812)
					(end 323.6849 -17.43964)
				)
				(arc
					(start 322.9483 -17.43964)
					(mid 322.6816 -17.703812)
					(end 322.4149 -17.43964)
				)
				(arc
					(start 322.4149 -17.4371)
					(mid 322.6816 -17.1704)
					(end 322.9483 -17.4371)
				)
				(arc
					(start 323.6849 -17.4371)
					(mid 323.9516 -17.1704)
					(end 324.2183 -17.4371)
				)
				(arc
					(start 324.43674 -17.4371)
					(mid 324.294646 -17.094054)
					(end 323.9516 -16.95196)
				)
			)
		)
	)
	(zone
		(layers "B.Cu" "In2.Cu")
		(hatch none 0.5)
		(connect_pads
			(clearance 0)
		)
		(min_thickness 0.25)
		(keepout
			(tracks not_allowed)
			(vias allowed)
			(pads allowed)
			(copperpour not_allowed)
			(footprints allowed)
		)
		(placement
			(enabled no)
			(sheetname "")
		)
		(fill yes
			(thermal_gap 0.5)
			(thermal_bridge_width 0.5)
			(island_removal_mode 0)
		)
		(polygon
			(pts
				(arc
					(start 127.64389 -18.115026)
					(mid 127.15875 -17.629886)
					(end 126.67361 -18.115026)
				)
				(arc
					(start 126.67361 -19.385026)
					(mid 127.15748 -19.870164)
					(end 127.64389 -19.387566)
				)
				(arc
					(start 127.42545 -19.387566)
					(mid 127.15875 -19.651738)
					(end 126.89205 -19.387566)
				)
				(arc
					(start 126.89205 -19.385026)
					(mid 127.15875 -19.118326)
					(end 127.42545 -19.385026)
				)
				(xy 127.64389 -19.385026) (xy 127.64389 -18.117566)
				(arc
					(start 127.42545 -18.117566)
					(mid 127.15875 -18.381738)
					(end 126.89205 -18.117566)
				)
				(arc
					(start 126.89205 -18.115026)
					(mid 127.15875 -17.848326)
					(end 127.42545 -18.115026)
				)
			)
		)
	)
	(zone
		(layers "B.Cu" "In2.Cu")
		(hatch none 0.5)
		(connect_pads
			(clearance 0)
		)
		(min_thickness 0.25)
		(keepout
			(tracks not_allowed)
			(vias allowed)
			(pads allowed)
			(copperpour not_allowed)
			(footprints allowed)
		)
		(placement
			(enabled no)
			(sheetname "")
		)
		(fill yes
			(thermal_gap 0.5)
			(thermal_bridge_width 0.5)
			(island_removal_mode 0)
		)
		(polygon
			(pts
				(arc
					(start 385.78155 -131.951984)
					(mid 385.29641 -132.437124)
					(end 385.78155 -132.922264)
				)
				(arc
					(start 387.051296 -132.922264)
					(mid 387.393607 -132.781156)
					(end 387.53669 -132.439664)
				)
				(arc
					(start 387.31825 -132.439664)
					(mid 387.05155 -132.703836)
					(end 386.78485 -132.439664)
				)
				(arc
					(start 386.04825 -132.439664)
					(mid 385.78155 -132.703836)
					(end 385.51485 -132.439664)
				)
				(arc
					(start 385.51485 -132.437124)
					(mid 385.78155 -132.170424)
					(end 386.04825 -132.437124)
				)
				(arc
					(start 386.78485 -132.437124)
					(mid 387.05155 -132.170424)
					(end 387.31825 -132.437124)
				)
				(arc
					(start 387.53669 -132.437124)
					(mid 387.394596 -132.094078)
					(end 387.05155 -131.951984)
				)
			)
		)
	)
	(zone
		(layers "B.Cu" "In2.Cu")
		(hatch none 0.5)
		(connect_pads
			(clearance 0)
		)
		(min_thickness 0.25)
		(keepout
			(tracks not_allowed)
			(vias allowed)
			(pads allowed)
			(copperpour not_allowed)
			(footprints allowed)
		)
		(placement
			(enabled no)
			(sheetname "")
		)
		(fill yes
			(thermal_gap 0.5)
			(thermal_bridge_width 0.5)
			(island_removal_mode 0)
		)
		(polygon
			(pts
				(arc
					(start 190.744094 -133.11505)
					(mid 190.258954 -132.62991)
					(end 189.773814 -133.11505)
				)
				(arc
					(start 189.773814 -134.38505)
					(mid 190.257684 -134.870188)
					(end 190.744094 -134.38759)
				)
				(arc
					(start 190.525654 -134.38759)
					(mid 190.258954 -134.651762)
					(end 189.992254 -134.38759)
				)
				(arc
					(start 189.992254 -134.38505)
					(mid 190.258954 -134.11835)
					(end 190.525654 -134.38505)
				)
				(xy 190.744094 -134.38505) (xy 190.744094 -133.11759)
				(arc
					(start 190.525654 -133.11759)
					(mid 190.258954 -133.381762)
					(end 189.992254 -133.11759)
				)
				(arc
					(start 189.992254 -133.11505)
					(mid 190.258954 -132.84835)
					(end 190.525654 -133.11505)
				)
			)
		)
	)
	(zone
		(layers "B.Cu" "In2.Cu")
		(hatch none 0.5)
		(connect_pads
			(clearance 0)
		)
		(min_thickness 0.25)
		(keepout
			(tracks not_allowed)
			(vias allowed)
			(pads allowed)
			(copperpour not_allowed)
			(footprints allowed)
		)
		(placement
			(enabled no)
			(sheetname "")
		)
		(fill yes
			(thermal_gap 0.5)
			(thermal_bridge_width 0.5)
			(island_removal_mode 0)
		)
		(polygon
			(pts
				(arc
					(start 127.64389 -133.11505)
					(mid 127.15875 -132.62991)
					(end 126.67361 -133.11505)
				)
				(arc
					(start 126.67361 -134.384796)
					(mid 127.157353 -134.870188)
					(end 127.64389 -134.38759)
				)
				(arc
					(start 127.42545 -134.38759)
					(mid 127.15875 -134.651762)
					(end 126.89205 -134.38759)
				)
				(arc
					(start 126.89205 -134.38505)
					(mid 127.15875 -134.11835)
					(end 127.42545 -134.38505)
				)
				(xy 127.64389 -134.38505) (xy 127.64389 -133.11759)
				(arc
					(start 127.42545 -133.11759)
					(mid 127.15875 -133.381762)
					(end 126.89205 -133.11759)
				)
				(arc
					(start 126.89205 -133.11505)
					(mid 127.15875 -132.84835)
					(end 127.42545 -133.11505)
				)
			)
		)
	)
	(zone
		(layers "B.Cu" "In2.Cu")
		(hatch none 0.5)
		(connect_pads
			(clearance 0)
		)
		(min_thickness 0.25)
		(keepout
			(tracks not_allowed)
			(vias allowed)
			(pads allowed)
			(copperpour not_allowed)
			(footprints allowed)
		)
		(placement
			(enabled no)
			(sheetname "")
		)
		(fill yes
			(thermal_gap 0.5)
			(thermal_bridge_width 0.5)
			(island_removal_mode 0)
		)
		(polygon
			(pts
				(arc
					(start 448.8815 -131.951984)
					(mid 448.39636 -132.437124)
					(end 448.8815 -132.922264)
				)
				(arc
					(start 450.151246 -132.922264)
					(mid 450.493557 -132.781156)
					(end 450.63664 -132.439664)
				)
				(arc
					(start 450.4182 -132.439664)
					(mid 450.1515 -132.703836)
					(end 449.8848 -132.439664)
				)
				(arc
					(start 449.1482 -132.439664)
					(mid 448.8815 -132.703836)
					(end 448.6148 -132.439664)
				)
				(arc
					(start 448.6148 -132.437124)
					(mid 448.8815 -132.170424)
					(end 449.1482 -132.437124)
				)
				(arc
					(start 449.8848 -132.437124)
					(mid 450.1515 -132.170424)
					(end 450.4182 -132.437124)
				)
				(arc
					(start 450.63664 -132.437124)
					(mid 450.494546 -132.094078)
					(end 450.1515 -131.951984)
				)
			)
		)
	)
	(zone
		(layers "B.Cu" "In2.Cu")
		(hatch none 0.5)
		(connect_pads
			(clearance 0)
		)
		(min_thickness 0.25)
		(keepout
			(tracks not_allowed)
			(vias allowed)
			(pads allowed)
			(copperpour not_allowed)
			(footprints allowed)
		)
		(placement
			(enabled no)
			(sheetname "")
		)
		(fill yes
			(thermal_gap 0.5)
			(thermal_bridge_width 0.5)
			(island_removal_mode 0)
		)
		(polygon
			(pts
				(arc
					(start 32.994092 -248.115074)
					(mid 32.508952 -247.629934)
					(end 32.023812 -248.115074)
				)
				(arc
					(start 32.023812 -249.385074)
					(mid 32.507682 -249.870212)
					(end 32.994092 -249.387614)
				)
				(arc
					(start 32.775652 -249.387614)
					(mid 32.508952 -249.651786)
					(end 32.242252 -249.387614)
				)
				(arc
					(start 32.242252 -249.385074)
					(mid 32.508952 -249.118374)
					(end 32.775652 -249.385074)
				)
				(xy 32.994092 -249.385074) (xy 32.994092 -248.117614)
				(arc
					(start 32.775652 -248.117614)
					(mid 32.508952 -248.381786)
					(end 32.242252 -248.117614)
				)
				(arc
					(start 32.242252 -248.115074)
					(mid 32.508952 -247.848374)
					(end 32.775652 -248.115074)
				)
			)
		)
	)
	(zone
		(layers "B.Cu" "In2.Cu")
		(hatch none 0.5)
		(connect_pads
			(clearance 0)
		)
		(min_thickness 0.25)
		(keepout
			(tracks not_allowed)
			(vias allowed)
			(pads allowed)
			(copperpour not_allowed)
			(footprints allowed)
		)
		(placement
			(enabled no)
			(sheetname "")
		)
		(fill yes
			(thermal_gap 0.5)
			(thermal_bridge_width 0.5)
			(island_removal_mode 0)
		)
		(polygon
			(pts
				(arc
					(start 385.78155 -16.95196)
					(mid 385.29641 -17.4371)
					(end 385.78155 -17.92224)
				)
				(arc
					(start 387.051296 -17.92224)
					(mid 387.393607 -17.781132)
					(end 387.53669 -17.43964)
				)
				(arc
					(start 387.31825 -17.43964)
					(mid 387.05155 -17.703812)
					(end 386.78485 -17.43964)
				)
				(arc
					(start 386.04825 -17.43964)
					(mid 385.78155 -17.703812)
					(end 385.51485 -17.43964)
				)
				(arc
					(start 385.51485 -17.4371)
					(mid 385.78155 -17.1704)
					(end 386.04825 -17.4371)
				)
				(arc
					(start 386.78485 -17.4371)
					(mid 387.05155 -17.1704)
					(end 387.31825 -17.4371)
				)
				(arc
					(start 387.53669 -17.4371)
					(mid 387.394596 -17.094054)
					(end 387.05155 -16.95196)
				)
			)
		)
	)
	(zone
		(net "GND")
		(layer "In1.Cu")
		(hatch none 0.5)
		(connect_pads
			(clearance 0.5)
		)
		(min_thickness 0.25)
		(fill yes
			(thermal_gap 0.5)
			(thermal_bridge_width 0.5)
			(island_removal_mode 0)
		)
		(polygon
			(pts
				(arc
					(start 0.999998 -0.763016)
					(mid 0.832426 -0.832426)
					(end 0.763016 -0.999998)
				)
				(arc
					(start 0.763016 -370.000022)
					(mid 0.832426 -370.167594)
					(end 0.999998 -370.237004)
				)
				(arc
					(start 1.999996 -370.237004)
					(mid 3.246635 -370.753379)
					(end 3.76301 -372.000018)
				)
				(arc
					(start 3.76301 -384.999992)
					(mid 3.83242 -385.167564)
					(end 3.999992 -385.236974)
				)
				(arc
					(start 15.249906 -385.236974)
					(mid 15.417478 -385.167564)
					(end 15.486888 -384.999992)
				)
				(arc
					(start 15.486888 -383.29997)
					(mid 16.003263 -382.053331)
					(end 17.249902 -381.536956)
				)
				(arc
					(start 23.750016 -381.536956)
					(mid 24.996655 -382.053331)
					(end 25.51303 -383.29997)
				)
				(arc
					(start 25.51303 -384.999992)
					(mid 25.58244 -385.167564)
					(end 25.750012 -385.236974)
				)
				(arc
					(start 71.300086 -385.236974)
					(mid 71.467658 -385.167564)
					(end 71.537068 -384.999992)
				)
				(arc
					(start 71.537068 -381)
					(mid 72.053443 -379.753361)
					(end 73.300082 -379.236986)
				)
				(arc
					(start 125.299978 -379.236986)
					(mid 126.546617 -379.753361)
					(end 127.062992 -381)
				)
				(arc
					(start 127.062992 -384.999992)
					(mid 127.132402 -385.167564)
					(end 127.299974 -385.236974)
				)
				(arc
					(start 172.850048 -385.236974)
					(mid 173.01762 -385.167564)
					(end 173.08703 -384.999992)
				)
				(arc
					(start 173.08703 -383.29997)
					(mid 173.603405 -382.053331)
					(end 174.850044 -381.536956)
				)
				(arc
					(start 181.349904 -381.536956)
					(mid 182.596543 -382.053331)
					(end 183.112918 -383.29997)
				)
				(arc
					(start 183.112918 -384.999992)
					(mid 183.182328 -385.167564)
					(end 183.3499 -385.236974)
				)
				(arc
					(start 197.000114 -385.236974)
					(mid 197.167686 -385.167564)
					(end 197.237096 -384.999992)
				)
				(arc
					(start 197.237096 -381)
					(mid 197.753471 -379.753361)
					(end 199.00011 -379.236986)
				)
				(arc
					(start 251.000006 -379.236986)
					(mid 252.246645 -379.753361)
					(end 252.76302 -381)
				)
				(arc
					(start 252.76302 -384.999992)
					(mid 252.83243 -385.167564)
					(end 253.000002 -385.236974)
				)
				(arc
					(start 269.036292 -385.236974)
					(mid 269.126761 -385.218921)
					(end 269.203424 -385.167632)
				)
				(arc
					(start 271.617694 -382.753362)
					(mid 271.668989 -382.676683)
					(end 271.687036 -382.58623)
				)
				(arc
					(start 271.687036 -361.00004)
					(mid 272.203411 -359.753401)
					(end 273.45005 -359.237026)
				)
				(arc
					(start 275.75002 -359.237026)
					(mid 276.996659 -359.753401)
					(end 277.513034 -361.00004)
				)
				(arc
					(start 277.513034 -382.58623)
					(mid 277.531087 -382.676699)
					(end 277.582376 -382.753362)
				)
				(arc
					(start 279.996646 -385.167632)
					(mid 280.07334 -385.218844)
					(end 280.163778 -385.236974)
				)
				(arc
					(start 306.649882 -385.236974)
					(mid 306.817454 -385.167564)
					(end 306.886864 -384.999992)
				)
				(arc
					(start 306.886864 -383.29997)
					(mid 307.403239 -382.053331)
					(end 308.649878 -381.536956)
				)
				(arc
					(start 315.149992 -381.536956)
					(mid 316.396631 -382.053331)
					(end 316.913006 -383.29997)
				)
				(arc
					(start 316.913006 -384.999992)
					(mid 316.982416 -385.167564)
					(end 317.149988 -385.236974)
				)
				(arc
					(start 362.700062 -385.236974)
					(mid 362.867634 -385.167564)
					(end 362.937044 -384.999992)
				)
				(arc
					(start 362.937044 -381)
					(mid 363.453419 -379.753361)
					(end 364.700058 -379.236986)
				)
				(arc
					(start 416.699954 -379.236986)
					(mid 417.946593 -379.753361)
					(end 418.462968 -381)
				)
				(arc
					(start 418.462968 -384.999992)
					(mid 418.532378 -385.167564)
					(end 418.69995 -385.236974)
				)
				(arc
					(start 464.250024 -385.236974)
					(mid 464.417596 -385.167564)
					(end 464.487006 -384.999992)
				)
				(arc
					(start 464.487006 -383.29997)
					(mid 465.003381 -382.053331)
					(end 466.25002 -381.536956)
				)
				(arc
					(start 472.74988 -381.536956)
					(mid 473.996519 -382.053331)
					(end 474.512894 -383.29997)
				)
				(arc
					(start 474.512894 -384.999992)
					(mid 474.582304 -385.167564)
					(end 474.749876 -385.236974)
				)
				(arc
					(start 487.449876 -385.236974)
					(mid 487.617448 -385.167564)
					(end 487.686858 -384.999992)
				)
				(arc
					(start 487.686858 -372.000018)
					(mid 488.203143 -370.753469)
					(end 489.449618 -370.237004)
				)
				(arc
					(start 490.450124 -370.237004)
					(mid 490.617696 -370.167594)
					(end 490.687106 -370.000022)
				)
				(arc
					(start 490.687106 -0.999998)
					(mid 490.617696 -0.832426)
					(end 490.450124 -0.763016)
				)
				(arc
					(start 311.999884 -0.763016)
					(mid 311.832312 -0.832426)
					(end 311.762902 -0.999998)
				)
				(arc
					(start 311.762902 -47.200058)
					(mid 311.246527 -48.446697)
					(end 309.999888 -48.963072)
				)
				(arc
					(start 269.999968 -48.963072)
					(mid 269.832396 -49.032482)
					(end 269.762986 -49.200054)
				)
				(arc
					(start 269.762986 -61.999876)
					(mid 269.246611 -63.246515)
					(end 267.999972 -63.76289)
				)
				(arc
					(start 207.999838 -63.76289)
					(mid 206.753453 -63.246515)
					(end 206.237078 -62.00013)
				)
				(arc
					(start 206.237078 -49.200054)
					(mid 206.167668 -49.032482)
					(end 206.000096 -48.963072)
				)
				(arc
					(start 200.000108 -48.963072)
					(mid 198.753469 -48.446697)
					(end 198.237094 -47.200058)
				)
				(arc
					(start 198.237094 -0.999998)
					(mid 198.167684 -0.832426)
					(end 198.000112 -0.763016)
				)
			)
		)
		(polygon
			(pts
				(xy 179.171346 -359.6005) (xy 169.212006 -359.6005) (xy 167.615362 -361.197144) (xy 161.627566 -361.197144)
				(xy 161.071814 -361.752896) (xy 161.071814 -374.71604) (xy 165.589204 -379.23343) (xy 172.216064 -379.23343)
				(xy 175.465994 -375.9835) (xy 181.942994 -375.9835) (xy 184.9755 -372.950994) (xy 184.9755 -370.156994)
				(xy 186.2455 -368.886994) (xy 186.2455 -366.674654)
			)
		)
		(polygon
			(pts
				(xy 267.960094 -356.559612) (xy 247.77192 -356.559612) (xy 246.339614 -357.991918) (xy 239.645698 -357.991918)
				(xy 238.714788 -358.922828) (xy 238.714788 -369.497864) (xy 240.063528 -370.846604) (xy 246.335296 -370.846604)
				(xy 251.62256 -376.133868) (xy 258.322318 -376.133868) (xy 260.419596 -374.03659) (xy 260.419596 -371.815614)
				(xy 261.083298 -371.151912) (xy 265.909806 -371.151912) (xy 268.660372 -368.401346) (xy 268.660372 -357.25989)
			)
		)
		(polygon
			(pts
				(xy 204.307694 -328.7395) (xy 166.0144 -328.7395) (xy 166.0144 -358.5845) (xy 204.269594 -358.5845)
				(xy 204.8256 -358.028494) (xy 204.8256 -329.257406)
			)
		)
		(polygon
			(pts
				(xy 157.431994 -326.8345) (xy 152.194006 -326.8345) (xy 151.4475 -327.581006) (xy 151.4475 -330.756006)
				(xy 151.18461 -331.018896) (xy 104.06761 -331.018896) (xy 102.5525 -332.534006) (xy 102.5525 -346.280994)
				(xy 103.4415 -347.169994) (xy 103.4415 -364.348776) (xy 103.964994 -364.87227) (xy 109.369606 -364.87227)
				(xy 112.286796 -361.95508) (xy 123.153932 -361.95508) (xy 126.524512 -358.5845) (xy 160.9725 -358.5845)
				(xy 160.9725 -328.7395) (xy 158.066994 -328.7395) (xy 157.7975 -328.470006) (xy 157.7975 -327.200006)
			)
		)
		(polygon
			(pts
				(arc
					(start 159.193992 -248.115074)
					(mid 158.708852 -247.629934)
					(end 158.223712 -248.115074)
				)
				(arc
					(start 158.223712 -249.385328)
					(mid 158.708979 -249.870214)
					(end 159.193992 -249.385074)
				)
			)
		)
		(polygon
			(pts
				(arc
					(start 481.824792 -248.11482)
					(mid 481.339525 -247.629934)
					(end 480.854512 -248.115074)
				)
				(arc
					(start 480.854512 -249.385074)
					(mid 481.339652 -249.870214)
					(end 481.824792 -249.385074)
				)
			)
		)
		(polygon
			(pts
				(arc
					(start 450.27469 -248.11482)
					(mid 449.789423 -247.629934)
					(end 449.30441 -248.115074)
				)
				(arc
					(start 449.30441 -249.385074)
					(mid 449.78955 -249.870214)
					(end 450.27469 -249.385074)
				)
			)
		)
		(polygon
			(pts
				(arc
					(start 418.724842 -248.11482)
					(mid 418.239575 -247.629934)
					(end 417.754562 -248.115074)
				)
				(arc
					(start 417.754562 -249.385074)
					(mid 418.239702 -249.870214)
					(end 418.724842 -249.385074)
				)
			)
		)
		(polygon
			(pts
				(arc
					(start 387.17474 -248.11482)
					(mid 386.689473 -247.629934)
					(end 386.20446 -248.115074)
				)
				(arc
					(start 386.20446 -249.385074)
					(mid 386.6896 -249.870214)
					(end 387.17474 -249.385074)
				)
			)
		)
		(polygon
			(pts
				(arc
					(start 355.624892 -248.11482)
					(mid 355.139625 -247.629934)
					(end 354.654612 -248.115074)
				)
				(arc
					(start 354.654612 -249.385074)
					(mid 355.139752 -249.870214)
					(end 355.624892 -249.385074)
				)
			)
		)
		(polygon
			(pts
				(arc
					(start 324.07479 -248.11482)
					(mid 323.589523 -247.629934)
					(end 323.10451 -248.115074)
				)
				(arc
					(start 323.10451 -249.385074)
					(mid 323.58965 -249.870214)
					(end 324.07479 -249.385074)
				)
			)
		)
		(polygon
			(pts
				(arc
					(start 190.744094 -248.11482)
					(mid 190.258827 -247.629934)
					(end 189.773814 -248.115074)
				)
				(arc
					(start 189.773814 -249.385074)
					(mid 190.258954 -249.870214)
					(end 190.744094 -249.385074)
				)
			)
		)
		(polygon
			(pts
				(arc
					(start 127.64389 -248.11482)
					(mid 127.158623 -247.629934)
					(end 126.67361 -248.115074)
				)
				(arc
					(start 126.67361 -249.385074)
					(mid 127.15875 -249.870214)
					(end 127.64389 -249.385074)
				)
			)
		)
		(polygon
			(pts
				(arc
					(start 96.094042 -248.11482)
					(mid 95.608775 -247.629934)
					(end 95.123762 -248.115074)
				)
				(arc
					(start 95.123762 -249.385074)
					(mid 95.608902 -249.870214)
					(end 96.094042 -249.385074)
				)
			)
		)
		(polygon
			(pts
				(arc
					(start 64.54394 -248.11482)
					(mid 64.058673 -247.629934)
					(end 63.57366 -248.115074)
				)
				(arc
					(start 63.57366 -249.385074)
					(mid 64.0588 -249.870214)
					(end 64.54394 -249.385074)
				)
			)
		)
		(polygon
			(pts
				(arc
					(start 32.994092 -248.11482)
					(mid 32.508825 -247.629934)
					(end 32.023812 -248.115074)
				)
				(arc
					(start 32.023812 -249.385074)
					(mid 32.508952 -249.870214)
					(end 32.994092 -249.385074)
				)
			)
		)
		(polygon
			(pts
				(xy 486.306114 -247.149874) (xy 483.943914 -247.149874) (xy 483.943914 -250.350274) (xy 486.306114 -250.350274)
			)
		)
		(polygon
			(pts
				(xy 454.756012 -247.149874) (xy 452.393812 -247.149874) (xy 452.393812 -250.350274) (xy 454.756012 -250.350274)
			)
		)
		(polygon
			(pts
				(xy 423.206164 -247.149874) (xy 420.843964 -247.149874) (xy 420.843964 -250.350274) (xy 423.206164 -250.350274)
			)
		)
		(polygon
			(pts
				(xy 391.656062 -247.149874) (xy 389.293862 -247.149874) (xy 389.293862 -250.350274) (xy 391.656062 -250.350274)
			)
		)
		(polygon
			(pts
				(xy 360.106214 -247.149874) (xy 357.744014 -247.149874) (xy 357.744014 -250.350274) (xy 360.106214 -250.350274)
			)
		)
		(polygon
			(pts
				(xy 328.556112 -247.149874) (xy 326.193912 -247.149874) (xy 326.193912 -250.350274) (xy 328.556112 -250.350274)
			)
		)
		(polygon
			(pts
				(xy 188.956188 -247.149874) (xy 186.593988 -247.149874) (xy 186.593988 -250.350274) (xy 188.956188 -250.350274)
			)
		)
		(polygon
			(pts
				(xy 157.406086 -247.149874) (xy 155.043886 -247.149874) (xy 155.043886 -250.350274) (xy 157.406086 -250.350274)
			)
		)
		(polygon
			(pts
				(xy 125.855984 -247.149874) (xy 123.493784 -247.149874) (xy 123.493784 -250.350274) (xy 125.855984 -250.350274)
			)
		)
		(polygon
			(pts
				(xy 94.306136 -247.149874) (xy 91.943936 -247.149874) (xy 91.943936 -250.350274) (xy 94.306136 -250.350274)
			)
		)
		(polygon
			(pts
				(xy 62.756034 -247.149874) (xy 60.393834 -247.149874) (xy 60.393834 -250.350274) (xy 62.756034 -250.350274)
			)
		)
		(polygon
			(pts
				(xy 31.206186 -247.149874) (xy 28.843986 -247.149874) (xy 28.843986 -250.350274) (xy 31.206186 -250.350274)
			)
		)
		(polygon
			(pts
				(arc
					(start 479.841814 -245.117874)
					(mid 479.826935 -245.081953)
					(end 479.791014 -245.067074)
				)
				(arc
					(start 478.978214 -245.067074)
					(mid 478.942293 -245.081953)
					(end 478.927414 -245.117874)
				)
				(arc
					(start 478.927414 -245.321074)
					(mid 478.942293 -245.356995)
					(end 478.978214 -245.371874)
				)
				(arc
					(start 479.791014 -245.371874)
					(mid 479.826935 -245.356995)
					(end 479.841814 -245.321074)
				)
			)
		)
		(polygon
			(pts
				(arc
					(start 448.291712 -245.117874)
					(mid 448.276833 -245.081953)
					(end 448.240912 -245.067074)
				)
				(arc
					(start 447.428112 -245.067074)
					(mid 447.392191 -245.081953)
					(end 447.377312 -245.117874)
				)
				(arc
					(start 447.377312 -245.321074)
					(mid 447.392191 -245.356995)
					(end 447.428112 -245.371874)
				)
				(arc
					(start 448.240912 -245.371874)
					(mid 448.276833 -245.356995)
					(end 448.291712 -245.321074)
				)
			)
		)
		(polygon
			(pts
				(arc
					(start 416.741864 -245.117874)
					(mid 416.726985 -245.081953)
					(end 416.691064 -245.067074)
				)
				(arc
					(start 415.878264 -245.067074)
					(mid 415.842343 -245.081953)
					(end 415.827464 -245.117874)
				)
				(arc
					(start 415.827464 -245.321074)
					(mid 415.842343 -245.356995)
					(end 415.878264 -245.371874)
				)
				(arc
					(start 416.691064 -245.371874)
					(mid 416.726985 -245.356995)
					(end 416.741864 -245.321074)
				)
			)
		)
		(polygon
			(pts
				(arc
					(start 385.191762 -245.117874)
					(mid 385.176883 -245.081953)
					(end 385.140962 -245.067074)
				)
				(arc
					(start 384.328162 -245.067074)
					(mid 384.292241 -245.081953)
					(end 384.277362 -245.117874)
				)
				(arc
					(start 384.277362 -245.321074)
					(mid 384.292241 -245.356995)
					(end 384.328162 -245.371874)
				)
				(arc
					(start 385.140962 -245.371874)
					(mid 385.176883 -245.356995)
					(end 385.191762 -245.321074)
				)
			)
		)
		(polygon
			(pts
				(arc
					(start 353.641914 -245.117874)
					(mid 353.627035 -245.081953)
					(end 353.591114 -245.067074)
				)
				(arc
					(start 352.778314 -245.067074)
					(mid 352.742393 -245.081953)
					(end 352.727514 -245.117874)
				)
				(arc
					(start 352.727514 -245.321074)
					(mid 352.742393 -245.356995)
					(end 352.778314 -245.371874)
				)
				(arc
					(start 353.591114 -245.371874)
					(mid 353.627035 -245.356995)
					(end 353.641914 -245.321074)
				)
			)
		)
		(polygon
			(pts
				(arc
					(start 322.091812 -245.117874)
					(mid 322.076933 -245.081953)
					(end 322.041012 -245.067074)
				)
				(arc
					(start 321.228212 -245.067074)
					(mid 321.192291 -245.081953)
					(end 321.177412 -245.117874)
				)
				(arc
					(start 321.177412 -245.321074)
					(mid 321.192291 -245.356995)
					(end 321.228212 -245.371874)
				)
				(arc
					(start 322.041012 -245.371874)
					(mid 322.076933 -245.356995)
					(end 322.091812 -245.321074)
				)
			)
		)
		(polygon
			(pts
				(arc
					(start 190.670688 -245.117874)
					(mid 190.655809 -245.081953)
					(end 190.619888 -245.067074)
				)
				(arc
					(start 189.807088 -245.067074)
					(mid 189.771167 -245.081953)
					(end 189.756288 -245.117874)
				)
				(arc
					(start 189.756288 -245.321074)
					(mid 189.771167 -245.356995)
					(end 189.807088 -245.371874)
				)
				(arc
					(start 190.619888 -245.371874)
					(mid 190.655809 -245.356995)
					(end 190.670688 -245.321074)
				)
			)
		)
		(polygon
			(pts
				(arc
					(start 159.120586 -245.117874)
					(mid 159.105707 -245.081953)
					(end 159.069786 -245.067074)
				)
				(arc
					(start 158.256986 -245.067074)
					(mid 158.221065 -245.081953)
					(end 158.206186 -245.117874)
				)
				(arc
					(start 158.206186 -245.321074)
					(mid 158.221065 -245.356995)
					(end 158.256986 -245.371874)
				)
				(arc
					(start 159.069786 -245.371874)
					(mid 159.105707 -245.356995)
					(end 159.120586 -245.321074)
				)
			)
		)
		(polygon
			(pts
				(arc
					(start 127.570484 -245.117874)
					(mid 127.555605 -245.081953)
					(end 127.519684 -245.067074)
				)
				(arc
					(start 126.706884 -245.067074)
					(mid 126.670963 -245.081953)
					(end 126.656084 -245.117874)
				)
				(arc
					(start 126.656084 -245.321074)
					(mid 126.670963 -245.356995)
					(end 126.706884 -245.371874)
				)
				(arc
					(start 127.519684 -245.371874)
					(mid 127.555605 -245.356995)
					(end 127.570484 -245.321074)
				)
			)
		)
		(polygon
			(pts
				(arc
					(start 96.020636 -245.117874)
					(mid 96.005757 -245.081953)
					(end 95.969836 -245.067074)
				)
				(arc
					(start 95.157036 -245.067074)
					(mid 95.121115 -245.081953)
					(end 95.106236 -245.117874)
				)
				(arc
					(start 95.106236 -245.321074)
					(mid 95.121115 -245.356995)
					(end 95.157036 -245.371874)
				)
				(arc
					(start 95.969836 -245.371874)
					(mid 96.005757 -245.356995)
					(end 96.020636 -245.321074)
				)
			)
		)
		(polygon
			(pts
				(arc
					(start 64.470534 -245.117874)
					(mid 64.455655 -245.081953)
					(end 64.419734 -245.067074)
				)
				(arc
					(start 63.606934 -245.067074)
					(mid 63.571013 -245.081953)
					(end 63.556134 -245.117874)
				)
				(arc
					(start 63.556134 -245.321074)
					(mid 63.571013 -245.356995)
					(end 63.606934 -245.371874)
				)
				(arc
					(start 64.419734 -245.371874)
					(mid 64.455655 -245.356995)
					(end 64.470534 -245.321074)
				)
			)
		)
		(polygon
			(pts
				(arc
					(start 32.920686 -245.117874)
					(mid 32.905807 -245.081953)
					(end 32.869886 -245.067074)
				)
				(arc
					(start 32.057086 -245.067074)
					(mid 32.021165 -245.081953)
					(end 32.006286 -245.117874)
				)
				(arc
					(start 32.006286 -245.321074)
					(mid 32.021165 -245.356995)
					(end 32.057086 -245.371874)
				)
				(arc
					(start 32.869886 -245.371874)
					(mid 32.905807 -245.356995)
					(end 32.920686 -245.321074)
				)
			)
		)
		(polygon
			(pts
				(arc
					(start 479.841814 -244.559074)
					(mid 479.826935 -244.523153)
					(end 479.791014 -244.508274)
				)
				(arc
					(start 478.978214 -244.508274)
					(mid 478.942293 -244.523153)
					(end 478.927414 -244.559074)
				)
				(arc
					(start 478.927414 -244.762274)
					(mid 478.942293 -244.798195)
					(end 478.978214 -244.813074)
				)
				(arc
					(start 479.791014 -244.813074)
					(mid 479.826935 -244.798195)
					(end 479.841814 -244.762274)
				)
			)
		)
		(polygon
			(pts
				(arc
					(start 448.291712 -244.559074)
					(mid 448.276833 -244.523153)
					(end 448.240912 -244.508274)
				)
				(arc
					(start 447.428112 -244.508274)
					(mid 447.392191 -244.523153)
					(end 447.377312 -244.559074)
				)
				(arc
					(start 447.377312 -244.762274)
					(mid 447.392191 -244.798195)
					(end 447.428112 -244.813074)
				)
				(arc
					(start 448.240912 -244.813074)
					(mid 448.276833 -244.798195)
					(end 448.291712 -244.762274)
				)
			)
		)
		(polygon
			(pts
				(arc
					(start 416.741864 -244.559074)
					(mid 416.726985 -244.523153)
					(end 416.691064 -244.508274)
				)
				(arc
					(start 415.878264 -244.508274)
					(mid 415.842343 -244.523153)
					(end 415.827464 -244.559074)
				)
				(arc
					(start 415.827464 -244.762274)
					(mid 415.842343 -244.798195)
					(end 415.878264 -244.813074)
				)
				(arc
					(start 416.691064 -244.813074)
					(mid 416.726985 -244.798195)
					(end 416.741864 -244.762274)
				)
			)
		)
		(polygon
			(pts
				(arc
					(start 385.191762 -244.559074)
					(mid 385.176883 -244.523153)
					(end 385.140962 -244.508274)
				)
				(arc
					(start 384.328162 -244.508274)
					(mid 384.292241 -244.523153)
					(end 384.277362 -244.559074)
				)
				(arc
					(start 384.277362 -244.762274)
					(mid 384.292241 -244.798195)
					(end 384.328162 -244.813074)
				)
				(arc
					(start 385.140962 -244.813074)
					(mid 385.176883 -244.798195)
					(end 385.191762 -244.762274)
				)
			)
		)
		(polygon
			(pts
				(arc
					(start 353.641914 -244.559074)
					(mid 353.627035 -244.523153)
					(end 353.591114 -244.508274)
				)
				(arc
					(start 352.778314 -244.508274)
					(mid 352.742393 -244.523153)
					(end 352.727514 -244.559074)
				)
				(arc
					(start 352.727514 -244.762274)
					(mid 352.742393 -244.798195)
					(end 352.778314 -244.813074)
				)
				(arc
					(start 353.591114 -244.813074)
					(mid 353.627035 -244.798195)
					(end 353.641914 -244.762274)
				)
			)
		)
		(polygon
			(pts
				(arc
					(start 322.091812 -244.559074)
					(mid 322.076933 -244.523153)
					(end 322.041012 -244.508274)
				)
				(arc
					(start 321.228212 -244.508274)
					(mid 321.192291 -244.523153)
					(end 321.177412 -244.559074)
				)
				(arc
					(start 321.177412 -244.762274)
					(mid 321.192291 -244.798195)
					(end 321.228212 -244.813074)
				)
				(arc
					(start 322.041012 -244.813074)
					(mid 322.076933 -244.798195)
					(end 322.091812 -244.762274)
				)
			)
		)
		(polygon
			(pts
				(arc
					(start 190.670688 -244.559074)
					(mid 190.655809 -244.523153)
					(end 190.619888 -244.508274)
				)
				(arc
					(start 189.807088 -244.508274)
					(mid 189.771167 -244.523153)
					(end 189.756288 -244.559074)
				)
				(arc
					(start 189.756288 -244.762274)
					(mid 189.771167 -244.798195)
					(end 189.807088 -244.813074)
				)
				(arc
					(start 190.619888 -244.813074)
					(mid 190.655809 -244.798195)
					(end 190.670688 -244.762274)
				)
			)
		)
		(polygon
			(pts
				(arc
					(start 159.120586 -244.559074)
					(mid 159.105707 -244.523153)
					(end 159.069786 -244.508274)
				)
				(arc
					(start 158.256986 -244.508274)
					(mid 158.221065 -244.523153)
					(end 158.206186 -244.559074)
				)
				(arc
					(start 158.206186 -244.762274)
					(mid 158.221065 -244.798195)
					(end 158.256986 -244.813074)
				)
				(arc
					(start 159.069786 -244.813074)
					(mid 159.105707 -244.798195)
					(end 159.120586 -244.762274)
				)
			)
		)
		(polygon
			(pts
				(arc
					(start 127.570484 -244.559074)
					(mid 127.555605 -244.523153)
					(end 127.519684 -244.508274)
				)
				(arc
					(start 126.706884 -244.508274)
					(mid 126.670963 -244.523153)
					(end 126.656084 -244.559074)
				)
				(arc
					(start 126.656084 -244.762274)
					(mid 126.670963 -244.798195)
					(end 126.706884 -244.813074)
				)
				(arc
					(start 127.519684 -244.813074)
					(mid 127.555605 -244.798195)
					(end 127.570484 -244.762274)
				)
			)
		)
		(polygon
			(pts
				(arc
					(start 96.020636 -244.559074)
					(mid 96.005757 -244.523153)
					(end 95.969836 -244.508274)
				)
				(arc
					(start 95.157036 -244.508274)
					(mid 95.121115 -244.523153)
					(end 95.106236 -244.559074)
				)
				(arc
					(start 95.106236 -244.762274)
					(mid 95.121115 -244.798195)
					(end 95.157036 -244.813074)
				)
				(arc
					(start 95.969836 -244.813074)
					(mid 96.005757 -244.798195)
					(end 96.020636 -244.762274)
				)
			)
		)
		(polygon
			(pts
				(arc
					(start 64.470534 -244.559074)
					(mid 64.455655 -244.523153)
					(end 64.419734 -244.508274)
				)
				(arc
					(start 63.606934 -244.508274)
					(mid 63.571013 -244.523153)
					(end 63.556134 -244.559074)
				)
				(arc
					(start 63.556134 -244.762274)
					(mid 63.571013 -244.798195)
					(end 63.606934 -244.813074)
				)
				(arc
					(start 64.419734 -244.813074)
					(mid 64.455655 -244.798195)
					(end 64.470534 -244.762274)
				)
			)
		)
		(polygon
			(pts
				(arc
					(start 32.920686 -244.559074)
					(mid 32.905807 -244.523153)
					(end 32.869886 -244.508274)
				)
				(arc
					(start 32.057086 -244.508274)
					(mid 32.021165 -244.523153)
					(end 32.006286 -244.559074)
				)
				(arc
					(start 32.006286 -244.762274)
					(mid 32.021165 -244.798195)
					(end 32.057086 -244.813074)
				)
				(arc
					(start 32.869886 -244.813074)
					(mid 32.905807 -244.798195)
					(end 32.920686 -244.762274)
				)
			)
		)
		(polygon
			(pts
				(arc
					(start 414.527492 -244.444774)
					(mid 414.042352 -243.959634)
					(end 413.557212 -244.444774)
				)
				(arc
					(start 413.557212 -245.588028)
					(mid 414.042479 -246.072914)
					(end 414.527492 -245.587774)
				)
			)
		)
		(polygon
			(pts
				(arc
					(start 192.520824 -244.419374)
					(mid 192.035684 -243.934234)
					(end 191.550544 -244.419374)
				)
				(arc
					(start 191.550544 -245.562628)
					(mid 192.035811 -246.047514)
					(end 192.520824 -245.562374)
				)
			)
		)
		(polygon
			(pts
				(arc
					(start 160.970722 -244.419374)
					(mid 160.485582 -243.934234)
					(end 160.000442 -244.419374)
				)
				(arc
					(start 160.000442 -245.562628)
					(mid 160.485709 -246.047514)
					(end 160.970722 -245.562374)
				)
			)
		)
		(polygon
			(pts
				(arc
					(start 129.42062 -244.419374)
					(mid 128.93548 -243.934234)
					(end 128.45034 -244.419374)
				)
				(arc
					(start 128.45034 -245.562628)
					(mid 128.935607 -246.047514)
					(end 129.42062 -245.562374)
				)
			)
		)
		(polygon
			(pts
				(arc
					(start 97.870772 -244.419374)
					(mid 97.385632 -243.934234)
					(end 96.900492 -244.419374)
				)
				(arc
					(start 96.900492 -245.562628)
					(mid 97.385759 -246.047514)
					(end 97.870772 -245.562374)
				)
			)
		)
		(polygon
			(pts
				(arc
					(start 66.32067 -244.419374)
					(mid 65.83553 -243.934234)
					(end 65.35039 -244.419374)
				)
				(arc
					(start 65.35039 -245.562628)
					(mid 65.835657 -246.047514)
					(end 66.32067 -245.562374)
				)
			)
		)
		(polygon
			(pts
				(arc
					(start 34.770822 -244.419374)
					(mid 34.285682 -243.934234)
					(end 33.800542 -244.419374)
				)
				(arc
					(start 33.800542 -245.562628)
					(mid 34.285809 -246.047514)
					(end 34.770822 -245.562374)
				)
			)
		)
		(polygon
			(pts
				(arc
					(start 351.427542 -244.317774)
					(mid 350.942402 -243.832634)
					(end 350.457262 -244.317774)
				)
				(arc
					(start 350.457262 -245.461028)
					(mid 350.942529 -245.945914)
					(end 351.427542 -245.460774)
				)
			)
		)
		(polygon
			(pts
				(arc
					(start 477.637602 -244.312694)
					(mid 477.152462 -243.827554)
					(end 476.667322 -244.312694)
				)
				(arc
					(start 476.667322 -245.455948)
					(mid 477.152589 -245.940834)
					(end 477.637602 -245.455694)
				)
			)
		)
		(polygon
			(pts
				(arc
					(start 446.0875 -244.312694)
					(mid 445.60236 -243.827554)
					(end 445.11722 -244.312694)
				)
				(arc
					(start 445.11722 -245.455948)
					(mid 445.602487 -245.940834)
					(end 446.0875 -245.455694)
				)
			)
		)
		(polygon
			(pts
				(arc
					(start 319.8876 -244.312694)
					(mid 319.40246 -243.827554)
					(end 318.91732 -244.312694)
				)
				(arc
					(start 318.91732 -245.455948)
					(mid 319.402587 -245.940834)
					(end 319.8876 -245.455694)
				)
			)
		)
		(polygon
			(pts
				(arc
					(start 382.97739 -244.302534)
					(mid 382.49225 -243.817394)
					(end 382.00711 -244.302534)
				)
				(arc
					(start 382.00711 -245.445788)
					(mid 382.492377 -245.930674)
					(end 382.97739 -245.445534)
				)
			)
		)
		(polygon
			(pts
				(xy 486.306114 -243.339874) (xy 483.943914 -243.339874) (xy 483.943914 -246.540274) (xy 486.306114 -246.540274)
			)
		)
		(polygon
			(pts
				(xy 454.756012 -243.339874) (xy 452.393812 -243.339874) (xy 452.393812 -246.540274) (xy 454.756012 -246.540274)
			)
		)
		(polygon
			(pts
				(xy 423.206164 -243.339874) (xy 420.843964 -243.339874) (xy 420.843964 -246.540274) (xy 423.206164 -246.540274)
			)
		)
		(polygon
			(pts
				(xy 391.656062 -243.339874) (xy 389.293862 -243.339874) (xy 389.293862 -246.540274) (xy 391.656062 -246.540274)
			)
		)
		(polygon
			(pts
				(xy 360.106214 -243.339874) (xy 357.744014 -243.339874) (xy 357.744014 -246.540274) (xy 360.106214 -246.540274)
			)
		)
		(polygon
			(pts
				(xy 328.556112 -243.339874) (xy 326.193912 -243.339874) (xy 326.193912 -246.540274) (xy 328.556112 -246.540274)
			)
		)
		(polygon
			(pts
				(xy 188.956188 -243.339874) (xy 186.593988 -243.339874) (xy 186.593988 -246.540274) (xy 188.956188 -246.540274)
			)
		)
		(polygon
			(pts
				(xy 157.406086 -243.339874) (xy 155.043886 -243.339874) (xy 155.043886 -246.540274) (xy 157.406086 -246.540274)
			)
		)
		(polygon
			(pts
				(xy 125.855984 -243.339874) (xy 123.493784 -243.339874) (xy 123.493784 -246.540274) (xy 125.855984 -246.540274)
			)
		)
		(polygon
			(pts
				(xy 94.306136 -243.339874) (xy 91.943936 -243.339874) (xy 91.943936 -246.540274) (xy 94.306136 -246.540274)
			)
		)
		(polygon
			(pts
				(xy 62.756034 -243.339874) (xy 60.393834 -243.339874) (xy 60.393834 -246.540274) (xy 62.756034 -246.540274)
			)
		)
		(polygon
			(pts
				(xy 31.206186 -243.339874) (xy 28.843986 -243.339874) (xy 28.843986 -246.540274) (xy 31.206186 -246.540274)
			)
		)
		(polygon
			(pts
				(arc
					(start 287.83661 -239.243108)
					(mid 288.38525 -238.694468)
					(end 287.83661 -238.145828)
				)
				(arc
					(start 286.436562 -238.145828)
					(mid 285.887922 -238.694468)
					(end 286.436562 -239.243108)
				)
			)
		)
		(polygon
			(pts
				(arc
					(start 280.636726 -239.243108)
					(mid 281.185366 -238.694468)
					(end 280.636726 -238.145828)
				)
				(arc
					(start 279.236678 -238.145828)
					(mid 278.688038 -238.694468)
					(end 279.236678 -239.243108)
				)
			)
		)
		(polygon
			(pts
				(arc
					(start 286.836612 -237.44301)
					(mid 287.385252 -236.89437)
					(end 286.836612 -236.34573)
				)
				(arc
					(start 285.436564 -236.34573)
					(mid 284.887924 -236.89437)
					(end 285.436564 -237.44301)
				)
			)
		)
		(polygon
			(pts
				(arc
					(start 279.636728 -237.44301)
					(mid 280.185368 -236.89437)
					(end 279.636728 -236.34573)
				)
				(arc
					(start 278.23668 -236.34573)
					(mid 277.68804 -236.89437)
					(end 278.23668 -237.44301)
				)
			)
		)
		(polygon
			(pts
				(arc
					(start 287.83661 -235.643166)
					(mid 288.38525 -235.094526)
					(end 287.83661 -234.545886)
				)
				(arc
					(start 286.436562 -234.545886)
					(mid 285.887922 -235.094526)
					(end 286.436562 -235.643166)
				)
			)
		)
		(polygon
			(pts
				(arc
					(start 280.636726 -235.643166)
					(mid 281.185366 -235.094526)
					(end 280.636726 -234.545886)
				)
				(arc
					(start 279.236678 -234.545886)
					(mid 278.688038 -235.094526)
					(end 279.236678 -235.643166)
				)
			)
		)
		(polygon
			(pts
				(arc
					(start 286.836612 -233.843068)
					(mid 287.385252 -233.294428)
					(end 286.836612 -232.745788)
				)
				(arc
					(start 285.436564 -232.745788)
					(mid 284.887924 -233.294428)
					(end 285.436564 -233.843068)
				)
			)
		)
		(polygon
			(pts
				(arc
					(start 279.636728 -233.843068)
					(mid 280.185368 -233.294428)
					(end 279.636728 -232.745788)
				)
				(arc
					(start 278.23668 -232.745788)
					(mid 277.68804 -233.294428)
					(end 278.23668 -233.843068)
				)
			)
		)
		(polygon
			(pts
				(arc
					(start 287.83661 -232.043224)
					(mid 288.38525 -231.494584)
					(end 287.83661 -230.945944)
				)
				(arc
					(start 286.436562 -230.945944)
					(mid 285.887922 -231.494584)
					(end 286.436562 -232.043224)
				)
			)
		)
		(polygon
			(pts
				(arc
					(start 280.636726 -232.043224)
					(mid 281.185366 -231.494584)
					(end 280.636726 -230.945944)
				)
				(arc
					(start 279.236678 -230.945944)
					(mid 278.688038 -231.494584)
					(end 279.236678 -232.043224)
				)
			)
		)
		(polygon
			(pts
				(arc
					(start 286.836612 -230.243126)
					(mid 287.385252 -229.694486)
					(end 286.836612 -229.145846)
				)
				(arc
					(start 285.436564 -229.145846)
					(mid 284.887924 -229.694486)
					(end 285.436564 -230.243126)
				)
			)
		)
		(polygon
			(pts
				(arc
					(start 279.636728 -230.243126)
					(mid 280.185368 -229.694486)
					(end 279.636728 -229.145846)
				)
				(arc
					(start 278.23668 -229.145846)
					(mid 277.68804 -229.694486)
					(end 278.23668 -230.243126)
				)
			)
		)
		(polygon
			(pts
				(arc
					(start 287.83661 -228.443028)
					(mid 288.38525 -227.894388)
					(end 287.83661 -227.345748)
				)
				(arc
					(start 286.436562 -227.345748)
					(mid 285.887922 -227.894388)
					(end 286.436562 -228.443028)
				)
			)
		)
		(polygon
			(pts
				(arc
					(start 280.636726 -228.443028)
					(mid 281.185366 -227.894388)
					(end 280.636726 -227.345748)
				)
				(arc
					(start 279.236678 -227.345748)
					(mid 278.688038 -227.894388)
					(end 279.236678 -228.443028)
				)
			)
		)
		(polygon
			(pts
				(arc
					(start 286.836612 -226.643184)
					(mid 287.385252 -226.094544)
					(end 286.836612 -225.545904)
				)
				(arc
					(start 285.436564 -225.545904)
					(mid 284.887924 -226.094544)
					(end 285.436564 -226.643184)
				)
			)
		)
		(polygon
			(pts
				(arc
					(start 279.636728 -226.643184)
					(mid 280.185368 -226.094544)
					(end 279.636728 -225.545904)
				)
				(arc
					(start 278.23668 -225.545904)
					(mid 277.68804 -226.094544)
					(end 278.23668 -226.643184)
				)
			)
		)
		(polygon
			(pts
				(arc
					(start 280.636726 -224.843086)
					(mid 281.185366 -224.294446)
					(end 280.636726 -223.745806)
				)
				(arc
					(start 279.236678 -223.745806)
					(mid 278.688038 -224.294446)
					(end 279.236678 -224.843086)
				)
			)
		)
		(polygon
			(pts
				(arc
					(start 287.83661 -224.906586)
					(mid 288.44875 -224.294446)
					(end 287.83661 -223.682306)
				)
				(arc
					(start 286.436562 -223.682306)
					(mid 285.824422 -224.294446)
					(end 286.436562 -224.906586)
				)
			)
		)
		(polygon
			(pts
				(arc
					(start 286.836612 -223.042988)
					(mid 287.385252 -222.494348)
					(end 286.836612 -221.945708)
				)
				(arc
					(start 285.436564 -221.945708)
					(mid 284.887924 -222.494348)
					(end 285.436564 -223.042988)
				)
			)
		)
		(polygon
			(pts
				(arc
					(start 279.636728 -223.042988)
					(mid 280.185368 -222.494348)
					(end 279.636728 -221.945708)
				)
				(arc
					(start 278.23668 -221.945708)
					(mid 277.68804 -222.494348)
					(end 278.23668 -223.042988)
				)
			)
		)
		(polygon
			(pts
				(arc
					(start 287.83661 -221.243144)
					(mid 288.38525 -220.694504)
					(end 287.83661 -220.145864)
				)
				(arc
					(start 286.436562 -220.145864)
					(mid 285.887922 -220.694504)
					(end 286.436562 -221.243144)
				)
			)
		)
		(polygon
			(pts
				(arc
					(start 280.636726 -221.243144)
					(mid 281.185366 -220.694504)
					(end 280.636726 -220.145864)
				)
				(arc
					(start 279.236678 -220.145864)
					(mid 278.688038 -220.694504)
					(end 279.236678 -221.243144)
				)
			)
		)
		(polygon
			(pts
				(arc
					(start 286.836612 -219.443046)
					(mid 287.385252 -218.894406)
					(end 286.836612 -218.345766)
				)
				(arc
					(start 285.436564 -218.345766)
					(mid 284.887924 -218.894406)
					(end 285.436564 -219.443046)
				)
			)
		)
		(polygon
			(pts
				(arc
					(start 279.636728 -219.443046)
					(mid 280.185368 -218.894406)
					(end 279.636728 -218.345766)
				)
				(arc
					(start 278.23668 -218.345766)
					(mid 277.68804 -218.894406)
					(end 278.23668 -219.443046)
				)
			)
		)
		(polygon
			(pts
				(arc
					(start 287.83661 -217.643202)
					(mid 288.38525 -217.094562)
					(end 287.83661 -216.545922)
				)
				(arc
					(start 286.436562 -216.545922)
					(mid 285.887922 -217.094562)
					(end 286.436562 -217.643202)
				)
			)
		)
		(polygon
			(pts
				(arc
					(start 280.636726 -217.643202)
					(mid 281.185366 -217.094562)
					(end 280.636726 -216.545922)
				)
				(arc
					(start 279.236678 -216.545922)
					(mid 278.688038 -217.094562)
					(end 279.236678 -217.643202)
				)
			)
		)
		(polygon
			(pts
				(arc
					(start 286.836612 -215.843104)
					(mid 287.385252 -215.294464)
					(end 286.836612 -214.745824)
				)
				(arc
					(start 285.436564 -214.745824)
					(mid 284.887924 -215.294464)
					(end 285.436564 -215.843104)
				)
			)
		)
		(polygon
			(pts
				(arc
					(start 279.636728 -215.843104)
					(mid 280.185368 -215.294464)
					(end 279.636728 -214.745824)
				)
				(arc
					(start 278.23668 -214.745824)
					(mid 277.68804 -215.294464)
					(end 278.23668 -215.843104)
				)
			)
		)
		(polygon
			(pts
				(arc
					(start 287.83661 -214.043006)
					(mid 288.38525 -213.494366)
					(end 287.83661 -212.945726)
				)
				(arc
					(start 286.436562 -212.945726)
					(mid 285.887922 -213.494366)
					(end 286.436562 -214.043006)
				)
			)
		)
		(polygon
			(pts
				(arc
					(start 280.636726 -214.043006)
					(mid 281.185366 -213.494366)
					(end 280.636726 -212.945726)
				)
				(arc
					(start 279.236678 -212.945726)
					(mid 278.688038 -213.494366)
					(end 279.236678 -214.043006)
				)
			)
		)
		(polygon
			(pts
				(arc
					(start 286.836612 -212.243162)
					(mid 287.385252 -211.694522)
					(end 286.836612 -211.145882)
				)
				(arc
					(start 285.436564 -211.145882)
					(mid 284.887924 -211.694522)
					(end 285.436564 -212.243162)
				)
			)
		)
		(polygon
			(pts
				(arc
					(start 279.636728 -212.243162)
					(mid 280.185368 -211.694522)
					(end 279.636728 -211.145882)
				)
				(arc
					(start 278.23668 -211.145882)
					(mid 277.68804 -211.694522)
					(end 278.23668 -212.243162)
				)
			)
		)
		(polygon
			(pts
				(arc
					(start 287.83661 -210.443064)
					(mid 288.38525 -209.894424)
					(end 287.83661 -209.345784)
				)
				(arc
					(start 286.436562 -209.345784)
					(mid 285.887922 -209.894424)
					(end 286.436562 -210.443064)
				)
			)
		)
		(polygon
			(pts
				(arc
					(start 280.636726 -210.443064)
					(mid 281.185366 -209.894424)
					(end 280.636726 -209.345784)
				)
				(arc
					(start 279.236678 -209.345784)
					(mid 278.688038 -209.894424)
					(end 279.236678 -210.443064)
				)
			)
		)
		(polygon
			(pts
				(arc
					(start 286.836612 -208.64322)
					(mid 287.385252 -208.09458)
					(end 286.836612 -207.54594)
				)
				(arc
					(start 285.436564 -207.54594)
					(mid 284.887924 -208.09458)
					(end 285.436564 -208.64322)
				)
			)
		)
		(polygon
			(pts
				(arc
					(start 279.636728 -208.64322)
					(mid 280.185368 -208.09458)
					(end 279.636728 -207.54594)
				)
				(arc
					(start 278.23668 -207.54594)
					(mid 277.68804 -208.09458)
					(end 278.23668 -208.64322)
				)
			)
		)
		(polygon
			(pts
				(arc
					(start 287.83661 -206.843122)
					(mid 288.38525 -206.294482)
					(end 287.83661 -205.745842)
				)
				(arc
					(start 286.436562 -205.745842)
					(mid 285.887922 -206.294482)
					(end 286.436562 -206.843122)
				)
			)
		)
		(polygon
			(pts
				(arc
					(start 280.636726 -206.843122)
					(mid 281.185366 -206.294482)
					(end 280.636726 -205.745842)
				)
				(arc
					(start 279.236678 -205.745842)
					(mid 278.688038 -206.294482)
					(end 279.236678 -206.843122)
				)
			)
		)
		(polygon
			(pts
				(arc
					(start 286.836612 -205.043024)
					(mid 287.385252 -204.494384)
					(end 286.836612 -203.945744)
				)
				(arc
					(start 285.436564 -203.945744)
					(mid 284.887924 -204.494384)
					(end 285.436564 -205.043024)
				)
			)
		)
		(polygon
			(pts
				(arc
					(start 279.636728 -205.043024)
					(mid 280.185368 -204.494384)
					(end 279.636728 -203.945744)
				)
				(arc
					(start 278.23668 -203.945744)
					(mid 277.68804 -204.494384)
					(end 278.23668 -205.043024)
				)
			)
		)
		(polygon
			(pts
				(arc
					(start 287.83661 -203.24318)
					(mid 288.38525 -202.69454)
					(end 287.83661 -202.1459)
				)
				(arc
					(start 286.436562 -202.1459)
					(mid 285.887922 -202.69454)
					(end 286.436562 -203.24318)
				)
			)
		)
		(polygon
			(pts
				(arc
					(start 280.636726 -203.24318)
					(mid 281.185366 -202.69454)
					(end 280.636726 -202.1459)
				)
				(arc
					(start 279.236678 -202.1459)
					(mid 278.688038 -202.69454)
					(end 279.236678 -203.24318)
				)
			)
		)
		(polygon
			(pts
				(arc
					(start 286.836612 -201.443082)
					(mid 287.385252 -200.894442)
					(end 286.836612 -200.345802)
				)
				(arc
					(start 285.436564 -200.345802)
					(mid 284.887924 -200.894442)
					(end 285.436564 -201.443082)
				)
			)
		)
		(polygon
			(pts
				(arc
					(start 279.636728 -201.443082)
					(mid 280.185368 -200.894442)
					(end 279.636728 -200.345802)
				)
				(arc
					(start 278.23668 -200.345802)
					(mid 277.68804 -200.894442)
					(end 278.23668 -201.443082)
				)
			)
		)
		(polygon
			(pts
				(arc
					(start 287.83661 -199.642984)
					(mid 288.38525 -199.094344)
					(end 287.83661 -198.545704)
				)
				(arc
					(start 286.436562 -198.545704)
					(mid 285.887922 -199.094344)
					(end 286.436562 -199.642984)
				)
			)
		)
		(polygon
			(pts
				(arc
					(start 280.636726 -199.642984)
					(mid 281.185366 -199.094344)
					(end 280.636726 -198.545704)
				)
				(arc
					(start 279.236678 -198.545704)
					(mid 278.688038 -199.094344)
					(end 279.236678 -199.642984)
				)
			)
		)
		(polygon
			(pts
				(arc
					(start 286.836612 -197.84314)
					(mid 287.385252 -197.2945)
					(end 286.836612 -196.74586)
				)
				(arc
					(start 285.436564 -196.74586)
					(mid 284.887924 -197.2945)
					(end 285.436564 -197.84314)
				)
			)
		)
		(polygon
			(pts
				(arc
					(start 279.636728 -197.84314)
					(mid 280.185368 -197.2945)
					(end 279.636728 -196.74586)
				)
				(arc
					(start 278.23668 -196.74586)
					(mid 277.68804 -197.2945)
					(end 278.23668 -197.84314)
				)
			)
		)
		(polygon
			(pts
				(arc
					(start 287.83661 -196.043042)
					(mid 288.38525 -195.494402)
					(end 287.83661 -194.945762)
				)
				(arc
					(start 286.436562 -194.945762)
					(mid 285.887922 -195.494402)
					(end 286.436562 -196.043042)
				)
			)
		)
		(polygon
			(pts
				(arc
					(start 280.636726 -196.043042)
					(mid 281.185366 -195.494402)
					(end 280.636726 -194.945762)
				)
				(arc
					(start 279.236678 -194.945762)
					(mid 278.688038 -195.494402)
					(end 279.236678 -196.043042)
				)
			)
		)
		(polygon
			(pts
				(arc
					(start 286.836612 -194.243198)
					(mid 287.385252 -193.694558)
					(end 286.836612 -193.145918)
				)
				(arc
					(start 285.436564 -193.145918)
					(mid 284.887924 -193.694558)
					(end 285.436564 -194.243198)
				)
			)
		)
		(polygon
			(pts
				(arc
					(start 279.636728 -194.243198)
					(mid 280.185368 -193.694558)
					(end 279.636728 -193.145918)
				)
				(arc
					(start 278.23668 -193.145918)
					(mid 277.68804 -193.694558)
					(end 278.23668 -194.243198)
				)
			)
		)
		(polygon
			(pts
				(arc
					(start 287.83661 -192.4431)
					(mid 288.38525 -191.89446)
					(end 287.83661 -191.34582)
				)
				(arc
					(start 286.436562 -191.34582)
					(mid 285.887922 -191.89446)
					(end 286.436562 -192.4431)
				)
			)
		)
		(polygon
			(pts
				(arc
					(start 280.636726 -192.4431)
					(mid 281.185366 -191.89446)
					(end 280.636726 -191.34582)
				)
				(arc
					(start 279.236678 -191.34582)
					(mid 278.688038 -191.89446)
					(end 279.236678 -192.4431)
				)
			)
		)
		(polygon
			(pts
				(arc
					(start 286.836612 -190.643002)
					(mid 287.385252 -190.094362)
					(end 286.836612 -189.545722)
				)
				(arc
					(start 285.436564 -189.545722)
					(mid 284.887924 -190.094362)
					(end 285.436564 -190.643002)
				)
			)
		)
		(polygon
			(pts
				(arc
					(start 279.636728 -190.643002)
					(mid 280.185368 -190.094362)
					(end 279.636728 -189.545722)
				)
				(arc
					(start 278.23668 -189.545722)
					(mid 277.68804 -190.094362)
					(end 278.23668 -190.643002)
				)
			)
		)
		(polygon
			(pts
				(arc
					(start 287.83661 -188.843158)
					(mid 288.38525 -188.294518)
					(end 287.83661 -187.745878)
				)
				(arc
					(start 286.436562 -187.745878)
					(mid 285.887922 -188.294518)
					(end 286.436562 -188.843158)
				)
			)
		)
		(polygon
			(pts
				(arc
					(start 280.636726 -188.843158)
					(mid 281.185366 -188.294518)
					(end 280.636726 -187.745878)
				)
				(arc
					(start 279.236678 -187.745878)
					(mid 278.688038 -188.294518)
					(end 279.236678 -188.843158)
				)
			)
		)
		(polygon
			(pts
				(arc
					(start 286.836612 -187.04306)
					(mid 287.385252 -186.49442)
					(end 286.836612 -185.94578)
				)
				(arc
					(start 285.436564 -185.94578)
					(mid 284.887924 -186.49442)
					(end 285.436564 -187.04306)
				)
			)
		)
		(polygon
			(pts
				(arc
					(start 279.636728 -187.04306)
					(mid 280.185368 -186.49442)
					(end 279.636728 -185.94578)
				)
				(arc
					(start 278.23668 -185.94578)
					(mid 277.68804 -186.49442)
					(end 278.23668 -187.04306)
				)
			)
		)
		(polygon
			(pts
				(arc
					(start 287.83661 -185.243216)
					(mid 288.38525 -184.694576)
					(end 287.83661 -184.145936)
				)
				(arc
					(start 286.436562 -184.145936)
					(mid 285.887922 -184.694576)
					(end 286.436562 -185.243216)
				)
			)
		)
		(polygon
			(pts
				(arc
					(start 280.636726 -185.243216)
					(mid 281.185366 -184.694576)
					(end 280.636726 -184.145936)
				)
				(arc
					(start 279.236678 -184.145936)
					(mid 278.688038 -184.694576)
					(end 279.236678 -185.243216)
				)
			)
		)
		(polygon
			(pts
				(arc
					(start 286.836612 -183.443118)
					(mid 287.385252 -182.894478)
					(end 286.836612 -182.345838)
				)
				(arc
					(start 285.436564 -182.345838)
					(mid 284.887924 -182.894478)
					(end 285.436564 -183.443118)
				)
			)
		)
		(polygon
			(pts
				(arc
					(start 279.636728 -183.443118)
					(mid 280.185368 -182.894478)
					(end 279.636728 -182.345838)
				)
				(arc
					(start 278.23668 -182.345838)
					(mid 277.68804 -182.894478)
					(end 278.23668 -183.443118)
				)
			)
		)
		(polygon
			(pts
				(arc
					(start 287.83661 -181.64302)
					(mid 288.38525 -181.09438)
					(end 287.83661 -180.54574)
				)
				(arc
					(start 286.436562 -180.54574)
					(mid 285.887922 -181.09438)
					(end 286.436562 -181.64302)
				)
			)
		)
		(polygon
			(pts
				(arc
					(start 280.636726 -181.64302)
					(mid 281.185366 -181.09438)
					(end 280.636726 -180.54574)
				)
				(arc
					(start 279.236678 -180.54574)
					(mid 278.688038 -181.09438)
					(end 279.236678 -181.64302)
				)
			)
		)
		(polygon
			(pts
				(arc
					(start 286.836612 -179.843176)
					(mid 287.385252 -179.294536)
					(end 286.836612 -178.745896)
				)
				(arc
					(start 285.436564 -178.745896)
					(mid 284.887924 -179.294536)
					(end 285.436564 -179.843176)
				)
			)
		)
		(polygon
			(pts
				(arc
					(start 279.636728 -179.843176)
					(mid 280.185368 -179.294536)
					(end 279.636728 -178.745896)
				)
				(arc
					(start 278.23668 -178.745896)
					(mid 277.68804 -179.294536)
					(end 278.23668 -179.843176)
				)
			)
		)
		(polygon
			(pts
				(arc
					(start 287.83661 -178.043078)
					(mid 288.38525 -177.494438)
					(end 287.83661 -176.945798)
				)
				(arc
					(start 286.436562 -176.945798)
					(mid 285.887922 -177.494438)
					(end 286.436562 -178.043078)
				)
			)
		)
		(polygon
			(pts
				(arc
					(start 280.636726 -178.043078)
					(mid 281.185366 -177.494438)
					(end 280.636726 -176.945798)
				)
				(arc
					(start 279.236678 -176.945798)
					(mid 278.688038 -177.494438)
					(end 279.236678 -178.043078)
				)
			)
		)
		(polygon
			(pts
				(arc
					(start 286.836612 -176.243234)
					(mid 287.385252 -175.694594)
					(end 286.836612 -175.145954)
				)
				(arc
					(start 285.436564 -175.145954)
					(mid 284.887924 -175.694594)
					(end 285.436564 -176.243234)
				)
			)
		)
		(polygon
			(pts
				(arc
					(start 279.636728 -176.243234)
					(mid 280.185368 -175.694594)
					(end 279.636728 -175.145954)
				)
				(arc
					(start 278.23668 -175.145954)
					(mid 277.68804 -175.694594)
					(end 278.23668 -176.243234)
				)
			)
		)
		(polygon
			(pts
				(arc
					(start 287.83661 -145.243042)
					(mid 288.38525 -144.694402)
					(end 287.83661 -144.145762)
				)
				(arc
					(start 286.436562 -144.145762)
					(mid 285.887922 -144.694402)
					(end 286.436562 -145.243042)
				)
			)
		)
		(polygon
			(pts
				(arc
					(start 284.236668 -145.243042)
					(mid 284.785308 -144.694402)
					(end 284.236668 -144.145762)
				)
				(arc
					(start 282.83662 -144.145762)
					(mid 282.28798 -144.694402)
					(end 282.83662 -145.243042)
				)
			)
		)
		(polygon
			(pts
				(arc
					(start 280.636726 -145.243042)
					(mid 281.185366 -144.694402)
					(end 280.636726 -144.145762)
				)
				(arc
					(start 279.236678 -144.145762)
					(mid 278.688038 -144.694402)
					(end 279.236678 -145.243042)
				)
			)
		)
		(polygon
			(pts
				(arc
					(start 286.836612 -143.442944)
					(mid 287.385252 -142.894304)
					(end 286.836612 -142.345664)
				)
				(arc
					(start 285.436564 -142.345664)
					(mid 284.887924 -142.894304)
					(end 285.436564 -143.442944)
				)
			)
		)
		(polygon
			(pts
				(arc
					(start 279.636728 -143.442944)
					(mid 280.185368 -142.894304)
					(end 279.636728 -142.345664)
				)
				(arc
					(start 278.23668 -142.345664)
					(mid 277.68804 -142.894304)
					(end 278.23668 -143.442944)
				)
			)
		)
		(polygon
			(pts
				(arc
					(start 287.83661 -141.6431)
					(mid 288.38525 -141.09446)
					(end 287.83661 -140.54582)
				)
				(arc
					(start 286.436562 -140.54582)
					(mid 285.887922 -141.09446)
					(end 286.436562 -141.6431)
				)
			)
		)
		(polygon
			(pts
				(arc
					(start 280.636726 -141.6431)
					(mid 281.185366 -141.09446)
					(end 280.636726 -140.54582)
				)
				(arc
					(start 279.236678 -140.54582)
					(mid 278.688038 -141.09446)
					(end 279.236678 -141.6431)
				)
			)
		)
		(polygon
			(pts
				(arc
					(start 286.836612 -139.843002)
					(mid 287.385252 -139.294362)
					(end 286.836612 -138.745722)
				)
				(arc
					(start 285.436564 -138.745722)
					(mid 284.887924 -139.294362)
					(end 285.436564 -139.843002)
				)
			)
		)
		(polygon
			(pts
				(arc
					(start 279.636728 -139.843002)
					(mid 280.185368 -139.294362)
					(end 279.636728 -138.745722)
				)
				(arc
					(start 278.23668 -138.745722)
					(mid 277.68804 -139.294362)
					(end 278.23668 -139.843002)
				)
			)
		)
		(polygon
			(pts
				(arc
					(start 287.83661 -138.043158)
					(mid 288.38525 -137.494518)
					(end 287.83661 -136.945878)
				)
				(arc
					(start 286.436562 -136.945878)
					(mid 285.887922 -137.494518)
					(end 286.436562 -138.043158)
				)
			)
		)
		(polygon
			(pts
				(arc
					(start 280.636726 -138.045698)
					(mid 281.187906 -137.494518)
					(end 280.636726 -136.943338)
				)
				(arc
					(start 279.236678 -136.943338)
					(mid 278.685498 -137.494518)
					(end 279.236678 -138.045698)
				)
			)
		)
		(polygon
			(pts
				(arc
					(start 286.836612 -136.24306)
					(mid 287.385252 -135.69442)
					(end 286.836612 -135.14578)
				)
				(arc
					(start 285.436564 -135.14578)
					(mid 284.887924 -135.69442)
					(end 285.436564 -136.24306)
				)
			)
		)
		(polygon
			(pts
				(arc
					(start 279.636728 -136.24306)
					(mid 280.185368 -135.69442)
					(end 279.636728 -135.14578)
				)
				(arc
					(start 278.23668 -135.14578)
					(mid 277.68804 -135.69442)
					(end 278.23668 -136.24306)
				)
			)
		)
		(polygon
			(pts
				(arc
					(start 287.83661 -134.442962)
					(mid 288.38525 -133.894322)
					(end 287.83661 -133.345682)
				)
				(arc
					(start 286.436562 -133.345682)
					(mid 285.887922 -133.894322)
					(end 286.436562 -134.442962)
				)
			)
		)
		(polygon
			(pts
				(arc
					(start 280.636726 -134.442962)
					(mid 281.185366 -133.894322)
					(end 280.636726 -133.345682)
				)
				(arc
					(start 279.236678 -133.345682)
					(mid 278.688038 -133.894322)
					(end 279.236678 -134.442962)
				)
			)
		)
		(polygon
			(pts
				(arc
					(start 159.193992 -133.11505)
					(mid 158.708852 -132.62991)
					(end 158.223712 -133.11505)
				)
				(arc
					(start 158.223712 -134.385304)
					(mid 158.708979 -134.87019)
					(end 159.193992 -134.38505)
				)
			)
		)
		(polygon
			(pts
				(arc
					(start 127.64389 -133.11505)
					(mid 127.15875 -132.62991)
					(end 126.67361 -133.11505)
				)
				(arc
					(start 126.67361 -134.385304)
					(mid 127.158877 -134.87019)
					(end 127.64389 -134.38505)
				)
			)
		)
		(polygon
			(pts
				(arc
					(start 96.094042 -133.11505)
					(mid 95.608902 -132.62991)
					(end 95.123762 -133.11505)
				)
				(arc
					(start 95.123762 -134.385304)
					(mid 95.609029 -134.87019)
					(end 96.094042 -134.38505)
				)
			)
		)
		(polygon
			(pts
				(arc
					(start 64.54394 -133.11505)
					(mid 64.0588 -132.62991)
					(end 63.57366 -133.11505)
				)
				(arc
					(start 63.57366 -134.385304)
					(mid 64.058927 -134.87019)
					(end 64.54394 -134.38505)
				)
			)
		)
		(polygon
			(pts
				(arc
					(start 32.994092 -133.11505)
					(mid 32.508952 -132.62991)
					(end 32.023812 -133.11505)
				)
				(arc
					(start 32.023812 -134.385304)
					(mid 32.509079 -134.87019)
					(end 32.994092 -134.38505)
				)
			)
		)
		(polygon
			(pts
				(arc
					(start 190.744094 -133.114796)
					(mid 190.258827 -132.62991)
					(end 189.773814 -133.11505)
				)
				(arc
					(start 189.773814 -134.38505)
					(mid 190.258954 -134.87019)
					(end 190.744094 -134.38505)
				)
			)
		)
		(polygon
			(pts
				(xy 486.306114 -132.14985) (xy 483.943914 -132.14985) (xy 483.943914 -135.35025) (xy 486.306114 -135.35025)
			)
		)
		(polygon
			(pts
				(xy 454.756012 -132.14985) (xy 452.393812 -132.14985) (xy 452.393812 -135.35025) (xy 454.756012 -135.35025)
			)
		)
		(polygon
			(pts
				(xy 423.206164 -132.14985) (xy 420.843964 -132.14985) (xy 420.843964 -135.35025) (xy 423.206164 -135.35025)
			)
		)
		(polygon
			(pts
				(xy 391.656062 -132.14985) (xy 389.293862 -132.14985) (xy 389.293862 -135.35025) (xy 391.656062 -135.35025)
			)
		)
		(polygon
			(pts
				(xy 360.106214 -132.14985) (xy 357.744014 -132.14985) (xy 357.744014 -135.35025) (xy 360.106214 -135.35025)
			)
		)
		(polygon
			(pts
				(xy 328.556112 -132.14985) (xy 326.193912 -132.14985) (xy 326.193912 -135.35025) (xy 328.556112 -135.35025)
			)
		)
		(polygon
			(pts
				(xy 188.956188 -132.14985) (xy 186.593988 -132.14985) (xy 186.593988 -135.35025) (xy 188.956188 -135.35025)
			)
		)
		(polygon
			(pts
				(xy 157.406086 -132.14985) (xy 155.043886 -132.14985) (xy 155.043886 -135.35025) (xy 157.406086 -135.35025)
			)
		)
		(polygon
			(pts
				(xy 125.855984 -132.14985) (xy 123.493784 -132.14985) (xy 123.493784 -135.35025) (xy 125.855984 -135.35025)
			)
		)
		(polygon
			(pts
				(xy 94.306136 -132.14985) (xy 91.943936 -132.14985) (xy 91.943936 -135.35025) (xy 94.306136 -135.35025)
			)
		)
		(polygon
			(pts
				(xy 62.756034 -132.14985) (xy 60.393834 -132.14985) (xy 60.393834 -135.35025) (xy 62.756034 -135.35025)
			)
		)
		(polygon
			(pts
				(xy 31.206186 -132.14985) (xy 28.843986 -132.14985) (xy 28.843986 -135.35025) (xy 31.206186 -135.35025)
			)
		)
		(polygon
			(pts
				(arc
					(start 481.701602 -132.922264)
					(mid 482.186742 -132.437124)
					(end 481.701602 -131.951984)
				)
				(arc
					(start 480.431348 -131.951984)
					(mid 479.946462 -132.437251)
					(end 480.431602 -132.922264)
				)
			)
		)
		(polygon
			(pts
				(arc
					(start 450.151754 -132.922264)
					(mid 450.63664 -132.436997)
					(end 450.1515 -131.951984)
				)
				(arc
					(start 448.8815 -131.951984)
					(mid 448.39636 -132.437124)
					(end 448.8815 -132.922264)
				)
			)
		)
		(polygon
			(pts
				(arc
					(start 418.601652 -132.922264)
					(mid 419.086792 -132.437124)
					(end 418.601652 -131.951984)
				)
				(arc
					(start 417.331398 -131.951984)
					(mid 416.846512 -132.437251)
					(end 417.331652 -132.922264)
				)
			)
		)
		(polygon
			(pts
				(arc
					(start 387.051804 -132.922264)
					(mid 387.53669 -132.436997)
					(end 387.05155 -131.951984)
				)
				(arc
					(start 385.78155 -131.951984)
					(mid 385.29641 -132.437124)
					(end 385.78155 -132.922264)
				)
			)
		)
		(polygon
			(pts
				(arc
					(start 355.501702 -132.922264)
					(mid 355.986842 -132.437124)
					(end 355.501702 -131.951984)
				)
				(arc
					(start 354.231448 -131.951984)
					(mid 353.746562 -132.437251)
					(end 354.231702 -132.922264)
				)
			)
		)
		(polygon
			(pts
				(arc
					(start 323.951854 -132.922264)
					(mid 324.43674 -132.436997)
					(end 323.9516 -131.951984)
				)
				(arc
					(start 322.6816 -131.951984)
					(mid 322.19646 -132.437124)
					(end 322.6816 -132.922264)
				)
			)
		)
		(polygon
			(pts
				(arc
					(start 286.836612 -132.643118)
					(mid 287.385252 -132.094478)
					(end 286.836612 -131.545838)
				)
				(arc
					(start 285.436564 -131.545838)
					(mid 284.887924 -132.094478)
					(end 285.436564 -132.643118)
				)
			)
		)
		(polygon
			(pts
				(arc
					(start 279.636728 -132.643118)
					(mid 280.185368 -132.094478)
					(end 279.636728 -131.545838)
				)
				(arc
					(start 278.23668 -131.545838)
					(mid 277.68804 -132.094478)
					(end 278.23668 -132.643118)
				)
			)
		)
		(polygon
			(pts
				(arc
					(start 479.841814 -130.11785)
					(mid 479.826935 -130.081929)
					(end 479.791014 -130.06705)
				)
				(arc
					(start 478.978214 -130.06705)
					(mid 478.942293 -130.081929)
					(end 478.927414 -130.11785)
				)
				(arc
					(start 478.927414 -130.32105)
					(mid 478.942293 -130.356971)
					(end 478.978214 -130.37185)
				)
				(arc
					(start 479.791014 -130.37185)
					(mid 479.826935 -130.356971)
					(end 479.841814 -130.32105)
				)
			)
		)
		(polygon
			(pts
				(arc
					(start 448.291712 -130.11785)
					(mid 448.276833 -130.081929)
					(end 448.240912 -130.06705)
				)
				(arc
					(start 447.428112 -130.06705)
					(mid 447.392191 -130.081929)
					(end 447.377312 -130.11785)
				)
				(arc
					(start 447.377312 -130.32105)
					(mid 447.392191 -130.356971)
					(end 447.428112 -130.37185)
				)
				(arc
					(start 448.240912 -130.37185)
					(mid 448.276833 -130.356971)
					(end 448.291712 -130.32105)
				)
			)
		)
		(polygon
			(pts
				(arc
					(start 416.741864 -130.11785)
					(mid 416.726985 -130.081929)
					(end 416.691064 -130.06705)
				)
				(arc
					(start 415.878264 -130.06705)
					(mid 415.842343 -130.081929)
					(end 415.827464 -130.11785)
				)
				(arc
					(start 415.827464 -130.32105)
					(mid 415.842343 -130.356971)
					(end 415.878264 -130.37185)
				)
				(arc
					(start 416.691064 -130.37185)
					(mid 416.726985 -130.356971)
					(end 416.741864 -130.32105)
				)
			)
		)
		(polygon
			(pts
				(arc
					(start 385.191762 -130.11785)
					(mid 385.176883 -130.081929)
					(end 385.140962 -130.06705)
				)
				(arc
					(start 384.328162 -130.06705)
					(mid 384.292241 -130.081929)
					(end 384.277362 -130.11785)
				)
				(arc
					(start 384.277362 -130.32105)
					(mid 384.292241 -130.356971)
					(end 384.328162 -130.37185)
				)
				(arc
					(start 385.140962 -130.37185)
					(mid 385.176883 -130.356971)
					(end 385.191762 -130.32105)
				)
			)
		)
		(polygon
			(pts
				(arc
					(start 353.641914 -130.11785)
					(mid 353.627035 -130.081929)
					(end 353.591114 -130.06705)
				)
				(arc
					(start 352.778314 -130.06705)
					(mid 352.742393 -130.081929)
					(end 352.727514 -130.11785)
				)
				(arc
					(start 352.727514 -130.32105)
					(mid 352.742393 -130.356971)
					(end 352.778314 -130.37185)
				)
				(arc
					(start 353.591114 -130.37185)
					(mid 353.627035 -130.356971)
					(end 353.641914 -130.32105)
				)
			)
		)
		(polygon
			(pts
				(arc
					(start 322.091812 -130.11785)
					(mid 322.076933 -130.081929)
					(end 322.041012 -130.06705)
				)
				(arc
					(start 321.228212 -130.06705)
					(mid 321.192291 -130.081929)
					(end 321.177412 -130.11785)
				)
				(arc
					(start 321.177412 -130.32105)
					(mid 321.192291 -130.356971)
					(end 321.228212 -130.37185)
				)
				(arc
					(start 322.041012 -130.37185)
					(mid 322.076933 -130.356971)
					(end 322.091812 -130.32105)
				)
			)
		)
		(polygon
			(pts
				(arc
					(start 190.670688 -130.11785)
					(mid 190.655809 -130.081929)
					(end 190.619888 -130.06705)
				)
				(arc
					(start 189.807088 -130.06705)
					(mid 189.771167 -130.081929)
					(end 189.756288 -130.11785)
				)
				(arc
					(start 189.756288 -130.32105)
					(mid 189.771167 -130.356971)
					(end 189.807088 -130.37185)
				)
				(arc
					(start 190.619888 -130.37185)
					(mid 190.655809 -130.356971)
					(end 190.670688 -130.32105)
				)
			)
		)
		(polygon
			(pts
				(arc
					(start 159.120586 -130.11785)
					(mid 159.105707 -130.081929)
					(end 159.069786 -130.06705)
				)
				(arc
					(start 158.256986 -130.06705)
					(mid 158.221065 -130.081929)
					(end 158.206186 -130.11785)
				)
				(arc
					(start 158.206186 -130.32105)
					(mid 158.221065 -130.356971)
					(end 158.256986 -130.37185)
				)
				(arc
					(start 159.069786 -130.37185)
					(mid 159.105707 -130.356971)
					(end 159.120586 -130.32105)
				)
			)
		)
		(polygon
			(pts
				(arc
					(start 127.570484 -130.11785)
					(mid 127.555605 -130.081929)
					(end 127.519684 -130.06705)
				)
				(arc
					(start 126.706884 -130.06705)
					(mid 126.670963 -130.081929)
					(end 126.656084 -130.11785)
				)
				(arc
					(start 126.656084 -130.32105)
					(mid 126.670963 -130.356971)
					(end 126.706884 -130.37185)
				)
				(arc
					(start 127.519684 -130.37185)
					(mid 127.555605 -130.356971)
					(end 127.570484 -130.32105)
				)
			)
		)
		(polygon
			(pts
				(arc
					(start 96.020636 -130.11785)
					(mid 96.005757 -130.081929)
					(end 95.969836 -130.06705)
				)
				(arc
					(start 95.157036 -130.06705)
					(mid 95.121115 -130.081929)
					(end 95.106236 -130.11785)
				)
				(arc
					(start 95.106236 -130.32105)
					(mid 95.121115 -130.356971)
					(end 95.157036 -130.37185)
				)
				(arc
					(start 95.969836 -130.37185)
					(mid 96.005757 -130.356971)
					(end 96.020636 -130.32105)
				)
			)
		)
		(polygon
			(pts
				(arc
					(start 64.470534 -130.11785)
					(mid 64.455655 -130.081929)
					(end 64.419734 -130.06705)
				)
				(arc
					(start 63.606934 -130.06705)
					(mid 63.571013 -130.081929)
					(end 63.556134 -130.11785)
				)
				(arc
					(start 63.556134 -130.32105)
					(mid 63.571013 -130.356971)
					(end 63.606934 -130.37185)
				)
				(arc
					(start 64.419734 -130.37185)
					(mid 64.455655 -130.356971)
					(end 64.470534 -130.32105)
				)
			)
		)
		(polygon
			(pts
				(arc
					(start 32.920686 -130.11785)
					(mid 32.905807 -130.081929)
					(end 32.869886 -130.06705)
				)
				(arc
					(start 32.057086 -130.06705)
					(mid 32.021165 -130.081929)
					(end 32.006286 -130.11785)
				)
				(arc
					(start 32.006286 -130.32105)
					(mid 32.021165 -130.356971)
					(end 32.057086 -130.37185)
				)
				(arc
					(start 32.869886 -130.37185)
					(mid 32.905807 -130.356971)
					(end 32.920686 -130.32105)
				)
			)
		)
		(polygon
			(pts
				(arc
					(start 479.841814 -129.55905)
					(mid 479.826935 -129.523129)
					(end 479.791014 -129.50825)
				)
				(arc
					(start 478.978214 -129.50825)
					(mid 478.942293 -129.523129)
					(end 478.927414 -129.55905)
				)
				(arc
					(start 478.927414 -129.76225)
					(mid 478.942293 -129.798171)
					(end 478.978214 -129.81305)
				)
				(arc
					(start 479.791014 -129.81305)
					(mid 479.826935 -129.798171)
					(end 479.841814 -129.76225)
				)
			)
		)
		(polygon
			(pts
				(arc
					(start 448.291712 -129.55905)
					(mid 448.276833 -129.523129)
					(end 448.240912 -129.50825)
				)
				(arc
					(start 447.428112 -129.50825)
					(mid 447.392191 -129.523129)
					(end 447.377312 -129.55905)
				)
				(arc
					(start 447.377312 -129.76225)
					(mid 447.392191 -129.798171)
					(end 447.428112 -129.81305)
				)
				(arc
					(start 448.240912 -129.81305)
					(mid 448.276833 -129.798171)
					(end 448.291712 -129.76225)
				)
			)
		)
		(polygon
			(pts
				(arc
					(start 416.741864 -129.55905)
					(mid 416.726985 -129.523129)
					(end 416.691064 -129.50825)
				)
				(arc
					(start 415.878264 -129.50825)
					(mid 415.842343 -129.523129)
					(end 415.827464 -129.55905)
				)
				(arc
					(start 415.827464 -129.76225)
					(mid 415.842343 -129.798171)
					(end 415.878264 -129.81305)
				)
				(arc
					(start 416.691064 -129.81305)
					(mid 416.726985 -129.798171)
					(end 416.741864 -129.76225)
				)
			)
		)
		(polygon
			(pts
				(arc
					(start 385.191762 -129.55905)
					(mid 385.176883 -129.523129)
					(end 385.140962 -129.50825)
				)
				(arc
					(start 384.328162 -129.50825)
					(mid 384.292241 -129.523129)
					(end 384.277362 -129.55905)
				)
				(arc
					(start 384.277362 -129.76225)
					(mid 384.292241 -129.798171)
					(end 384.328162 -129.81305)
				)
				(arc
					(start 385.140962 -129.81305)
					(mid 385.176883 -129.798171)
					(end 385.191762 -129.76225)
				)
			)
		)
		(polygon
			(pts
				(arc
					(start 353.641914 -129.55905)
					(mid 353.627035 -129.523129)
					(end 353.591114 -129.50825)
				)
				(arc
					(start 352.778314 -129.50825)
					(mid 352.742393 -129.523129)
					(end 352.727514 -129.55905)
				)
				(arc
					(start 352.727514 -129.76225)
					(mid 352.742393 -129.798171)
					(end 352.778314 -129.81305)
				)
				(arc
					(start 353.591114 -129.81305)
					(mid 353.627035 -129.798171)
					(end 353.641914 -129.76225)
				)
			)
		)
		(polygon
			(pts
				(arc
					(start 322.091812 -129.55905)
					(mid 322.076933 -129.523129)
					(end 322.041012 -129.50825)
				)
				(arc
					(start 321.228212 -129.50825)
					(mid 321.192291 -129.523129)
					(end 321.177412 -129.55905)
				)
				(arc
					(start 321.177412 -129.76225)
					(mid 321.192291 -129.798171)
					(end 321.228212 -129.81305)
				)
				(arc
					(start 322.041012 -129.81305)
					(mid 322.076933 -129.798171)
					(end 322.091812 -129.76225)
				)
			)
		)
		(polygon
			(pts
				(arc
					(start 190.670688 -129.55905)
					(mid 190.655809 -129.523129)
					(end 190.619888 -129.50825)
				)
				(arc
					(start 189.807088 -129.50825)
					(mid 189.771167 -129.523129)
					(end 189.756288 -129.55905)
				)
				(arc
					(start 189.756288 -129.76225)
					(mid 189.771167 -129.798171)
					(end 189.807088 -129.81305)
				)
				(arc
					(start 190.619888 -129.81305)
					(mid 190.655809 -129.798171)
					(end 190.670688 -129.76225)
				)
			)
		)
		(polygon
			(pts
				(arc
					(start 159.120586 -129.55905)
					(mid 159.105707 -129.523129)
					(end 159.069786 -129.50825)
				)
				(arc
					(start 158.256986 -129.50825)
					(mid 158.221065 -129.523129)
					(end 158.206186 -129.55905)
				)
				(arc
					(start 158.206186 -129.76225)
					(mid 158.221065 -129.798171)
					(end 158.256986 -129.81305)
				)
				(arc
					(start 159.069786 -129.81305)
					(mid 159.105707 -129.798171)
					(end 159.120586 -129.76225)
				)
			)
		)
		(polygon
			(pts
				(arc
					(start 127.570484 -129.55905)
					(mid 127.555605 -129.523129)
					(end 127.519684 -129.50825)
				)
				(arc
					(start 126.706884 -129.50825)
					(mid 126.670963 -129.523129)
					(end 126.656084 -129.55905)
				)
				(arc
					(start 126.656084 -129.76225)
					(mid 126.670963 -129.798171)
					(end 126.706884 -129.81305)
				)
				(arc
					(start 127.519684 -129.81305)
					(mid 127.555605 -129.798171)
					(end 127.570484 -129.76225)
				)
			)
		)
		(polygon
			(pts
				(arc
					(start 96.020636 -129.55905)
					(mid 96.005757 -129.523129)
					(end 95.969836 -129.50825)
				)
				(arc
					(start 95.157036 -129.50825)
					(mid 95.121115 -129.523129)
					(end 95.106236 -129.55905)
				)
				(arc
					(start 95.106236 -129.76225)
					(mid 95.121115 -129.798171)
					(end 95.157036 -129.81305)
				)
				(arc
					(start 95.969836 -129.81305)
					(mid 96.005757 -129.798171)
					(end 96.020636 -129.76225)
				)
			)
		)
		(polygon
			(pts
				(arc
					(start 64.470534 -129.55905)
					(mid 64.455655 -129.523129)
					(end 64.419734 -129.50825)
				)
				(arc
					(start 63.606934 -129.50825)
					(mid 63.571013 -129.523129)
					(end 63.556134 -129.55905)
				)
				(arc
					(start 63.556134 -129.76225)
					(mid 63.571013 -129.798171)
					(end 63.606934 -129.81305)
				)
				(arc
					(start 64.419734 -129.81305)
					(mid 64.455655 -129.798171)
					(end 64.470534 -129.76225)
				)
			)
		)
		(polygon
			(pts
				(arc
					(start 32.920686 -129.55905)
					(mid 32.905807 -129.523129)
					(end 32.869886 -129.50825)
				)
				(arc
					(start 32.057086 -129.50825)
					(mid 32.021165 -129.523129)
					(end 32.006286 -129.55905)
				)
				(arc
					(start 32.006286 -129.76225)
					(mid 32.021165 -129.798171)
					(end 32.057086 -129.81305)
				)
				(arc
					(start 32.869886 -129.81305)
					(mid 32.905807 -129.798171)
					(end 32.920686 -129.76225)
				)
			)
		)
		(polygon
			(pts
				(arc
					(start 192.520824 -129.419096)
					(mid 192.035557 -128.93421)
					(end 191.550544 -129.41935)
				)
				(arc
					(start 191.550544 -130.56235)
					(mid 192.035684 -131.04749)
					(end 192.520824 -130.56235)
				)
			)
		)
		(polygon
			(pts
				(arc
					(start 160.970722 -129.419096)
					(mid 160.485455 -128.93421)
					(end 160.000442 -129.41935)
				)
				(arc
					(start 160.000442 -130.56235)
					(mid 160.485582 -131.04749)
					(end 160.970722 -130.56235)
				)
			)
		)
		(polygon
			(pts
				(arc
					(start 129.42062 -129.419096)
					(mid 128.935353 -128.93421)
					(end 128.45034 -129.41935)
				)
				(arc
					(start 128.45034 -130.56235)
					(mid 128.93548 -131.04749)
					(end 129.42062 -130.56235)
				)
			)
		)
		(polygon
			(pts
				(arc
					(start 97.870772 -129.419096)
					(mid 97.385505 -128.93421)
					(end 96.900492 -129.41935)
				)
				(arc
					(start 96.900492 -130.56235)
					(mid 97.385632 -131.04749)
					(end 97.870772 -130.56235)
				)
			)
		)
		(polygon
			(pts
				(arc
					(start 66.32067 -129.419096)
					(mid 65.835403 -128.93421)
					(end 65.35039 -129.41935)
				)
				(arc
					(start 65.35039 -130.56235)
					(mid 65.83553 -131.04749)
					(end 66.32067 -130.56235)
				)
			)
		)
		(polygon
			(pts
				(arc
					(start 34.770822 -129.419096)
					(mid 34.285555 -128.93421)
					(end 33.800542 -129.41935)
				)
				(arc
					(start 33.800542 -130.56235)
					(mid 34.285682 -131.04749)
					(end 34.770822 -130.56235)
				)
			)
		)
		(polygon
			(pts
				(xy 486.306114 -128.33985) (xy 483.943914 -128.33985) (xy 483.943914 -131.54025) (xy 486.306114 -131.54025)
			)
		)
		(polygon
			(pts
				(xy 454.756012 -128.33985) (xy 452.393812 -128.33985) (xy 452.393812 -131.54025) (xy 454.756012 -131.54025)
			)
		)
		(polygon
			(pts
				(xy 423.206164 -128.33985) (xy 420.843964 -128.33985) (xy 420.843964 -131.54025) (xy 423.206164 -131.54025)
			)
		)
		(polygon
			(pts
				(xy 391.656062 -128.33985) (xy 389.293862 -128.33985) (xy 389.293862 -131.54025) (xy 391.656062 -131.54025)
			)
		)
		(polygon
			(pts
				(xy 360.106214 -128.33985) (xy 357.744014 -128.33985) (xy 357.744014 -131.54025) (xy 360.106214 -131.54025)
			)
		)
		(polygon
			(pts
				(xy 328.556112 -128.33985) (xy 326.193912 -128.33985) (xy 326.193912 -131.54025) (xy 328.556112 -131.54025)
			)
		)
		(polygon
			(pts
				(xy 188.956188 -128.33985) (xy 186.593988 -128.33985) (xy 186.593988 -131.54025) (xy 188.956188 -131.54025)
			)
		)
		(polygon
			(pts
				(xy 157.406086 -128.33985) (xy 155.043886 -128.33985) (xy 155.043886 -131.54025) (xy 157.406086 -131.54025)
			)
		)
		(polygon
			(pts
				(xy 125.855984 -128.33985) (xy 123.493784 -128.33985) (xy 123.493784 -131.54025) (xy 125.855984 -131.54025)
			)
		)
		(polygon
			(pts
				(xy 94.306136 -128.33985) (xy 91.943936 -128.33985) (xy 91.943936 -131.54025) (xy 94.306136 -131.54025)
			)
		)
		(polygon
			(pts
				(xy 62.756034 -128.33985) (xy 60.393834 -128.33985) (xy 60.393834 -131.54025) (xy 62.756034 -131.54025)
			)
		)
		(polygon
			(pts
				(xy 31.206186 -128.33985) (xy 28.843986 -128.33985) (xy 28.843986 -131.54025) (xy 31.206186 -131.54025)
			)
		)
		(polygon
			(pts
				(arc
					(start 478.107502 -129.112264)
					(mid 478.592642 -128.627124)
					(end 478.107502 -128.141984)
				)
				(arc
					(start 476.964248 -128.141984)
					(mid 476.479362 -128.627251)
					(end 476.964502 -129.112264)
				)
			)
		)
		(polygon
			(pts
				(arc
					(start 446.5574 -129.112264)
					(mid 447.04254 -128.627124)
					(end 446.5574 -128.141984)
				)
				(arc
					(start 445.414146 -128.141984)
					(mid 444.92926 -128.627251)
					(end 445.4144 -129.112264)
				)
			)
		)
		(polygon
			(pts
				(arc
					(start 415.007552 -129.112264)
					(mid 415.492692 -128.627124)
					(end 415.007552 -128.141984)
				)
				(arc
					(start 413.864298 -128.141984)
					(mid 413.379412 -128.627251)
					(end 413.864552 -129.112264)
				)
			)
		)
		(polygon
			(pts
				(arc
					(start 383.45745 -129.112264)
					(mid 383.94259 -128.627124)
					(end 383.45745 -128.141984)
				)
				(arc
					(start 382.314196 -128.141984)
					(mid 381.82931 -128.627251)
					(end 382.31445 -129.112264)
				)
			)
		)
		(polygon
			(pts
				(arc
					(start 351.907602 -129.112264)
					(mid 352.392742 -128.627124)
					(end 351.907602 -128.141984)
				)
				(arc
					(start 350.764348 -128.141984)
					(mid 350.279462 -128.627251)
					(end 350.764602 -129.112264)
				)
			)
		)
		(polygon
			(pts
				(arc
					(start 320.3575 -129.112264)
					(mid 320.84264 -128.627124)
					(end 320.3575 -128.141984)
				)
				(arc
					(start 319.214246 -128.141984)
					(mid 318.72936 -128.627251)
					(end 319.2145 -129.112264)
				)
			)
		)
		(polygon
			(pts
				(arc
					(start 221.348808 -77.599794)
					(mid 220.800041 -77.051408)
					(end 220.251528 -77.600048)
				)
				(arc
					(start 220.251528 -78.999842)
					(mid 220.800168 -79.548482)
					(end 221.348808 -78.999842)
				)
			)
		)
		(polygon
			(pts
				(arc
					(start 217.748612 -77.599794)
					(mid 217.199845 -77.051408)
					(end 216.651332 -77.600048)
				)
				(arc
					(start 216.651332 -78.999842)
					(mid 217.199972 -79.548482)
					(end 217.748612 -78.999842)
				)
			)
		)
		(polygon
			(pts
				(arc
					(start 214.14867 -77.599794)
					(mid 213.599903 -77.051408)
					(end 213.05139 -77.600048)
				)
				(arc
					(start 213.05139 -78.999842)
					(mid 213.60003 -79.548482)
					(end 214.14867 -78.999842)
				)
			)
		)
		(polygon
			(pts
				(arc
					(start 210.548728 -77.599794)
					(mid 209.999961 -77.051408)
					(end 209.451448 -77.600048)
				)
				(arc
					(start 209.451448 -78.999842)
					(mid 210.000088 -79.548482)
					(end 210.548728 -78.999842)
				)
			)
		)
		(polygon
			(pts
				(arc
					(start 223.148652 -76.399898)
					(mid 222.600012 -75.851258)
					(end 222.051372 -76.399898)
				)
				(arc
					(start 222.051372 -77.8002)
					(mid 222.600139 -78.348586)
					(end 223.148652 -77.799946)
				)
			)
		)
		(polygon
			(pts
				(arc
					(start 219.54871 -76.399898)
					(mid 219.00007 -75.851258)
					(end 218.45143 -76.399898)
				)
				(arc
					(start 218.45143 -77.8002)
					(mid 219.000197 -78.348586)
					(end 219.54871 -77.799946)
				)
			)
		)
		(polygon
			(pts
				(arc
					(start 215.948768 -76.399898)
					(mid 215.400128 -75.851258)
					(end 214.851488 -76.399898)
				)
				(arc
					(start 214.851488 -77.8002)
					(mid 215.400255 -78.348586)
					(end 215.948768 -77.799946)
				)
			)
		)
		(polygon
			(pts
				(arc
					(start 212.348826 -76.399898)
					(mid 211.800186 -75.851258)
					(end 211.251546 -76.399898)
				)
				(arc
					(start 211.251546 -77.8002)
					(mid 211.800313 -78.348586)
					(end 212.348826 -77.799946)
				)
			)
		)
		(polygon
			(pts
				(arc
					(start 210.548728 -73.999852)
					(mid 210.000088 -73.451212)
					(end 209.451448 -73.999852)
				)
				(arc
					(start 209.451448 -75.400154)
					(mid 210.000215 -75.94854)
					(end 210.548728 -75.3999)
				)
			)
		)
		(polygon
			(pts
				(arc
					(start 221.348808 -70.39991)
					(mid 220.800168 -69.85127)
					(end 220.251528 -70.39991)
				)
				(arc
					(start 220.251528 -71.800212)
					(mid 220.800295 -72.348598)
					(end 221.348808 -71.799958)
				)
			)
		)
		(polygon
			(pts
				(arc
					(start 217.748612 -70.39991)
					(mid 217.199972 -69.85127)
					(end 216.651332 -70.39991)
				)
				(arc
					(start 216.651332 -71.800212)
					(mid 217.200099 -72.348598)
					(end 217.748612 -71.799958)
				)
			)
		)
		(polygon
			(pts
				(arc
					(start 214.14867 -70.39991)
					(mid 213.60003 -69.85127)
					(end 213.05139 -70.39991)
				)
				(arc
					(start 213.05139 -71.800212)
					(mid 213.600157 -72.348598)
					(end 214.14867 -71.799958)
				)
			)
		)
		(polygon
			(pts
				(arc
					(start 210.548728 -70.39991)
					(mid 210.000088 -69.85127)
					(end 209.451448 -70.39991)
				)
				(arc
					(start 209.451448 -71.800212)
					(mid 210.000215 -72.348598)
					(end 210.548728 -71.799958)
				)
			)
		)
		(polygon
			(pts
				(arc
					(start 219.54871 -65.600072)
					(mid 219.00007 -65.051432)
					(end 218.45143 -65.600072)
				)
				(arc
					(start 218.45143 -67.00012)
					(mid 219.000197 -67.548506)
					(end 219.54871 -66.999866)
				)
			)
		)
		(polygon
			(pts
				(arc
					(start 215.948768 -65.600072)
					(mid 215.400128 -65.051432)
					(end 214.851488 -65.600072)
				)
				(arc
					(start 214.851488 -67.00012)
					(mid 215.400255 -67.548506)
					(end 215.948768 -66.999866)
				)
			)
		)
		(polygon
			(pts
				(arc
					(start 212.348826 -65.600072)
					(mid 211.800186 -65.051432)
					(end 211.251546 -65.600072)
				)
				(arc
					(start 211.251546 -67.00012)
					(mid 211.800313 -67.548506)
					(end 212.348826 -66.999866)
				)
			)
		)
		(polygon
			(pts
				(arc
					(start 223.148652 -65.599818)
					(mid 222.599885 -65.051432)
					(end 222.051372 -65.600072)
				)
				(arc
					(start 222.051372 -66.999866)
					(mid 222.600012 -67.548506)
					(end 223.148652 -66.999866)
				)
			)
		)
		(polygon
			(pts
				(arc
					(start 190.744094 -18.114772)
					(mid 190.258827 -17.629886)
					(end 189.773814 -18.115026)
				)
				(arc
					(start 189.773814 -19.385026)
					(mid 190.258954 -19.870166)
					(end 190.744094 -19.385026)
				)
			)
		)
		(polygon
			(pts
				(arc
					(start 159.193992 -18.114772)
					(mid 158.708725 -17.629886)
					(end 158.223712 -18.115026)
				)
				(arc
					(start 158.223712 -19.385026)
					(mid 158.708852 -19.870166)
					(end 159.193992 -19.385026)
				)
			)
		)
		(polygon
			(pts
				(arc
					(start 127.64389 -18.114772)
					(mid 127.158623 -17.629886)
					(end 126.67361 -18.115026)
				)
				(arc
					(start 126.67361 -19.385026)
					(mid 127.15875 -19.870166)
					(end 127.64389 -19.385026)
				)
			)
		)
		(polygon
			(pts
				(arc
					(start 96.094042 -18.114772)
					(mid 95.608775 -17.629886)
					(end 95.123762 -18.115026)
				)
				(arc
					(start 95.123762 -19.385026)
					(mid 95.608902 -19.870166)
					(end 96.094042 -19.385026)
				)
			)
		)
		(polygon
			(pts
				(arc
					(start 64.54394 -18.114772)
					(mid 64.058673 -17.629886)
					(end 63.57366 -18.115026)
				)
				(arc
					(start 63.57366 -19.385026)
					(mid 64.0588 -19.870166)
					(end 64.54394 -19.385026)
				)
			)
		)
		(polygon
			(pts
				(arc
					(start 32.994092 -18.114772)
					(mid 32.508825 -17.629886)
					(end 32.023812 -18.115026)
				)
				(arc
					(start 32.023812 -19.385026)
					(mid 32.508952 -19.870166)
					(end 32.994092 -19.385026)
				)
			)
		)
		(polygon
			(pts
				(xy 486.306114 -17.149826) (xy 483.943914 -17.149826) (xy 483.943914 -20.350226) (xy 486.306114 -20.350226)
			)
		)
		(polygon
			(pts
				(xy 454.756012 -17.149826) (xy 452.393812 -17.149826) (xy 452.393812 -20.350226) (xy 454.756012 -20.350226)
			)
		)
		(polygon
			(pts
				(xy 423.206164 -17.149826) (xy 420.843964 -17.149826) (xy 420.843964 -20.350226) (xy 423.206164 -20.350226)
			)
		)
		(polygon
			(pts
				(xy 391.656062 -17.149826) (xy 389.293862 -17.149826) (xy 389.293862 -20.350226) (xy 391.656062 -20.350226)
			)
		)
		(polygon
			(pts
				(xy 360.106214 -17.149826) (xy 357.744014 -17.149826) (xy 357.744014 -20.350226) (xy 360.106214 -20.350226)
			)
		)
		(polygon
			(pts
				(xy 328.556112 -17.149826) (xy 326.193912 -17.149826) (xy 326.193912 -20.350226) (xy 328.556112 -20.350226)
			)
		)
		(polygon
			(pts
				(xy 188.956188 -17.149826) (xy 186.593988 -17.149826) (xy 186.593988 -20.350226) (xy 188.956188 -20.350226)
			)
		)
		(polygon
			(pts
				(xy 157.406086 -17.149826) (xy 155.043886 -17.149826) (xy 155.043886 -20.350226) (xy 157.406086 -20.350226)
			)
		)
		(polygon
			(pts
				(xy 125.855984 -17.149826) (xy 123.493784 -17.149826) (xy 123.493784 -20.350226) (xy 125.855984 -20.350226)
			)
		)
		(polygon
			(pts
				(xy 94.306136 -17.149826) (xy 91.943936 -17.149826) (xy 91.943936 -20.350226) (xy 94.306136 -20.350226)
			)
		)
		(polygon
			(pts
				(xy 62.756034 -17.149826) (xy 60.393834 -17.149826) (xy 60.393834 -20.350226) (xy 62.756034 -20.350226)
			)
		)
		(polygon
			(pts
				(xy 31.206186 -17.149826) (xy 28.843986 -17.149826) (xy 28.843986 -20.350226) (xy 31.206186 -20.350226)
			)
		)
		(polygon
			(pts
				(arc
					(start 481.701602 -17.92224)
					(mid 482.186742 -17.4371)
					(end 481.701602 -16.95196)
				)
				(arc
					(start 480.431348 -16.95196)
					(mid 479.946462 -17.437227)
					(end 480.431602 -17.92224)
				)
			)
		)
		(polygon
			(pts
				(arc
					(start 450.151754 -17.92224)
					(mid 450.63664 -17.436973)
					(end 450.1515 -16.95196)
				)
				(arc
					(start 448.8815 -16.95196)
					(mid 448.39636 -17.4371)
					(end 448.8815 -17.92224)
				)
			)
		)
		(polygon
			(pts
				(arc
					(start 418.601652 -17.92224)
					(mid 419.086792 -17.4371)
					(end 418.601652 -16.95196)
				)
				(arc
					(start 417.331398 -16.95196)
					(mid 416.846512 -17.437227)
					(end 417.331652 -17.92224)
				)
			)
		)
		(polygon
			(pts
				(arc
					(start 387.051804 -17.92224)
					(mid 387.53669 -17.436973)
					(end 387.05155 -16.95196)
				)
				(arc
					(start 385.78155 -16.95196)
					(mid 385.29641 -17.4371)
					(end 385.78155 -17.92224)
				)
			)
		)
		(polygon
			(pts
				(arc
					(start 355.501702 -17.92224)
					(mid 355.986842 -17.4371)
					(end 355.501702 -16.95196)
				)
				(arc
					(start 354.231448 -16.95196)
					(mid 353.746562 -17.437227)
					(end 354.231702 -17.92224)
				)
			)
		)
		(polygon
			(pts
				(arc
					(start 323.951854 -17.92224)
					(mid 324.43674 -17.436973)
					(end 323.9516 -16.95196)
				)
				(arc
					(start 322.6816 -16.95196)
					(mid 322.19646 -17.4371)
					(end 322.6816 -17.92224)
				)
			)
		)
		(polygon
			(pts
				(arc
					(start 479.841814 -15.117826)
					(mid 479.826935 -15.081905)
					(end 479.791014 -15.067026)
				)
				(arc
					(start 478.978214 -15.067026)
					(mid 478.942293 -15.081905)
					(end 478.927414 -15.117826)
				)
				(arc
					(start 478.927414 -15.321026)
					(mid 478.942293 -15.356947)
					(end 478.978214 -15.371826)
				)
				(arc
					(start 479.791014 -15.371826)
					(mid 479.826935 -15.356947)
					(end 479.841814 -15.321026)
				)
			)
		)
		(polygon
			(pts
				(arc
					(start 448.291712 -15.117826)
					(mid 448.276833 -15.081905)
					(end 448.240912 -15.067026)
				)
				(arc
					(start 447.428112 -15.067026)
					(mid 447.392191 -15.081905)
					(end 447.377312 -15.117826)
				)
				(arc
					(start 447.377312 -15.321026)
					(mid 447.392191 -15.356947)
					(end 447.428112 -15.371826)
				)
				(arc
					(start 448.240912 -15.371826)
					(mid 448.276833 -15.356947)
					(end 448.291712 -15.321026)
				)
			)
		)
		(polygon
			(pts
				(arc
					(start 416.741864 -15.117826)
					(mid 416.726985 -15.081905)
					(end 416.691064 -15.067026)
				)
				(arc
					(start 415.878264 -15.067026)
					(mid 415.842343 -15.081905)
					(end 415.827464 -15.117826)
				)
				(arc
					(start 415.827464 -15.321026)
					(mid 415.842343 -15.356947)
					(end 415.878264 -15.371826)
				)
				(arc
					(start 416.691064 -15.371826)
					(mid 416.726985 -15.356947)
					(end 416.741864 -15.321026)
				)
			)
		)
		(polygon
			(pts
				(arc
					(start 385.191762 -15.117826)
					(mid 385.176883 -15.081905)
					(end 385.140962 -15.067026)
				)
				(arc
					(start 384.328162 -15.067026)
					(mid 384.292241 -15.081905)
					(end 384.277362 -15.117826)
				)
				(arc
					(start 384.277362 -15.321026)
					(mid 384.292241 -15.356947)
					(end 384.328162 -15.371826)
				)
				(arc
					(start 385.140962 -15.371826)
					(mid 385.176883 -15.356947)
					(end 385.191762 -15.321026)
				)
			)
		)
		(polygon
			(pts
				(arc
					(start 353.641914 -15.117826)
					(mid 353.627035 -15.081905)
					(end 353.591114 -15.067026)
				)
				(arc
					(start 352.778314 -15.067026)
					(mid 352.742393 -15.081905)
					(end 352.727514 -15.117826)
				)
				(arc
					(start 352.727514 -15.321026)
					(mid 352.742393 -15.356947)
					(end 352.778314 -15.371826)
				)
				(arc
					(start 353.591114 -15.371826)
					(mid 353.627035 -15.356947)
					(end 353.641914 -15.321026)
				)
			)
		)
		(polygon
			(pts
				(arc
					(start 322.091812 -15.117826)
					(mid 322.076933 -15.081905)
					(end 322.041012 -15.067026)
				)
				(arc
					(start 321.228212 -15.067026)
					(mid 321.192291 -15.081905)
					(end 321.177412 -15.117826)
				)
				(arc
					(start 321.177412 -15.321026)
					(mid 321.192291 -15.356947)
					(end 321.228212 -15.371826)
				)
				(arc
					(start 322.041012 -15.371826)
					(mid 322.076933 -15.356947)
					(end 322.091812 -15.321026)
				)
			)
		)
		(polygon
			(pts
				(arc
					(start 190.670688 -15.117826)
					(mid 190.655809 -15.081905)
					(end 190.619888 -15.067026)
				)
				(arc
					(start 189.807088 -15.067026)
					(mid 189.771167 -15.081905)
					(end 189.756288 -15.117826)
				)
				(arc
					(start 189.756288 -15.321026)
					(mid 189.771167 -15.356947)
					(end 189.807088 -15.371826)
				)
				(arc
					(start 190.619888 -15.371826)
					(mid 190.655809 -15.356947)
					(end 190.670688 -15.321026)
				)
			)
		)
		(polygon
			(pts
				(arc
					(start 159.120586 -15.117826)
					(mid 159.105707 -15.081905)
					(end 159.069786 -15.067026)
				)
				(arc
					(start 158.256986 -15.067026)
					(mid 158.221065 -15.081905)
					(end 158.206186 -15.117826)
				)
				(arc
					(start 158.206186 -15.321026)
					(mid 158.221065 -15.356947)
					(end 158.256986 -15.371826)
				)
				(arc
					(start 159.069786 -15.371826)
					(mid 159.105707 -15.356947)
					(end 159.120586 -15.321026)
				)
			)
		)
		(polygon
			(pts
				(arc
					(start 127.570484 -15.117826)
					(mid 127.555605 -15.081905)
					(end 127.519684 -15.067026)
				)
				(arc
					(start 126.706884 -15.067026)
					(mid 126.670963 -15.081905)
					(end 126.656084 -15.117826)
				)
				(arc
					(start 126.656084 -15.321026)
					(mid 126.670963 -15.356947)
					(end 126.706884 -15.371826)
				)
				(arc
					(start 127.519684 -15.371826)
					(mid 127.555605 -15.356947)
					(end 127.570484 -15.321026)
				)
			)
		)
		(polygon
			(pts
				(arc
					(start 96.020636 -15.117826)
					(mid 96.005757 -15.081905)
					(end 95.969836 -15.067026)
				)
				(arc
					(start 95.157036 -15.067026)
					(mid 95.121115 -15.081905)
					(end 95.106236 -15.117826)
				)
				(arc
					(start 95.106236 -15.321026)
					(mid 95.121115 -15.356947)
					(end 95.157036 -15.371826)
				)
				(arc
					(start 95.969836 -15.371826)
					(mid 96.005757 -15.356947)
					(end 96.020636 -15.321026)
				)
			)
		)
		(polygon
			(pts
				(arc
					(start 64.470534 -15.117826)
					(mid 64.455655 -15.081905)
					(end 64.419734 -15.067026)
				)
				(arc
					(start 63.606934 -15.067026)
					(mid 63.571013 -15.081905)
					(end 63.556134 -15.117826)
				)
				(arc
					(start 63.556134 -15.321026)
					(mid 63.571013 -15.356947)
					(end 63.606934 -15.371826)
				)
				(arc
					(start 64.419734 -15.371826)
					(mid 64.455655 -15.356947)
					(end 64.470534 -15.321026)
				)
			)
		)
		(polygon
			(pts
				(arc
					(start 32.920686 -15.117826)
					(mid 32.905807 -15.081905)
					(end 32.869886 -15.067026)
				)
				(arc
					(start 32.057086 -15.067026)
					(mid 32.021165 -15.081905)
					(end 32.006286 -15.117826)
				)
				(arc
					(start 32.006286 -15.321026)
					(mid 32.021165 -15.356947)
					(end 32.057086 -15.371826)
				)
				(arc
					(start 32.869886 -15.371826)
					(mid 32.905807 -15.356947)
					(end 32.920686 -15.321026)
				)
			)
		)
		(polygon
			(pts
				(arc
					(start 479.841814 -14.559026)
					(mid 479.826935 -14.523105)
					(end 479.791014 -14.508226)
				)
				(arc
					(start 478.978214 -14.508226)
					(mid 478.942293 -14.523105)
					(end 478.927414 -14.559026)
				)
				(arc
					(start 478.927414 -14.762226)
					(mid 478.942293 -14.798147)
					(end 478.978214 -14.813026)
				)
				(arc
					(start 479.791014 -14.813026)
					(mid 479.826935 -14.798147)
					(end 479.841814 -14.762226)
				)
			)
		)
		(polygon
			(pts
				(arc
					(start 448.291712 -14.559026)
					(mid 448.276833 -14.523105)
					(end 448.240912 -14.508226)
				)
				(arc
					(start 447.428112 -14.508226)
					(mid 447.392191 -14.523105)
					(end 447.377312 -14.559026)
				)
				(arc
					(start 447.377312 -14.762226)
					(mid 447.392191 -14.798147)
					(end 447.428112 -14.813026)
				)
				(arc
					(start 448.240912 -14.813026)
					(mid 448.276833 -14.798147)
					(end 448.291712 -14.762226)
				)
			)
		)
		(polygon
			(pts
				(arc
					(start 416.741864 -14.559026)
					(mid 416.726985 -14.523105)
					(end 416.691064 -14.508226)
				)
				(arc
					(start 415.878264 -14.508226)
					(mid 415.842343 -14.523105)
					(end 415.827464 -14.559026)
				)
				(arc
					(start 415.827464 -14.762226)
					(mid 415.842343 -14.798147)
					(end 415.878264 -14.813026)
				)
				(arc
					(start 416.691064 -14.813026)
					(mid 416.726985 -14.798147)
					(end 416.741864 -14.762226)
				)
			)
		)
		(polygon
			(pts
				(arc
					(start 385.191762 -14.559026)
					(mid 385.176883 -14.523105)
					(end 385.140962 -14.508226)
				)
				(arc
					(start 384.328162 -14.508226)
					(mid 384.292241 -14.523105)
					(end 384.277362 -14.559026)
				)
				(arc
					(start 384.277362 -14.762226)
					(mid 384.292241 -14.798147)
					(end 384.328162 -14.813026)
				)
				(arc
					(start 385.140962 -14.813026)
					(mid 385.176883 -14.798147)
					(end 385.191762 -14.762226)
				)
			)
		)
		(polygon
			(pts
				(arc
					(start 353.641914 -14.559026)
					(mid 353.627035 -14.523105)
					(end 353.591114 -14.508226)
				)
				(arc
					(start 352.778314 -14.508226)
					(mid 352.742393 -14.523105)
					(end 352.727514 -14.559026)
				)
				(arc
					(start 352.727514 -14.762226)
					(mid 352.742393 -14.798147)
					(end 352.778314 -14.813026)
				)
				(arc
					(start 353.591114 -14.813026)
					(mid 353.627035 -14.798147)
					(end 353.641914 -14.762226)
				)
			)
		)
		(polygon
			(pts
				(arc
					(start 322.091812 -14.559026)
					(mid 322.076933 -14.523105)
					(end 322.041012 -14.508226)
				)
				(arc
					(start 321.228212 -14.508226)
					(mid 321.192291 -14.523105)
					(end 321.177412 -14.559026)
				)
				(arc
					(start 321.177412 -14.762226)
					(mid 321.192291 -14.798147)
					(end 321.228212 -14.813026)
				)
				(arc
					(start 322.041012 -14.813026)
					(mid 322.076933 -14.798147)
					(end 322.091812 -14.762226)
				)
			)
		)
		(polygon
			(pts
				(arc
					(start 190.670688 -14.559026)
					(mid 190.655809 -14.523105)
					(end 190.619888 -14.508226)
				)
				(arc
					(start 189.807088 -14.508226)
					(mid 189.771167 -14.523105)
					(end 189.756288 -14.559026)
				)
				(arc
					(start 189.756288 -14.762226)
					(mid 189.771167 -14.798147)
					(end 189.807088 -14.813026)
				)
				(arc
					(start 190.619888 -14.813026)
					(mid 190.655809 -14.798147)
					(end 190.670688 -14.762226)
				)
			)
		)
		(polygon
			(pts
				(arc
					(start 159.120586 -14.559026)
					(mid 159.105707 -14.523105)
					(end 159.069786 -14.508226)
				)
				(arc
					(start 158.256986 -14.508226)
					(mid 158.221065 -14.523105)
					(end 158.206186 -14.559026)
				)
				(arc
					(start 158.206186 -14.762226)
					(mid 158.221065 -14.798147)
					(end 158.256986 -14.813026)
				)
				(arc
					(start 159.069786 -14.813026)
					(mid 159.105707 -14.798147)
					(end 159.120586 -14.762226)
				)
			)
		)
		(polygon
			(pts
				(arc
					(start 127.570484 -14.559026)
					(mid 127.555605 -14.523105)
					(end 127.519684 -14.508226)
				)
				(arc
					(start 126.706884 -14.508226)
					(mid 126.670963 -14.523105)
					(end 126.656084 -14.559026)
				)
				(arc
					(start 126.656084 -14.762226)
					(mid 126.670963 -14.798147)
					(end 126.706884 -14.813026)
				)
				(arc
					(start 127.519684 -14.813026)
					(mid 127.555605 -14.798147)
					(end 127.570484 -14.762226)
				)
			)
		)
		(polygon
			(pts
				(arc
					(start 96.020636 -14.559026)
					(mid 96.005757 -14.523105)
					(end 95.969836 -14.508226)
				)
				(arc
					(start 95.157036 -14.508226)
					(mid 95.121115 -14.523105)
					(end 95.106236 -14.559026)
				)
				(arc
					(start 95.106236 -14.762226)
					(mid 95.121115 -14.798147)
					(end 95.157036 -14.813026)
				)
				(arc
					(start 95.969836 -14.813026)
					(mid 96.005757 -14.798147)
					(end 96.020636 -14.762226)
				)
			)
		)
		(polygon
			(pts
				(arc
					(start 64.470534 -14.559026)
					(mid 64.455655 -14.523105)
					(end 64.419734 -14.508226)
				)
				(arc
					(start 63.606934 -14.508226)
					(mid 63.571013 -14.523105)
					(end 63.556134 -14.559026)
				)
				(arc
					(start 63.556134 -14.762226)
					(mid 63.571013 -14.798147)
					(end 63.606934 -14.813026)
				)
				(arc
					(start 64.419734 -14.813026)
					(mid 64.455655 -14.798147)
					(end 64.470534 -14.762226)
				)
			)
		)
		(polygon
			(pts
				(arc
					(start 32.920686 -14.559026)
					(mid 32.905807 -14.523105)
					(end 32.869886 -14.508226)
				)
				(arc
					(start 32.057086 -14.508226)
					(mid 32.021165 -14.523105)
					(end 32.006286 -14.559026)
				)
				(arc
					(start 32.006286 -14.762226)
					(mid 32.021165 -14.798147)
					(end 32.057086 -14.813026)
				)
				(arc
					(start 32.869886 -14.813026)
					(mid 32.905807 -14.798147)
					(end 32.920686 -14.762226)
				)
			)
		)
		(polygon
			(pts
				(arc
					(start 192.520824 -14.419072)
					(mid 192.035557 -13.934186)
					(end 191.550544 -14.419326)
				)
				(arc
					(start 191.550544 -15.562326)
					(mid 192.035684 -16.047466)
					(end 192.520824 -15.562326)
				)
			)
		)
		(polygon
			(pts
				(arc
					(start 160.970722 -14.419072)
					(mid 160.485455 -13.934186)
					(end 160.000442 -14.419326)
				)
				(arc
					(start 160.000442 -15.562326)
					(mid 160.485582 -16.047466)
					(end 160.970722 -15.562326)
				)
			)
		)
		(polygon
			(pts
				(arc
					(start 129.42062 -14.419072)
					(mid 128.935353 -13.934186)
					(end 128.45034 -14.419326)
				)
				(arc
					(start 128.45034 -15.562326)
					(mid 128.93548 -16.047466)
					(end 129.42062 -15.562326)
				)
			)
		)
		(polygon
			(pts
				(arc
					(start 97.870772 -14.419072)
					(mid 97.385505 -13.934186)
					(end 96.900492 -14.419326)
				)
				(arc
					(start 96.900492 -15.562326)
					(mid 97.385632 -16.047466)
					(end 97.870772 -15.562326)
				)
			)
		)
		(polygon
			(pts
				(arc
					(start 66.32067 -14.419072)
					(mid 65.835403 -13.934186)
					(end 65.35039 -14.419326)
				)
				(arc
					(start 65.35039 -15.562326)
					(mid 65.83553 -16.047466)
					(end 66.32067 -15.562326)
				)
			)
		)
		(polygon
			(pts
				(arc
					(start 34.770822 -14.419072)
					(mid 34.285555 -13.934186)
					(end 33.800542 -14.419326)
				)
				(arc
					(start 33.800542 -15.562326)
					(mid 34.285682 -16.047466)
					(end 34.770822 -15.562326)
				)
			)
		)
		(polygon
			(pts
				(xy 486.306114 -13.339826) (xy 483.943914 -13.339826) (xy 483.943914 -16.540226) (xy 486.306114 -16.540226)
			)
		)
		(polygon
			(pts
				(xy 454.756012 -13.339826) (xy 452.393812 -13.339826) (xy 452.393812 -16.540226) (xy 454.756012 -16.540226)
			)
		)
		(polygon
			(pts
				(xy 423.206164 -13.339826) (xy 420.843964 -13.339826) (xy 420.843964 -16.540226) (xy 423.206164 -16.540226)
			)
		)
		(polygon
			(pts
				(xy 391.656062 -13.339826) (xy 389.293862 -13.339826) (xy 389.293862 -16.540226) (xy 391.656062 -16.540226)
			)
		)
		(polygon
			(pts
				(xy 360.106214 -13.339826) (xy 357.744014 -13.339826) (xy 357.744014 -16.540226) (xy 360.106214 -16.540226)
			)
		)
		(polygon
			(pts
				(xy 328.556112 -13.339826) (xy 326.193912 -13.339826) (xy 326.193912 -16.540226) (xy 328.556112 -16.540226)
			)
		)
		(polygon
			(pts
				(xy 188.956188 -13.339826) (xy 186.593988 -13.339826) (xy 186.593988 -16.540226) (xy 188.956188 -16.540226)
			)
		)
		(polygon
			(pts
				(xy 157.406086 -13.339826) (xy 155.043886 -13.339826) (xy 155.043886 -16.540226) (xy 157.406086 -16.540226)
			)
		)
		(polygon
			(pts
				(xy 125.855984 -13.339826) (xy 123.493784 -13.339826) (xy 123.493784 -16.540226) (xy 125.855984 -16.540226)
			)
		)
		(polygon
			(pts
				(xy 94.306136 -13.339826) (xy 91.943936 -13.339826) (xy 91.943936 -16.540226) (xy 94.306136 -16.540226)
			)
		)
		(polygon
			(pts
				(xy 62.756034 -13.339826) (xy 60.393834 -13.339826) (xy 60.393834 -16.540226) (xy 62.756034 -16.540226)
			)
		)
		(polygon
			(pts
				(xy 31.206186 -13.339826) (xy 28.843986 -13.339826) (xy 28.843986 -16.540226) (xy 31.206186 -16.540226)
			)
		)
		(polygon
			(pts
				(arc
					(start 478.107502 -14.11224)
					(mid 478.592642 -13.6271)
					(end 478.107502 -13.14196)
				)
				(arc
					(start 476.964248 -13.14196)
					(mid 476.479362 -13.627227)
					(end 476.964502 -14.11224)
				)
			)
		)
		(polygon
			(pts
				(arc
					(start 446.5574 -14.11224)
					(mid 447.04254 -13.6271)
					(end 446.5574 -13.14196)
				)
				(arc
					(start 445.414146 -13.14196)
					(mid 444.92926 -13.627227)
					(end 445.4144 -14.11224)
				)
			)
		)
		(polygon
			(pts
				(arc
					(start 415.007552 -14.11224)
					(mid 415.492692 -13.6271)
					(end 415.007552 -13.14196)
				)
				(arc
					(start 413.864298 -13.14196)
					(mid 413.379412 -13.627227)
					(end 413.864552 -14.11224)
				)
			)
		)
		(polygon
			(pts
				(arc
					(start 383.45745 -14.11224)
					(mid 383.94259 -13.6271)
					(end 383.45745 -13.14196)
				)
				(arc
					(start 382.314196 -13.14196)
					(mid 381.82931 -13.627227)
					(end 382.31445 -14.11224)
				)
			)
		)
		(polygon
			(pts
				(arc
					(start 351.907602 -14.11224)
					(mid 352.392742 -13.6271)
					(end 351.907602 -13.14196)
				)
				(arc
					(start 350.764348 -13.14196)
					(mid 350.279462 -13.627227)
					(end 350.764602 -14.11224)
				)
			)
		)
		(polygon
			(pts
				(arc
					(start 320.3575 -14.11224)
					(mid 320.84264 -13.6271)
					(end 320.3575 -13.14196)
				)
				(arc
					(start 319.214246 -13.14196)
					(mid 318.72936 -13.627227)
					(end 319.2145 -14.11224)
				)
			)
		)
	)
	(zone
		(net "AGND_CURRENT_MON")
		(layer "In1.Cu")
		(hatch none 0.5)
		(connect_pads
			(clearance 0.5)
		)
		(min_thickness 0.25)
		(fill yes
			(thermal_gap 0.5)
			(thermal_bridge_width 0.5)
			(island_removal_mode 0)
		)
		(polygon
			(pts
				(xy 169.369994 -359.9815) (xy 167.77335 -361.578144) (xy 161.785554 -361.578144) (xy 161.452814 -361.910884)
				(xy 161.452814 -374.558052) (xy 165.747192 -378.85243) (xy 172.058076 -378.85243) (xy 175.308006 -375.6025)
				(xy 181.785006 -375.6025) (xy 184.5945 -372.793006) (xy 184.5945 -369.999006) (xy 185.8645 -368.729006)
				(xy 185.8645 -366.832642) (xy 179.013358 -359.9815)
			)
		)
	)
	(zone
		(net "AGND_CURRENT_DPB")
		(layer "In1.Cu")
		(hatch none 0.5)
		(connect_pads
			(clearance 0.5)
		)
		(min_thickness 0.25)
		(fill yes
			(thermal_gap 0.5)
			(thermal_bridge_width 0.5)
			(island_removal_mode 0)
		)
		(polygon
			(pts
				(xy 247.929908 -356.940612) (xy 246.497602 -358.372918) (xy 239.803686 -358.372918) (xy 239.095788 -359.080816)
				(xy 239.095788 -369.339876) (xy 240.221516 -370.465604) (xy 246.493284 -370.465604) (xy 251.780548 -375.752868)
				(xy 258.16433 -375.752868) (xy 260.038596 -373.878602) (xy 260.038596 -371.657626) (xy 260.92531 -370.770912)
				(xy 265.751818 -370.770912) (xy 268.279372 -368.243358) (xy 268.279372 -357.417878) (xy 267.802106 -356.940612)
			)
		)
	)
	(zone
		(layers "In1.Cu" "In2.Cu")
		(hatch none 0.5)
		(connect_pads
			(clearance 0)
		)
		(min_thickness 0.25)
		(keepout
			(tracks not_allowed)
			(vias allowed)
			(pads allowed)
			(copperpour not_allowed)
			(footprints allowed)
		)
		(placement
			(enabled no)
			(sheetname "")
		)
		(fill yes
			(thermal_gap 0.5)
			(thermal_bridge_width 0.5)
			(island_removal_mode 0)
		)
		(polygon
			(pts
				(xy 452.393812 -17.149826) (xy 454.756012 -17.149826) (xy 454.756012 -20.350226) (xy 452.393812 -20.350226)
			)
		)
	)
	(zone
		(layers "In1.Cu" "In2.Cu")
		(hatch none 0.5)
		(connect_pads
			(clearance 0)
		)
		(min_thickness 0.25)
		(keepout
			(tracks not_allowed)
			(vias allowed)
			(pads allowed)
			(copperpour not_allowed)
			(footprints allowed)
		)
		(placement
			(enabled no)
			(sheetname "")
		)
		(fill yes
			(thermal_gap 0.5)
			(thermal_bridge_width 0.5)
			(island_removal_mode 0)
		)
		(polygon
			(pts
				(xy 483.943914 -243.339874) (xy 486.306114 -243.339874) (xy 486.306114 -246.540274) (xy 483.943914 -246.540274)
			)
		)
	)
	(zone
		(layers "In1.Cu" "In2.Cu")
		(hatch none 0.5)
		(connect_pads
			(clearance 0)
		)
		(min_thickness 0.25)
		(keepout
			(tracks not_allowed)
			(vias allowed)
			(pads allowed)
			(copperpour not_allowed)
			(footprints allowed)
		)
		(placement
			(enabled no)
			(sheetname "")
		)
		(fill yes
			(thermal_gap 0.5)
			(thermal_bridge_width 0.5)
			(island_removal_mode 0)
		)
		(polygon
			(pts
				(xy 389.293862 -243.339874) (xy 391.656062 -243.339874) (xy 391.656062 -246.540274) (xy 389.293862 -246.540274)
			)
		)
	)
	(zone
		(layers "In1.Cu" "In2.Cu")
		(hatch none 0.5)
		(connect_pads
			(clearance 0)
		)
		(min_thickness 0.25)
		(keepout
			(tracks not_allowed)
			(vias allowed)
			(pads allowed)
			(copperpour not_allowed)
			(footprints allowed)
		)
		(placement
			(enabled no)
			(sheetname "")
		)
		(fill yes
			(thermal_gap 0.5)
			(thermal_bridge_width 0.5)
			(island_removal_mode 0)
		)
		(polygon
			(pts
				(xy 326.193912 -17.149826) (xy 328.556112 -17.149826) (xy 328.556112 -20.350226) (xy 326.193912 -20.350226)
			)
		)
	)
	(zone
		(layers "In1.Cu" "In2.Cu")
		(hatch none 0.5)
		(connect_pads
			(clearance 0)
		)
		(min_thickness 0.25)
		(keepout
			(tracks not_allowed)
			(vias allowed)
			(pads allowed)
			(copperpour not_allowed)
			(footprints allowed)
		)
		(placement
			(enabled no)
			(sheetname "")
		)
		(fill yes
			(thermal_gap 0.5)
			(thermal_bridge_width 0.5)
			(island_removal_mode 0)
		)
		(polygon
			(pts
				(xy 420.843964 -243.339874) (xy 423.206164 -243.339874) (xy 423.206164 -246.540274) (xy 420.843964 -246.540274)
			)
		)
	)
	(zone
		(layers "In1.Cu" "In2.Cu")
		(hatch none 0.5)
		(connect_pads
			(clearance 0)
		)
		(min_thickness 0.25)
		(keepout
			(tracks not_allowed)
			(vias allowed)
			(pads allowed)
			(copperpour not_allowed)
			(footprints allowed)
		)
		(placement
			(enabled no)
			(sheetname "")
		)
		(fill yes
			(thermal_gap 0.5)
			(thermal_bridge_width 0.5)
			(island_removal_mode 0)
		)
		(polygon
			(pts
				(xy 28.843986 -132.14985) (xy 31.206186 -132.14985) (xy 31.206186 -135.35025) (xy 28.843986 -135.35025)
			)
		)
	)
	(zone
		(layers "In1.Cu" "In2.Cu")
		(hatch none 0.5)
		(connect_pads
			(clearance 0)
		)
		(min_thickness 0.25)
		(keepout
			(tracks not_allowed)
			(vias allowed)
			(pads allowed)
			(copperpour not_allowed)
			(footprints allowed)
		)
		(placement
			(enabled no)
			(sheetname "")
		)
		(fill yes
			(thermal_gap 0.5)
			(thermal_bridge_width 0.5)
			(island_removal_mode 0)
		)
		(polygon
			(pts
				(arc
					(start 478.978214 -129.50825)
					(mid 478.942293 -129.523129)
					(end 478.927414 -129.55905)
				)
				(arc
					(start 478.927414 -129.76225)
					(mid 478.942293 -129.798171)
					(end 478.978214 -129.81305)
				)
				(arc
					(start 479.791014 -129.81305)
					(mid 479.826935 -129.798171)
					(end 479.841814 -129.76225)
				)
				(arc
					(start 479.841814 -129.55905)
					(mid 479.826935 -129.523129)
					(end 479.791014 -129.50825)
				)
			)
		)
	)
	(zone
		(layers "In1.Cu" "In2.Cu")
		(hatch none 0.5)
		(connect_pads
			(clearance 0)
		)
		(min_thickness 0.25)
		(keepout
			(tracks not_allowed)
			(vias allowed)
			(pads allowed)
			(copperpour not_allowed)
			(footprints allowed)
		)
		(placement
			(enabled no)
			(sheetname "")
		)
		(fill yes
			(thermal_gap 0.5)
			(thermal_bridge_width 0.5)
			(island_removal_mode 0)
		)
		(polygon
			(pts
				(xy 389.293862 -247.149874) (xy 391.656062 -247.149874) (xy 391.656062 -250.350274) (xy 389.293862 -250.350274)
			)
		)
	)
	(zone
		(layers "In1.Cu" "In2.Cu")
		(hatch none 0.5)
		(connect_pads
			(clearance 0)
		)
		(min_thickness 0.25)
		(keepout
			(tracks not_allowed)
			(vias allowed)
			(pads allowed)
			(copperpour not_allowed)
			(footprints allowed)
		)
		(placement
			(enabled no)
			(sheetname "")
		)
		(fill yes
			(thermal_gap 0.5)
			(thermal_bridge_width 0.5)
			(island_removal_mode 0)
		)
		(polygon
			(pts
				(xy 91.943936 -243.339874) (xy 94.306136 -243.339874) (xy 94.306136 -246.540274) (xy 91.943936 -246.540274)
			)
		)
	)
	(zone
		(layers "In1.Cu" "In2.Cu")
		(hatch none 0.5)
		(connect_pads
			(clearance 0)
		)
		(min_thickness 0.25)
		(keepout
			(tracks not_allowed)
			(vias allowed)
			(pads allowed)
			(copperpour not_allowed)
			(footprints allowed)
		)
		(placement
			(enabled no)
			(sheetname "")
		)
		(fill yes
			(thermal_gap 0.5)
			(thermal_bridge_width 0.5)
			(island_removal_mode 0)
		)
		(polygon
			(pts
				(arc
					(start 384.328162 -15.067026)
					(mid 384.292241 -15.081905)
					(end 384.277362 -15.117826)
				)
				(arc
					(start 384.277362 -15.321026)
					(mid 384.292241 -15.356947)
					(end 384.328162 -15.371826)
				)
				(arc
					(start 385.140962 -15.371826)
					(mid 385.176883 -15.356947)
					(end 385.191762 -15.321026)
				)
				(arc
					(start 385.191762 -15.117826)
					(mid 385.176883 -15.081905)
					(end 385.140962 -15.067026)
				)
			)
		)
	)
	(zone
		(layers "In1.Cu" "In2.Cu")
		(hatch none 0.5)
		(connect_pads
			(clearance 0)
		)
		(min_thickness 0.25)
		(keepout
			(tracks not_allowed)
			(vias allowed)
			(pads allowed)
			(copperpour not_allowed)
			(footprints allowed)
		)
		(placement
			(enabled no)
			(sheetname "")
		)
		(fill yes
			(thermal_gap 0.5)
			(thermal_bridge_width 0.5)
			(island_removal_mode 0)
		)
		(polygon
			(pts
				(xy 357.744014 -17.149826) (xy 360.106214 -17.149826) (xy 360.106214 -20.350226) (xy 357.744014 -20.350226)
			)
		)
	)
	(zone
		(layers "In1.Cu" "In2.Cu")
		(hatch none 0.5)
		(connect_pads
			(clearance 0)
		)
		(min_thickness 0.25)
		(keepout
			(tracks not_allowed)
			(vias allowed)
			(pads allowed)
			(copperpour not_allowed)
			(footprints allowed)
		)
		(placement
			(enabled no)
			(sheetname "")
		)
		(fill yes
			(thermal_gap 0.5)
			(thermal_bridge_width 0.5)
			(island_removal_mode 0)
		)
		(polygon
			(pts
				(xy 91.943936 -132.14985) (xy 94.306136 -132.14985) (xy 94.306136 -135.35025) (xy 91.943936 -135.35025)
			)
		)
	)
	(zone
		(layers "In1.Cu" "In2.Cu")
		(hatch none 0.5)
		(connect_pads
			(clearance 0)
		)
		(min_thickness 0.25)
		(keepout
			(tracks not_allowed)
			(vias allowed)
			(pads allowed)
			(copperpour not_allowed)
			(footprints allowed)
		)
		(placement
			(enabled no)
			(sheetname "")
		)
		(fill yes
			(thermal_gap 0.5)
			(thermal_bridge_width 0.5)
			(island_removal_mode 0)
		)
		(polygon
			(pts
				(xy 155.043886 -243.339874) (xy 157.406086 -243.339874) (xy 157.406086 -246.540274) (xy 155.043886 -246.540274)
			)
		)
	)
	(zone
		(layers "In1.Cu" "In2.Cu")
		(hatch none 0.5)
		(connect_pads
			(clearance 0)
		)
		(min_thickness 0.25)
		(keepout
			(tracks not_allowed)
			(vias allowed)
			(pads allowed)
			(copperpour not_allowed)
			(footprints allowed)
		)
		(placement
			(enabled no)
			(sheetname "")
		)
		(fill yes
			(thermal_gap 0.5)
			(thermal_bridge_width 0.5)
			(island_removal_mode 0)
		)
		(polygon
			(pts
				(arc
					(start 352.778314 -244.508274)
					(mid 352.742393 -244.523153)
					(end 352.727514 -244.559074)
				)
				(arc
					(start 352.727514 -244.762274)
					(mid 352.742393 -244.798195)
					(end 352.778314 -244.813074)
				)
				(arc
					(start 353.591114 -244.813074)
					(mid 353.627035 -244.798195)
					(end 353.641914 -244.762274)
				)
				(arc
					(start 353.641914 -244.559074)
					(mid 353.627035 -244.523153)
					(end 353.591114 -244.508274)
				)
			)
		)
	)
	(zone
		(layers "In1.Cu" "In2.Cu")
		(hatch none 0.5)
		(connect_pads
			(clearance 0)
		)
		(min_thickness 0.25)
		(keepout
			(tracks not_allowed)
			(vias allowed)
			(pads allowed)
			(copperpour not_allowed)
			(footprints allowed)
		)
		(placement
			(enabled no)
			(sheetname "")
		)
		(fill yes
			(thermal_gap 0.5)
			(thermal_bridge_width 0.5)
			(island_removal_mode 0)
		)
		(polygon
			(pts
				(arc
					(start 321.228212 -15.067026)
					(mid 321.192291 -15.081905)
					(end 321.177412 -15.117826)
				)
				(arc
					(start 321.177412 -15.321026)
					(mid 321.192291 -15.356947)
					(end 321.228212 -15.371826)
				)
				(arc
					(start 322.041012 -15.371826)
					(mid 322.076933 -15.356947)
					(end 322.091812 -15.321026)
				)
				(arc
					(start 322.091812 -15.117826)
					(mid 322.076933 -15.081905)
					(end 322.041012 -15.067026)
				)
			)
		)
	)
	(zone
		(layers "In1.Cu" "In2.Cu")
		(hatch none 0.5)
		(connect_pads
			(clearance 0)
		)
		(min_thickness 0.25)
		(keepout
			(tracks not_allowed)
			(vias allowed)
			(pads allowed)
			(copperpour not_allowed)
			(footprints allowed)
		)
		(placement
			(enabled no)
			(sheetname "")
		)
		(fill yes
			(thermal_gap 0.5)
			(thermal_bridge_width 0.5)
			(island_removal_mode 0)
		)
		(polygon
			(pts
				(arc
					(start 352.778314 -15.067026)
					(mid 352.742393 -15.081905)
					(end 352.727514 -15.117826)
				)
				(arc
					(start 352.727514 -15.321026)
					(mid 352.742393 -15.356947)
					(end 352.778314 -15.371826)
				)
				(arc
					(start 353.591114 -15.371826)
					(mid 353.627035 -15.356947)
					(end 353.641914 -15.321026)
				)
				(arc
					(start 353.641914 -15.117826)
					(mid 353.627035 -15.081905)
					(end 353.591114 -15.067026)
				)
			)
		)
	)
	(zone
		(layers "In1.Cu" "In2.Cu")
		(hatch none 0.5)
		(connect_pads
			(clearance 0)
		)
		(min_thickness 0.25)
		(keepout
			(tracks not_allowed)
			(vias allowed)
			(pads allowed)
			(copperpour not_allowed)
			(footprints allowed)
		)
		(placement
			(enabled no)
			(sheetname "")
		)
		(fill yes
			(thermal_gap 0.5)
			(thermal_bridge_width 0.5)
			(island_removal_mode 0)
		)
		(polygon
			(pts
				(arc
					(start 95.157036 -15.067026)
					(mid 95.121115 -15.081905)
					(end 95.106236 -15.117826)
				)
				(arc
					(start 95.106236 -15.321026)
					(mid 95.121115 -15.356947)
					(end 95.157036 -15.371826)
				)
				(arc
					(start 95.969836 -15.371826)
					(mid 96.005757 -15.356947)
					(end 96.020636 -15.321026)
				)
				(arc
					(start 96.020636 -15.117826)
					(mid 96.005757 -15.081905)
					(end 95.969836 -15.067026)
				)
			)
		)
	)
	(zone
		(layers "In1.Cu" "In2.Cu")
		(hatch none 0.5)
		(connect_pads
			(clearance 0)
		)
		(min_thickness 0.25)
		(keepout
			(tracks not_allowed)
			(vias allowed)
			(pads allowed)
			(copperpour not_allowed)
			(footprints allowed)
		)
		(placement
			(enabled no)
			(sheetname "")
		)
		(fill yes
			(thermal_gap 0.5)
			(thermal_bridge_width 0.5)
			(island_removal_mode 0)
		)
		(polygon
			(pts
				(arc
					(start 447.428112 -14.508226)
					(mid 447.392191 -14.523105)
					(end 447.377312 -14.559026)
				)
				(arc
					(start 447.377312 -14.762226)
					(mid 447.392191 -14.798147)
					(end 447.428112 -14.813026)
				)
				(arc
					(start 448.240912 -14.813026)
					(mid 448.276833 -14.798147)
					(end 448.291712 -14.762226)
				)
				(arc
					(start 448.291712 -14.559026)
					(mid 448.276833 -14.523105)
					(end 448.240912 -14.508226)
				)
			)
		)
	)
	(zone
		(layers "In1.Cu" "In2.Cu")
		(hatch none 0.5)
		(connect_pads
			(clearance 0)
		)
		(min_thickness 0.25)
		(keepout
			(tracks not_allowed)
			(vias allowed)
			(pads allowed)
			(copperpour not_allowed)
			(footprints allowed)
		)
		(placement
			(enabled no)
			(sheetname "")
		)
		(fill yes
			(thermal_gap 0.5)
			(thermal_bridge_width 0.5)
			(island_removal_mode 0)
		)
		(polygon
			(pts
				(arc
					(start 95.157036 -130.06705)
					(mid 95.121115 -130.081929)
					(end 95.106236 -130.11785)
				)
				(arc
					(start 95.106236 -130.32105)
					(mid 95.121115 -130.356971)
					(end 95.157036 -130.37185)
				)
				(arc
					(start 95.969836 -130.37185)
					(mid 96.005757 -130.356971)
					(end 96.020636 -130.32105)
				)
				(arc
					(start 96.020636 -130.11785)
					(mid 96.005757 -130.081929)
					(end 95.969836 -130.06705)
				)
			)
		)
	)
	(zone
		(layers "In1.Cu" "In2.Cu")
		(hatch none 0.5)
		(connect_pads
			(clearance 0)
		)
		(min_thickness 0.25)
		(keepout
			(tracks not_allowed)
			(vias allowed)
			(pads allowed)
			(copperpour not_allowed)
			(footprints allowed)
		)
		(placement
			(enabled no)
			(sheetname "")
		)
		(fill yes
			(thermal_gap 0.5)
			(thermal_bridge_width 0.5)
			(island_removal_mode 0)
		)
		(polygon
			(pts
				(arc
					(start 478.978214 -130.06705)
					(mid 478.942293 -130.081929)
					(end 478.927414 -130.11785)
				)
				(arc
					(start 478.927414 -130.32105)
					(mid 478.942293 -130.356971)
					(end 478.978214 -130.37185)
				)
				(arc
					(start 479.791014 -130.37185)
					(mid 479.826935 -130.356971)
					(end 479.841814 -130.32105)
				)
				(arc
					(start 479.841814 -130.11785)
					(mid 479.826935 -130.081929)
					(end 479.791014 -130.06705)
				)
			)
		)
	)
	(zone
		(layers "In1.Cu" "In2.Cu")
		(hatch none 0.5)
		(connect_pads
			(clearance 0)
		)
		(min_thickness 0.25)
		(keepout
			(tracks not_allowed)
			(vias allowed)
			(pads allowed)
			(copperpour not_allowed)
			(footprints allowed)
		)
		(placement
			(enabled no)
			(sheetname "")
		)
		(fill yes
			(thermal_gap 0.5)
			(thermal_bridge_width 0.5)
			(island_removal_mode 0)
		)
		(polygon
			(pts
				(xy 186.593988 -17.149826) (xy 188.956188 -17.149826) (xy 188.956188 -20.350226) (xy 186.593988 -20.350226)
			)
		)
	)
	(zone
		(layers "In1.Cu" "In2.Cu")
		(hatch none 0.5)
		(connect_pads
			(clearance 0)
		)
		(min_thickness 0.25)
		(keepout
			(tracks not_allowed)
			(vias allowed)
			(pads allowed)
			(copperpour not_allowed)
			(footprints allowed)
		)
		(placement
			(enabled no)
			(sheetname "")
		)
		(fill yes
			(thermal_gap 0.5)
			(thermal_bridge_width 0.5)
			(island_removal_mode 0)
		)
		(polygon
			(pts
				(xy 389.293862 -128.33985) (xy 391.656062 -128.33985) (xy 391.656062 -131.54025) (xy 389.293862 -131.54025)
			)
		)
	)
	(zone
		(layers "In1.Cu" "In2.Cu")
		(hatch none 0.5)
		(connect_pads
			(clearance 0)
		)
		(min_thickness 0.25)
		(keepout
			(tracks not_allowed)
			(vias allowed)
			(pads allowed)
			(copperpour not_allowed)
			(footprints allowed)
		)
		(placement
			(enabled no)
			(sheetname "")
		)
		(fill yes
			(thermal_gap 0.5)
			(thermal_bridge_width 0.5)
			(island_removal_mode 0)
		)
		(polygon
			(pts
				(xy 357.744014 -13.339826) (xy 360.106214 -13.339826) (xy 360.106214 -16.540226) (xy 357.744014 -16.540226)
			)
		)
	)
	(zone
		(layers "In1.Cu" "In2.Cu")
		(hatch none 0.5)
		(connect_pads
			(clearance 0)
		)
		(min_thickness 0.25)
		(keepout
			(tracks not_allowed)
			(vias allowed)
			(pads allowed)
			(copperpour not_allowed)
			(footprints allowed)
		)
		(placement
			(enabled no)
			(sheetname "")
		)
		(fill yes
			(thermal_gap 0.5)
			(thermal_bridge_width 0.5)
			(island_removal_mode 0)
		)
		(polygon
			(pts
				(arc
					(start 126.706884 -15.067026)
					(mid 126.670963 -15.081905)
					(end 126.656084 -15.117826)
				)
				(arc
					(start 126.656084 -15.321026)
					(mid 126.670963 -15.356947)
					(end 126.706884 -15.371826)
				)
				(arc
					(start 127.519684 -15.371826)
					(mid 127.555605 -15.356947)
					(end 127.570484 -15.321026)
				)
				(arc
					(start 127.570484 -15.117826)
					(mid 127.555605 -15.081905)
					(end 127.519684 -15.067026)
				)
			)
		)
	)
	(zone
		(layers "In1.Cu" "In2.Cu")
		(hatch none 0.5)
		(connect_pads
			(clearance 0)
		)
		(min_thickness 0.25)
		(keepout
			(tracks not_allowed)
			(vias allowed)
			(pads allowed)
			(copperpour not_allowed)
			(footprints allowed)
		)
		(placement
			(enabled no)
			(sheetname "")
		)
		(fill yes
			(thermal_gap 0.5)
			(thermal_bridge_width 0.5)
			(island_removal_mode 0)
		)
		(polygon
			(pts
				(arc
					(start 321.228212 -245.067074)
					(mid 321.192291 -245.081953)
					(end 321.177412 -245.117874)
				)
				(arc
					(start 321.177412 -245.321074)
					(mid 321.192291 -245.356995)
					(end 321.228212 -245.371874)
				)
				(arc
					(start 322.041012 -245.371874)
					(mid 322.076933 -245.356995)
					(end 322.091812 -245.321074)
				)
				(arc
					(start 322.091812 -245.117874)
					(mid 322.076933 -245.081953)
					(end 322.041012 -245.067074)
				)
			)
		)
	)
	(zone
		(layers "In1.Cu" "In2.Cu")
		(hatch none 0.5)
		(connect_pads
			(clearance 0)
		)
		(min_thickness 0.25)
		(keepout
			(tracks not_allowed)
			(vias allowed)
			(pads allowed)
			(copperpour not_allowed)
			(footprints allowed)
		)
		(placement
			(enabled no)
			(sheetname "")
		)
		(fill yes
			(thermal_gap 0.5)
			(thermal_bridge_width 0.5)
			(island_removal_mode 0)
		)
		(polygon
			(pts
				(arc
					(start 126.706884 -245.067074)
					(mid 126.670963 -245.081953)
					(end 126.656084 -245.117874)
				)
				(arc
					(start 126.656084 -245.321074)
					(mid 126.670963 -245.356995)
					(end 126.706884 -245.371874)
				)
				(arc
					(start 127.519684 -245.371874)
					(mid 127.555605 -245.356995)
					(end 127.570484 -245.321074)
				)
				(arc
					(start 127.570484 -245.117874)
					(mid 127.555605 -245.081953)
					(end 127.519684 -245.067074)
				)
			)
		)
	)
	(zone
		(layers "In1.Cu" "In2.Cu")
		(hatch none 0.5)
		(connect_pads
			(clearance 0)
		)
		(min_thickness 0.25)
		(keepout
			(tracks not_allowed)
			(vias allowed)
			(pads allowed)
			(copperpour not_allowed)
			(footprints allowed)
		)
		(placement
			(enabled no)
			(sheetname "")
		)
		(fill yes
			(thermal_gap 0.5)
			(thermal_bridge_width 0.5)
			(island_removal_mode 0)
		)
		(polygon
			(pts
				(arc
					(start 384.328162 -14.508226)
					(mid 384.292241 -14.523105)
					(end 384.277362 -14.559026)
				)
				(arc
					(start 384.277362 -14.762226)
					(mid 384.292241 -14.798147)
					(end 384.328162 -14.813026)
				)
				(arc
					(start 385.140962 -14.813026)
					(mid 385.176883 -14.798147)
					(end 385.191762 -14.762226)
				)
				(arc
					(start 385.191762 -14.559026)
					(mid 385.176883 -14.523105)
					(end 385.140962 -14.508226)
				)
			)
		)
	)
	(zone
		(layers "In1.Cu" "In2.Cu")
		(hatch none 0.5)
		(connect_pads
			(clearance 0)
		)
		(min_thickness 0.25)
		(keepout
			(tracks not_allowed)
			(vias allowed)
			(pads allowed)
			(copperpour not_allowed)
			(footprints allowed)
		)
		(placement
			(enabled no)
			(sheetname "")
		)
		(fill yes
			(thermal_gap 0.5)
			(thermal_bridge_width 0.5)
			(island_removal_mode 0)
		)
		(polygon
			(pts
				(arc
					(start 384.328162 -130.06705)
					(mid 384.292241 -130.081929)
					(end 384.277362 -130.11785)
				)
				(arc
					(start 384.277362 -130.32105)
					(mid 384.292241 -130.356971)
					(end 384.328162 -130.37185)
				)
				(arc
					(start 385.140962 -130.37185)
					(mid 385.176883 -130.356971)
					(end 385.191762 -130.32105)
				)
				(arc
					(start 385.191762 -130.11785)
					(mid 385.176883 -130.081929)
					(end 385.140962 -130.06705)
				)
			)
		)
	)
	(zone
		(layers "In1.Cu" "In2.Cu")
		(hatch none 0.5)
		(connect_pads
			(clearance 0)
		)
		(min_thickness 0.25)
		(keepout
			(tracks not_allowed)
			(vias allowed)
			(pads allowed)
			(copperpour not_allowed)
			(footprints allowed)
		)
		(placement
			(enabled no)
			(sheetname "")
		)
		(fill yes
			(thermal_gap 0.5)
			(thermal_bridge_width 0.5)
			(island_removal_mode 0)
		)
		(polygon
			(pts
				(xy 452.393812 -128.33985) (xy 454.756012 -128.33985) (xy 454.756012 -131.54025) (xy 452.393812 -131.54025)
			)
		)
	)
	(zone
		(layers "In1.Cu" "In2.Cu")
		(hatch none 0.5)
		(connect_pads
			(clearance 0)
		)
		(min_thickness 0.25)
		(keepout
			(tracks not_allowed)
			(vias allowed)
			(pads allowed)
			(copperpour not_allowed)
			(footprints allowed)
		)
		(placement
			(enabled no)
			(sheetname "")
		)
		(fill yes
			(thermal_gap 0.5)
			(thermal_bridge_width 0.5)
			(island_removal_mode 0)
		)
		(polygon
			(pts
				(arc
					(start 126.706884 -129.50825)
					(mid 126.670963 -129.523129)
					(end 126.656084 -129.55905)
				)
				(arc
					(start 126.656084 -129.76225)
					(mid 126.670963 -129.798171)
					(end 126.706884 -129.81305)
				)
				(arc
					(start 127.519684 -129.81305)
					(mid 127.555605 -129.798171)
					(end 127.570484 -129.76225)
				)
				(arc
					(start 127.570484 -129.55905)
					(mid 127.555605 -129.523129)
					(end 127.519684 -129.50825)
				)
			)
		)
	)
	(zone
		(layers "In1.Cu" "In2.Cu")
		(hatch none 0.5)
		(connect_pads
			(clearance 0)
		)
		(min_thickness 0.25)
		(keepout
			(tracks not_allowed)
			(vias allowed)
			(pads allowed)
			(copperpour not_allowed)
			(footprints allowed)
		)
		(placement
			(enabled no)
			(sheetname "")
		)
		(fill yes
			(thermal_gap 0.5)
			(thermal_bridge_width 0.5)
			(island_removal_mode 0)
		)
		(polygon
			(pts
				(arc
					(start 32.057086 -130.06705)
					(mid 32.021165 -130.081929)
					(end 32.006286 -130.11785)
				)
				(arc
					(start 32.006286 -130.32105)
					(mid 32.021165 -130.356971)
					(end 32.057086 -130.37185)
				)
				(arc
					(start 32.869886 -130.37185)
					(mid 32.905807 -130.356971)
					(end 32.920686 -130.32105)
				)
				(arc
					(start 32.920686 -130.11785)
					(mid 32.905807 -130.081929)
					(end 32.869886 -130.06705)
				)
			)
		)
	)
	(zone
		(layers "In1.Cu" "In2.Cu")
		(hatch none 0.5)
		(connect_pads
			(clearance 0)
		)
		(min_thickness 0.25)
		(keepout
			(tracks not_allowed)
			(vias allowed)
			(pads allowed)
			(copperpour not_allowed)
			(footprints allowed)
		)
		(placement
			(enabled no)
			(sheetname "")
		)
		(fill yes
			(thermal_gap 0.5)
			(thermal_bridge_width 0.5)
			(island_removal_mode 0)
		)
		(polygon
			(pts
				(xy 483.943914 -13.339826) (xy 486.306114 -13.339826) (xy 486.306114 -16.540226) (xy 483.943914 -16.540226)
			)
		)
	)
	(zone
		(layers "In1.Cu" "In2.Cu")
		(hatch none 0.5)
		(connect_pads
			(clearance 0)
		)
		(min_thickness 0.25)
		(keepout
			(tracks not_allowed)
			(vias allowed)
			(pads allowed)
			(copperpour not_allowed)
			(footprints allowed)
		)
		(placement
			(enabled no)
			(sheetname "")
		)
		(fill yes
			(thermal_gap 0.5)
			(thermal_bridge_width 0.5)
			(island_removal_mode 0)
		)
		(polygon
			(pts
				(xy 326.193912 -128.33985) (xy 328.556112 -128.33985) (xy 328.556112 -131.54025) (xy 326.193912 -131.54025)
			)
		)
	)
	(zone
		(layers "In1.Cu" "In2.Cu")
		(hatch none 0.5)
		(connect_pads
			(clearance 0)
		)
		(min_thickness 0.25)
		(keepout
			(tracks not_allowed)
			(vias allowed)
			(pads allowed)
			(copperpour not_allowed)
			(footprints allowed)
		)
		(placement
			(enabled no)
			(sheetname "")
		)
		(fill yes
			(thermal_gap 0.5)
			(thermal_bridge_width 0.5)
			(island_removal_mode 0)
		)
		(polygon
			(pts
				(arc
					(start 415.878264 -245.067074)
					(mid 415.842343 -245.081953)
					(end 415.827464 -245.117874)
				)
				(arc
					(start 415.827464 -245.321074)
					(mid 415.842343 -245.356995)
					(end 415.878264 -245.371874)
				)
				(arc
					(start 416.691064 -245.371874)
					(mid 416.726985 -245.356995)
					(end 416.741864 -245.321074)
				)
				(arc
					(start 416.741864 -245.117874)
					(mid 416.726985 -245.081953)
					(end 416.691064 -245.067074)
				)
			)
		)
	)
	(zone
		(layers "In1.Cu" "In2.Cu")
		(hatch none 0.5)
		(connect_pads
			(clearance 0)
		)
		(min_thickness 0.25)
		(keepout
			(tracks not_allowed)
			(vias allowed)
			(pads allowed)
			(copperpour not_allowed)
			(footprints allowed)
		)
		(placement
			(enabled no)
			(sheetname "")
		)
		(fill yes
			(thermal_gap 0.5)
			(thermal_bridge_width 0.5)
			(island_removal_mode 0)
		)
		(polygon
			(pts
				(xy 420.843964 -128.33985) (xy 423.206164 -128.33985) (xy 423.206164 -131.54025) (xy 420.843964 -131.54025)
			)
		)
	)
	(zone
		(layers "In1.Cu" "In2.Cu")
		(hatch none 0.5)
		(connect_pads
			(clearance 0)
		)
		(min_thickness 0.25)
		(keepout
			(tracks not_allowed)
			(vias allowed)
			(pads allowed)
			(copperpour not_allowed)
			(footprints allowed)
		)
		(placement
			(enabled no)
			(sheetname "")
		)
		(fill yes
			(thermal_gap 0.5)
			(thermal_bridge_width 0.5)
			(island_removal_mode 0)
		)
		(polygon
			(pts
				(xy 91.943936 -247.149874) (xy 94.306136 -247.149874) (xy 94.306136 -250.350274) (xy 91.943936 -250.350274)
			)
		)
	)
	(zone
		(layers "In1.Cu" "In2.Cu")
		(hatch none 0.5)
		(connect_pads
			(clearance 0)
		)
		(min_thickness 0.25)
		(keepout
			(tracks not_allowed)
			(vias allowed)
			(pads allowed)
			(copperpour not_allowed)
			(footprints allowed)
		)
		(placement
			(enabled no)
			(sheetname "")
		)
		(fill yes
			(thermal_gap 0.5)
			(thermal_bridge_width 0.5)
			(island_removal_mode 0)
		)
		(polygon
			(pts
				(arc
					(start 415.878264 -130.06705)
					(mid 415.842343 -130.081929)
					(end 415.827464 -130.11785)
				)
				(arc
					(start 415.827464 -130.32105)
					(mid 415.842343 -130.356971)
					(end 415.878264 -130.37185)
				)
				(arc
					(start 416.691064 -130.37185)
					(mid 416.726985 -130.356971)
					(end 416.741864 -130.32105)
				)
				(arc
					(start 416.741864 -130.11785)
					(mid 416.726985 -130.081929)
					(end 416.691064 -130.06705)
				)
			)
		)
	)
	(zone
		(layers "In1.Cu" "In2.Cu")
		(hatch none 0.5)
		(connect_pads
			(clearance 0)
		)
		(min_thickness 0.25)
		(keepout
			(tracks not_allowed)
			(vias allowed)
			(pads allowed)
			(copperpour not_allowed)
			(footprints allowed)
		)
		(placement
			(enabled no)
			(sheetname "")
		)
		(fill yes
			(thermal_gap 0.5)
			(thermal_bridge_width 0.5)
			(island_removal_mode 0)
		)
		(polygon
			(pts
				(arc
					(start 158.256986 -130.06705)
					(mid 158.221065 -130.081929)
					(end 158.206186 -130.11785)
				)
				(arc
					(start 158.206186 -130.32105)
					(mid 158.221065 -130.356971)
					(end 158.256986 -130.37185)
				)
				(arc
					(start 159.069786 -130.37185)
					(mid 159.105707 -130.356971)
					(end 159.120586 -130.32105)
				)
				(arc
					(start 159.120586 -130.11785)
					(mid 159.105707 -130.081929)
					(end 159.069786 -130.06705)
				)
			)
		)
	)
	(zone
		(layers "In1.Cu" "In2.Cu")
		(hatch none 0.5)
		(connect_pads
			(clearance 0)
		)
		(min_thickness 0.25)
		(keepout
			(tracks not_allowed)
			(vias allowed)
			(pads allowed)
			(copperpour not_allowed)
			(footprints allowed)
		)
		(placement
			(enabled no)
			(sheetname "")
		)
		(fill yes
			(thermal_gap 0.5)
			(thermal_bridge_width 0.5)
			(island_removal_mode 0)
		)
		(polygon
			(pts
				(xy 155.043886 -247.149874) (xy 157.406086 -247.149874) (xy 157.406086 -250.350274) (xy 155.043886 -250.350274)
			)
		)
	)
	(zone
		(layers "In1.Cu" "In2.Cu")
		(hatch none 0.5)
		(connect_pads
			(clearance 0)
		)
		(min_thickness 0.25)
		(keepout
			(tracks not_allowed)
			(vias allowed)
			(pads allowed)
			(copperpour not_allowed)
			(footprints allowed)
		)
		(placement
			(enabled no)
			(sheetname "")
		)
		(fill yes
			(thermal_gap 0.5)
			(thermal_bridge_width 0.5)
			(island_removal_mode 0)
		)
		(polygon
			(pts
				(xy 483.943914 -17.149826) (xy 486.306114 -17.149826) (xy 486.306114 -20.350226) (xy 483.943914 -20.350226)
			)
		)
	)
	(zone
		(layers "In1.Cu" "In2.Cu")
		(hatch none 0.5)
		(connect_pads
			(clearance 0)
		)
		(min_thickness 0.25)
		(keepout
			(tracks not_allowed)
			(vias allowed)
			(pads allowed)
			(copperpour not_allowed)
			(footprints allowed)
		)
		(placement
			(enabled no)
			(sheetname "")
		)
		(fill yes
			(thermal_gap 0.5)
			(thermal_bridge_width 0.5)
			(island_removal_mode 0)
		)
		(polygon
			(pts
				(arc
					(start 32.057086 -245.067074)
					(mid 32.021165 -245.081953)
					(end 32.006286 -245.117874)
				)
				(arc
					(start 32.006286 -245.321074)
					(mid 32.021165 -245.356995)
					(end 32.057086 -245.371874)
				)
				(arc
					(start 32.869886 -245.371874)
					(mid 32.905807 -245.356995)
					(end 32.920686 -245.321074)
				)
				(arc
					(start 32.920686 -245.117874)
					(mid 32.905807 -245.081953)
					(end 32.869886 -245.067074)
				)
			)
		)
	)
	(zone
		(layers "In1.Cu" "In2.Cu")
		(hatch none 0.5)
		(connect_pads
			(clearance 0)
		)
		(min_thickness 0.25)
		(keepout
			(tracks not_allowed)
			(vias allowed)
			(pads allowed)
			(copperpour not_allowed)
			(footprints allowed)
		)
		(placement
			(enabled no)
			(sheetname "")
		)
		(fill yes
			(thermal_gap 0.5)
			(thermal_bridge_width 0.5)
			(island_removal_mode 0)
		)
		(polygon
			(pts
				(arc
					(start 95.157036 -245.067074)
					(mid 95.121115 -245.081953)
					(end 95.106236 -245.117874)
				)
				(arc
					(start 95.106236 -245.321074)
					(mid 95.121115 -245.356995)
					(end 95.157036 -245.371874)
				)
				(arc
					(start 95.969836 -245.371874)
					(mid 96.005757 -245.356995)
					(end 96.020636 -245.321074)
				)
				(arc
					(start 96.020636 -245.117874)
					(mid 96.005757 -245.081953)
					(end 95.969836 -245.067074)
				)
			)
		)
	)
	(zone
		(layers "In1.Cu" "In2.Cu")
		(hatch none 0.5)
		(connect_pads
			(clearance 0)
		)
		(min_thickness 0.25)
		(keepout
			(tracks not_allowed)
			(vias allowed)
			(pads allowed)
			(copperpour not_allowed)
			(footprints allowed)
		)
		(placement
			(enabled no)
			(sheetname "")
		)
		(fill yes
			(thermal_gap 0.5)
			(thermal_bridge_width 0.5)
			(island_removal_mode 0)
		)
		(polygon
			(pts
				(xy 389.293862 -17.149826) (xy 391.656062 -17.149826) (xy 391.656062 -20.350226) (xy 389.293862 -20.350226)
			)
		)
	)
	(zone
		(layers "In1.Cu" "In2.Cu")
		(hatch none 0.5)
		(connect_pads
			(clearance 0)
		)
		(min_thickness 0.25)
		(keepout
			(tracks not_allowed)
			(vias allowed)
			(pads allowed)
			(copperpour not_allowed)
			(footprints allowed)
		)
		(placement
			(enabled no)
			(sheetname "")
		)
		(fill yes
			(thermal_gap 0.5)
			(thermal_bridge_width 0.5)
			(island_removal_mode 0)
		)
		(polygon
			(pts
				(xy 452.393812 -132.14985) (xy 454.756012 -132.14985) (xy 454.756012 -135.35025) (xy 452.393812 -135.35025)
			)
		)
	)
	(zone
		(layers "In1.Cu" "In2.Cu")
		(hatch none 0.5)
		(connect_pads
			(clearance 0)
		)
		(min_thickness 0.25)
		(keepout
			(tracks not_allowed)
			(vias allowed)
			(pads allowed)
			(copperpour not_allowed)
			(footprints allowed)
		)
		(placement
			(enabled no)
			(sheetname "")
		)
		(fill yes
			(thermal_gap 0.5)
			(thermal_bridge_width 0.5)
			(island_removal_mode 0)
		)
		(polygon
			(pts
				(xy 452.393812 -243.339874) (xy 454.756012 -243.339874) (xy 454.756012 -246.540274) (xy 452.393812 -246.540274)
			)
		)
	)
	(zone
		(layers "In1.Cu" "In2.Cu")
		(hatch none 0.5)
		(connect_pads
			(clearance 0)
		)
		(min_thickness 0.25)
		(keepout
			(tracks not_allowed)
			(vias allowed)
			(pads allowed)
			(copperpour not_allowed)
			(footprints allowed)
		)
		(placement
			(enabled no)
			(sheetname "")
		)
		(fill yes
			(thermal_gap 0.5)
			(thermal_bridge_width 0.5)
			(island_removal_mode 0)
		)
		(polygon
			(pts
				(xy 186.593988 -243.339874) (xy 188.956188 -243.339874) (xy 188.956188 -246.540274) (xy 186.593988 -246.540274)
			)
		)
	)
	(zone
		(layers "In1.Cu" "In2.Cu")
		(hatch none 0.5)
		(connect_pads
			(clearance 0)
		)
		(min_thickness 0.25)
		(keepout
			(tracks not_allowed)
			(vias allowed)
			(pads allowed)
			(copperpour not_allowed)
			(footprints allowed)
		)
		(placement
			(enabled no)
			(sheetname "")
		)
		(fill yes
			(thermal_gap 0.5)
			(thermal_bridge_width 0.5)
			(island_removal_mode 0)
		)
		(polygon
			(pts
				(arc
					(start 95.157036 -14.508226)
					(mid 95.121115 -14.523105)
					(end 95.106236 -14.559026)
				)
				(arc
					(start 95.106236 -14.762226)
					(mid 95.121115 -14.798147)
					(end 95.157036 -14.813026)
				)
				(arc
					(start 95.969836 -14.813026)
					(mid 96.005757 -14.798147)
					(end 96.020636 -14.762226)
				)
				(arc
					(start 96.020636 -14.559026)
					(mid 96.005757 -14.523105)
					(end 95.969836 -14.508226)
				)
			)
		)
	)
	(zone
		(layers "In1.Cu" "In2.Cu")
		(hatch none 0.5)
		(connect_pads
			(clearance 0)
		)
		(min_thickness 0.25)
		(keepout
			(tracks not_allowed)
			(vias allowed)
			(pads allowed)
			(copperpour not_allowed)
			(footprints allowed)
		)
		(placement
			(enabled no)
			(sheetname "")
		)
		(fill yes
			(thermal_gap 0.5)
			(thermal_bridge_width 0.5)
			(island_removal_mode 0)
		)
		(polygon
			(pts
				(xy 155.043886 -128.33985) (xy 157.406086 -128.33985) (xy 157.406086 -131.54025) (xy 155.043886 -131.54025)
			)
		)
	)
	(zone
		(layers "In1.Cu" "In2.Cu")
		(hatch none 0.5)
		(connect_pads
			(clearance 0)
		)
		(min_thickness 0.25)
		(keepout
			(tracks not_allowed)
			(vias allowed)
			(pads allowed)
			(copperpour not_allowed)
			(footprints allowed)
		)
		(placement
			(enabled no)
			(sheetname "")
		)
		(fill yes
			(thermal_gap 0.5)
			(thermal_bridge_width 0.5)
			(island_removal_mode 0)
		)
		(polygon
			(pts
				(xy 60.393834 -132.14985) (xy 62.756034 -132.14985) (xy 62.756034 -135.35025) (xy 60.393834 -135.35025)
			)
		)
	)
	(zone
		(layers "In1.Cu" "In2.Cu")
		(hatch none 0.5)
		(connect_pads
			(clearance 0)
		)
		(min_thickness 0.25)
		(keepout
			(tracks not_allowed)
			(vias allowed)
			(pads allowed)
			(copperpour not_allowed)
			(footprints allowed)
		)
		(placement
			(enabled no)
			(sheetname "")
		)
		(fill yes
			(thermal_gap 0.5)
			(thermal_bridge_width 0.5)
			(island_removal_mode 0)
		)
		(polygon
			(pts
				(arc
					(start 447.428112 -129.50825)
					(mid 447.392191 -129.523129)
					(end 447.377312 -129.55905)
				)
				(arc
					(start 447.377312 -129.76225)
					(mid 447.392191 -129.798171)
					(end 447.428112 -129.81305)
				)
				(arc
					(start 448.240912 -129.81305)
					(mid 448.276833 -129.798171)
					(end 448.291712 -129.76225)
				)
				(arc
					(start 448.291712 -129.55905)
					(mid 448.276833 -129.523129)
					(end 448.240912 -129.50825)
				)
			)
		)
	)
	(zone
		(layers "In1.Cu" "In2.Cu")
		(hatch none 0.5)
		(connect_pads
			(clearance 0)
		)
		(min_thickness 0.25)
		(keepout
			(tracks not_allowed)
			(vias allowed)
			(pads allowed)
			(copperpour not_allowed)
			(footprints allowed)
		)
		(placement
			(enabled no)
			(sheetname "")
		)
		(fill yes
			(thermal_gap 0.5)
			(thermal_bridge_width 0.5)
			(island_removal_mode 0)
		)
		(polygon
			(pts
				(xy 326.193912 -132.14985) (xy 328.556112 -132.14985) (xy 328.556112 -135.35025) (xy 326.193912 -135.35025)
			)
		)
	)
	(zone
		(layers "In1.Cu" "In2.Cu")
		(hatch none 0.5)
		(connect_pads
			(clearance 0)
		)
		(min_thickness 0.25)
		(keepout
			(tracks not_allowed)
			(vias allowed)
			(pads allowed)
			(copperpour not_allowed)
			(footprints allowed)
		)
		(placement
			(enabled no)
			(sheetname "")
		)
		(fill yes
			(thermal_gap 0.5)
			(thermal_bridge_width 0.5)
			(island_removal_mode 0)
		)
		(polygon
			(pts
				(xy 357.744014 -128.33985) (xy 360.106214 -128.33985) (xy 360.106214 -131.54025) (xy 357.744014 -131.54025)
			)
		)
	)
	(zone
		(layers "In1.Cu" "In2.Cu")
		(hatch none 0.5)
		(connect_pads
			(clearance 0)
		)
		(min_thickness 0.25)
		(keepout
			(tracks not_allowed)
			(vias allowed)
			(pads allowed)
			(copperpour not_allowed)
			(footprints allowed)
		)
		(placement
			(enabled no)
			(sheetname "")
		)
		(fill yes
			(thermal_gap 0.5)
			(thermal_bridge_width 0.5)
			(island_removal_mode 0)
		)
		(polygon
			(pts
				(arc
					(start 126.706884 -130.06705)
					(mid 126.670963 -130.081929)
					(end 126.656084 -130.11785)
				)
				(arc
					(start 126.656084 -130.32105)
					(mid 126.670963 -130.356971)
					(end 126.706884 -130.37185)
				)
				(arc
					(start 127.519684 -130.37185)
					(mid 127.555605 -130.356971)
					(end 127.570484 -130.32105)
				)
				(arc
					(start 127.570484 -130.11785)
					(mid 127.555605 -130.081929)
					(end 127.519684 -130.06705)
				)
			)
		)
	)
	(zone
		(layers "In1.Cu" "In2.Cu")
		(hatch none 0.5)
		(connect_pads
			(clearance 0)
		)
		(min_thickness 0.25)
		(keepout
			(tracks not_allowed)
			(vias allowed)
			(pads allowed)
			(copperpour not_allowed)
			(footprints allowed)
		)
		(placement
			(enabled no)
			(sheetname "")
		)
		(fill yes
			(thermal_gap 0.5)
			(thermal_bridge_width 0.5)
			(island_removal_mode 0)
		)
		(polygon
			(pts
				(xy 123.493784 -247.149874) (xy 125.855984 -247.149874) (xy 125.855984 -250.350274) (xy 123.493784 -250.350274)
			)
		)
	)
	(zone
		(layers "In1.Cu" "In2.Cu")
		(hatch none 0.5)
		(connect_pads
			(clearance 0)
		)
		(min_thickness 0.25)
		(keepout
			(tracks not_allowed)
			(vias allowed)
			(pads allowed)
			(copperpour not_allowed)
			(footprints allowed)
		)
		(placement
			(enabled no)
			(sheetname "")
		)
		(fill yes
			(thermal_gap 0.5)
			(thermal_bridge_width 0.5)
			(island_removal_mode 0)
		)
		(polygon
			(pts
				(xy 186.593988 -247.149874) (xy 188.956188 -247.149874) (xy 188.956188 -250.350274) (xy 186.593988 -250.350274)
			)
		)
	)
	(zone
		(layers "In1.Cu" "In2.Cu")
		(hatch none 0.5)
		(connect_pads
			(clearance 0)
		)
		(min_thickness 0.25)
		(keepout
			(tracks not_allowed)
			(vias allowed)
			(pads allowed)
			(copperpour not_allowed)
			(footprints allowed)
		)
		(placement
			(enabled no)
			(sheetname "")
		)
		(fill yes
			(thermal_gap 0.5)
			(thermal_bridge_width 0.5)
			(island_removal_mode 0)
		)
		(polygon
			(pts
				(arc
					(start 95.157036 -129.50825)
					(mid 95.121115 -129.523129)
					(end 95.106236 -129.55905)
				)
				(arc
					(start 95.106236 -129.76225)
					(mid 95.121115 -129.798171)
					(end 95.157036 -129.81305)
				)
				(arc
					(start 95.969836 -129.81305)
					(mid 96.005757 -129.798171)
					(end 96.020636 -129.76225)
				)
				(arc
					(start 96.020636 -129.55905)
					(mid 96.005757 -129.523129)
					(end 95.969836 -129.50825)
				)
			)
		)
	)
	(zone
		(layers "In1.Cu" "In2.Cu")
		(hatch none 0.5)
		(connect_pads
			(clearance 0)
		)
		(min_thickness 0.25)
		(keepout
			(tracks not_allowed)
			(vias allowed)
			(pads allowed)
			(copperpour not_allowed)
			(footprints allowed)
		)
		(placement
			(enabled no)
			(sheetname "")
		)
		(fill yes
			(thermal_gap 0.5)
			(thermal_bridge_width 0.5)
			(island_removal_mode 0)
		)
		(polygon
			(pts
				(xy 186.593988 -132.14985) (xy 188.956188 -132.14985) (xy 188.956188 -135.35025) (xy 186.593988 -135.35025)
			)
		)
	)
	(zone
		(layers "In1.Cu" "In2.Cu")
		(hatch none 0.5)
		(connect_pads
			(clearance 0)
		)
		(min_thickness 0.25)
		(keepout
			(tracks not_allowed)
			(vias allowed)
			(pads allowed)
			(copperpour not_allowed)
			(footprints allowed)
		)
		(placement
			(enabled no)
			(sheetname "")
		)
		(fill yes
			(thermal_gap 0.5)
			(thermal_bridge_width 0.5)
			(island_removal_mode 0)
		)
		(polygon
			(pts
				(arc
					(start 63.606934 -129.50825)
					(mid 63.571013 -129.523129)
					(end 63.556134 -129.55905)
				)
				(arc
					(start 63.556134 -129.76225)
					(mid 63.571013 -129.798171)
					(end 63.606934 -129.81305)
				)
				(arc
					(start 64.419734 -129.81305)
					(mid 64.455655 -129.798171)
					(end 64.470534 -129.76225)
				)
				(arc
					(start 64.470534 -129.55905)
					(mid 64.455655 -129.523129)
					(end 64.419734 -129.50825)
				)
			)
		)
	)
	(zone
		(layers "In1.Cu" "In2.Cu")
		(hatch none 0.5)
		(connect_pads
			(clearance 0)
		)
		(min_thickness 0.25)
		(keepout
			(tracks not_allowed)
			(vias allowed)
			(pads allowed)
			(copperpour not_allowed)
			(footprints allowed)
		)
		(placement
			(enabled no)
			(sheetname "")
		)
		(fill yes
			(thermal_gap 0.5)
			(thermal_bridge_width 0.5)
			(island_removal_mode 0)
		)
		(polygon
			(pts
				(arc
					(start 478.978214 -14.508226)
					(mid 478.942293 -14.523105)
					(end 478.927414 -14.559026)
				)
				(arc
					(start 478.927414 -14.762226)
					(mid 478.942293 -14.798147)
					(end 478.978214 -14.813026)
				)
				(arc
					(start 479.791014 -14.813026)
					(mid 479.826935 -14.798147)
					(end 479.841814 -14.762226)
				)
				(arc
					(start 479.841814 -14.559026)
					(mid 479.826935 -14.523105)
					(end 479.791014 -14.508226)
				)
			)
		)
	)
	(zone
		(layers "In1.Cu" "In2.Cu")
		(hatch none 0.5)
		(connect_pads
			(clearance 0)
		)
		(min_thickness 0.25)
		(keepout
			(tracks not_allowed)
			(vias allowed)
			(pads allowed)
			(copperpour not_allowed)
			(footprints allowed)
		)
		(placement
			(enabled no)
			(sheetname "")
		)
		(fill yes
			(thermal_gap 0.5)
			(thermal_bridge_width 0.5)
			(island_removal_mode 0)
		)
		(polygon
			(pts
				(xy 91.943936 -13.339826) (xy 94.306136 -13.339826) (xy 94.306136 -16.540226) (xy 91.943936 -16.540226)
			)
		)
	)
	(zone
		(layers "In1.Cu" "In2.Cu")
		(hatch none 0.5)
		(connect_pads
			(clearance 0)
		)
		(min_thickness 0.25)
		(keepout
			(tracks not_allowed)
			(vias allowed)
			(pads allowed)
			(copperpour not_allowed)
			(footprints allowed)
		)
		(placement
			(enabled no)
			(sheetname "")
		)
		(fill yes
			(thermal_gap 0.5)
			(thermal_bridge_width 0.5)
			(island_removal_mode 0)
		)
		(polygon
			(pts
				(arc
					(start 478.978214 -245.067074)
					(mid 478.942293 -245.081953)
					(end 478.927414 -245.117874)
				)
				(arc
					(start 478.927414 -245.321074)
					(mid 478.942293 -245.356995)
					(end 478.978214 -245.371874)
				)
				(arc
					(start 479.791014 -245.371874)
					(mid 479.826935 -245.356995)
					(end 479.841814 -245.321074)
				)
				(arc
					(start 479.841814 -245.117874)
					(mid 479.826935 -245.081953)
					(end 479.791014 -245.067074)
				)
			)
		)
	)
	(zone
		(layers "In1.Cu" "In2.Cu")
		(hatch none 0.5)
		(connect_pads
			(clearance 0)
		)
		(min_thickness 0.25)
		(keepout
			(tracks not_allowed)
			(vias allowed)
			(pads allowed)
			(copperpour not_allowed)
			(footprints allowed)
		)
		(placement
			(enabled no)
			(sheetname "")
		)
		(fill yes
			(thermal_gap 0.5)
			(thermal_bridge_width 0.5)
			(island_removal_mode 0)
		)
		(polygon
			(pts
				(arc
					(start 415.878264 -244.508274)
					(mid 415.842343 -244.523153)
					(end 415.827464 -244.559074)
				)
				(arc
					(start 415.827464 -244.762274)
					(mid 415.842343 -244.798195)
					(end 415.878264 -244.813074)
				)
				(arc
					(start 416.691064 -244.813074)
					(mid 416.726985 -244.798195)
					(end 416.741864 -244.762274)
				)
				(arc
					(start 416.741864 -244.559074)
					(mid 416.726985 -244.523153)
					(end 416.691064 -244.508274)
				)
			)
		)
	)
	(zone
		(layers "In1.Cu" "In2.Cu")
		(hatch none 0.5)
		(connect_pads
			(clearance 0)
		)
		(min_thickness 0.25)
		(keepout
			(tracks not_allowed)
			(vias allowed)
			(pads allowed)
			(copperpour not_allowed)
			(footprints allowed)
		)
		(placement
			(enabled no)
			(sheetname "")
		)
		(fill yes
			(thermal_gap 0.5)
			(thermal_bridge_width 0.5)
			(island_removal_mode 0)
		)
		(polygon
			(pts
				(xy 123.493784 -13.339826) (xy 125.855984 -13.339826) (xy 125.855984 -16.540226) (xy 123.493784 -16.540226)
			)
		)
	)
	(zone
		(layers "In1.Cu" "In2.Cu")
		(hatch none 0.5)
		(connect_pads
			(clearance 0)
		)
		(min_thickness 0.25)
		(keepout
			(tracks not_allowed)
			(vias allowed)
			(pads allowed)
			(copperpour not_allowed)
			(footprints allowed)
		)
		(placement
			(enabled no)
			(sheetname "")
		)
		(fill yes
			(thermal_gap 0.5)
			(thermal_bridge_width 0.5)
			(island_removal_mode 0)
		)
		(polygon
			(pts
				(arc
					(start 447.428112 -15.067026)
					(mid 447.392191 -15.081905)
					(end 447.377312 -15.117826)
				)
				(arc
					(start 447.377312 -15.321026)
					(mid 447.392191 -15.356947)
					(end 447.428112 -15.371826)
				)
				(arc
					(start 448.240912 -15.371826)
					(mid 448.276833 -15.356947)
					(end 448.291712 -15.321026)
				)
				(arc
					(start 448.291712 -15.117826)
					(mid 448.276833 -15.081905)
					(end 448.240912 -15.067026)
				)
			)
		)
	)
	(zone
		(layers "In1.Cu" "In2.Cu")
		(hatch none 0.5)
		(connect_pads
			(clearance 0)
		)
		(min_thickness 0.25)
		(keepout
			(tracks not_allowed)
			(vias allowed)
			(pads allowed)
			(copperpour not_allowed)
			(footprints allowed)
		)
		(placement
			(enabled no)
			(sheetname "")
		)
		(fill yes
			(thermal_gap 0.5)
			(thermal_bridge_width 0.5)
			(island_removal_mode 0)
		)
		(polygon
			(pts
				(xy 123.493784 -17.149826) (xy 125.855984 -17.149826) (xy 125.855984 -20.350226) (xy 123.493784 -20.350226)
			)
		)
	)
	(zone
		(layers "In1.Cu" "In2.Cu")
		(hatch none 0.5)
		(connect_pads
			(clearance 0)
		)
		(min_thickness 0.25)
		(keepout
			(tracks not_allowed)
			(vias allowed)
			(pads allowed)
			(copperpour not_allowed)
			(footprints allowed)
		)
		(placement
			(enabled no)
			(sheetname "")
		)
		(fill yes
			(thermal_gap 0.5)
			(thermal_bridge_width 0.5)
			(island_removal_mode 0)
		)
		(polygon
			(pts
				(xy 155.043886 -132.14985) (xy 157.406086 -132.14985) (xy 157.406086 -135.35025) (xy 155.043886 -135.35025)
			)
		)
	)
	(zone
		(layers "In1.Cu" "In2.Cu")
		(hatch none 0.5)
		(connect_pads
			(clearance 0)
		)
		(min_thickness 0.25)
		(keepout
			(tracks not_allowed)
			(vias allowed)
			(pads allowed)
			(copperpour not_allowed)
			(footprints allowed)
		)
		(placement
			(enabled no)
			(sheetname "")
		)
		(fill yes
			(thermal_gap 0.5)
			(thermal_bridge_width 0.5)
			(island_removal_mode 0)
		)
		(polygon
			(pts
				(arc
					(start 189.807088 -244.508274)
					(mid 189.771167 -244.523153)
					(end 189.756288 -244.559074)
				)
				(arc
					(start 189.756288 -244.762274)
					(mid 189.771167 -244.798195)
					(end 189.807088 -244.813074)
				)
				(arc
					(start 190.619888 -244.813074)
					(mid 190.655809 -244.798195)
					(end 190.670688 -244.762274)
				)
				(arc
					(start 190.670688 -244.559074)
					(mid 190.655809 -244.523153)
					(end 190.619888 -244.508274)
				)
			)
		)
	)
	(zone
		(layers "In1.Cu" "In2.Cu")
		(hatch none 0.5)
		(connect_pads
			(clearance 0)
		)
		(min_thickness 0.25)
		(keepout
			(tracks not_allowed)
			(vias allowed)
			(pads allowed)
			(copperpour not_allowed)
			(footprints allowed)
		)
		(placement
			(enabled no)
			(sheetname "")
		)
		(fill yes
			(thermal_gap 0.5)
			(thermal_bridge_width 0.5)
			(island_removal_mode 0)
		)
		(polygon
			(pts
				(arc
					(start 32.057086 -129.50825)
					(mid 32.021165 -129.523129)
					(end 32.006286 -129.55905)
				)
				(arc
					(start 32.006286 -129.76225)
					(mid 32.021165 -129.798171)
					(end 32.057086 -129.81305)
				)
				(arc
					(start 32.869886 -129.81305)
					(mid 32.905807 -129.798171)
					(end 32.920686 -129.76225)
				)
				(arc
					(start 32.920686 -129.55905)
					(mid 32.905807 -129.523129)
					(end 32.869886 -129.50825)
				)
			)
		)
	)
	(zone
		(layers "In1.Cu" "In2.Cu")
		(hatch none 0.5)
		(connect_pads
			(clearance 0)
		)
		(min_thickness 0.25)
		(keepout
			(tracks not_allowed)
			(vias allowed)
			(pads allowed)
			(copperpour not_allowed)
			(footprints allowed)
		)
		(placement
			(enabled no)
			(sheetname "")
		)
		(fill yes
			(thermal_gap 0.5)
			(thermal_bridge_width 0.5)
			(island_removal_mode 0)
		)
		(polygon
			(pts
				(arc
					(start 447.428112 -244.508274)
					(mid 447.392191 -244.523153)
					(end 447.377312 -244.559074)
				)
				(arc
					(start 447.377312 -244.762274)
					(mid 447.392191 -244.798195)
					(end 447.428112 -244.813074)
				)
				(arc
					(start 448.240912 -244.813074)
					(mid 448.276833 -244.798195)
					(end 448.291712 -244.762274)
				)
				(arc
					(start 448.291712 -244.559074)
					(mid 448.276833 -244.523153)
					(end 448.240912 -244.508274)
				)
			)
		)
	)
	(zone
		(layers "In1.Cu" "In2.Cu")
		(hatch none 0.5)
		(connect_pads
			(clearance 0)
		)
		(min_thickness 0.25)
		(keepout
			(tracks not_allowed)
			(vias allowed)
			(pads allowed)
			(copperpour not_allowed)
			(footprints allowed)
		)
		(placement
			(enabled no)
			(sheetname "")
		)
		(fill yes
			(thermal_gap 0.5)
			(thermal_bridge_width 0.5)
			(island_removal_mode 0)
		)
		(polygon
			(pts
				(xy 123.493784 -128.33985) (xy 125.855984 -128.33985) (xy 125.855984 -131.54025) (xy 123.493784 -131.54025)
			)
		)
	)
	(zone
		(layers "In1.Cu" "In2.Cu")
		(hatch none 0.5)
		(connect_pads
			(clearance 0)
		)
		(min_thickness 0.25)
		(keepout
			(tracks not_allowed)
			(vias allowed)
			(pads allowed)
			(copperpour not_allowed)
			(footprints allowed)
		)
		(placement
			(enabled no)
			(sheetname "")
		)
		(fill yes
			(thermal_gap 0.5)
			(thermal_bridge_width 0.5)
			(island_removal_mode 0)
		)
		(polygon
			(pts
				(arc
					(start 415.878264 -129.50825)
					(mid 415.842343 -129.523129)
					(end 415.827464 -129.55905)
				)
				(arc
					(start 415.827464 -129.76225)
					(mid 415.842343 -129.798171)
					(end 415.878264 -129.81305)
				)
				(arc
					(start 416.691064 -129.81305)
					(mid 416.726985 -129.798171)
					(end 416.741864 -129.76225)
				)
				(arc
					(start 416.741864 -129.55905)
					(mid 416.726985 -129.523129)
					(end 416.691064 -129.50825)
				)
			)
		)
	)
	(zone
		(layers "In1.Cu" "In2.Cu")
		(hatch none 0.5)
		(connect_pads
			(clearance 0)
		)
		(min_thickness 0.25)
		(keepout
			(tracks not_allowed)
			(vias allowed)
			(pads allowed)
			(copperpour not_allowed)
			(footprints allowed)
		)
		(placement
			(enabled no)
			(sheetname "")
		)
		(fill yes
			(thermal_gap 0.5)
			(thermal_bridge_width 0.5)
			(island_removal_mode 0)
		)
		(polygon
			(pts
				(xy 155.043886 -17.149826) (xy 157.406086 -17.149826) (xy 157.406086 -20.350226) (xy 155.043886 -20.350226)
			)
		)
	)
	(zone
		(layers "In1.Cu" "In2.Cu")
		(hatch none 0.5)
		(connect_pads
			(clearance 0)
		)
		(min_thickness 0.25)
		(keepout
			(tracks not_allowed)
			(vias allowed)
			(pads allowed)
			(copperpour not_allowed)
			(footprints allowed)
		)
		(placement
			(enabled no)
			(sheetname "")
		)
		(fill yes
			(thermal_gap 0.5)
			(thermal_bridge_width 0.5)
			(island_removal_mode 0)
		)
		(polygon
			(pts
				(arc
					(start 126.706884 -14.508226)
					(mid 126.670963 -14.523105)
					(end 126.656084 -14.559026)
				)
				(arc
					(start 126.656084 -14.762226)
					(mid 126.670963 -14.798147)
					(end 126.706884 -14.813026)
				)
				(arc
					(start 127.519684 -14.813026)
					(mid 127.555605 -14.798147)
					(end 127.570484 -14.762226)
				)
				(arc
					(start 127.570484 -14.559026)
					(mid 127.555605 -14.523105)
					(end 127.519684 -14.508226)
				)
			)
		)
	)
	(zone
		(layers "In1.Cu" "In2.Cu")
		(hatch none 0.5)
		(connect_pads
			(clearance 0)
		)
		(min_thickness 0.25)
		(keepout
			(tracks not_allowed)
			(vias allowed)
			(pads allowed)
			(copperpour not_allowed)
			(footprints allowed)
		)
		(placement
			(enabled no)
			(sheetname "")
		)
		(fill yes
			(thermal_gap 0.5)
			(thermal_bridge_width 0.5)
			(island_removal_mode 0)
		)
		(polygon
			(pts
				(arc
					(start 415.878264 -15.067026)
					(mid 415.842343 -15.081905)
					(end 415.827464 -15.117826)
				)
				(arc
					(start 415.827464 -15.321026)
					(mid 415.842343 -15.356947)
					(end 415.878264 -15.371826)
				)
				(arc
					(start 416.691064 -15.371826)
					(mid 416.726985 -15.356947)
					(end 416.741864 -15.321026)
				)
				(arc
					(start 416.741864 -15.117826)
					(mid 416.726985 -15.081905)
					(end 416.691064 -15.067026)
				)
			)
		)
	)
	(zone
		(layers "In1.Cu" "In2.Cu")
		(hatch none 0.5)
		(connect_pads
			(clearance 0)
		)
		(min_thickness 0.25)
		(keepout
			(tracks not_allowed)
			(vias allowed)
			(pads allowed)
			(copperpour not_allowed)
			(footprints allowed)
		)
		(placement
			(enabled no)
			(sheetname "")
		)
		(fill yes
			(thermal_gap 0.5)
			(thermal_bridge_width 0.5)
			(island_removal_mode 0)
		)
		(polygon
			(pts
				(xy 452.393812 -13.339826) (xy 454.756012 -13.339826) (xy 454.756012 -16.540226) (xy 452.393812 -16.540226)
			)
		)
	)
	(zone
		(layers "In1.Cu" "In2.Cu")
		(hatch none 0.5)
		(connect_pads
			(clearance 0)
		)
		(min_thickness 0.25)
		(keepout
			(tracks not_allowed)
			(vias allowed)
			(pads allowed)
			(copperpour not_allowed)
			(footprints allowed)
		)
		(placement
			(enabled no)
			(sheetname "")
		)
		(fill yes
			(thermal_gap 0.5)
			(thermal_bridge_width 0.5)
			(island_removal_mode 0)
		)
		(polygon
			(pts
				(arc
					(start 384.328162 -129.50825)
					(mid 384.292241 -129.523129)
					(end 384.277362 -129.55905)
				)
				(arc
					(start 384.277362 -129.76225)
					(mid 384.292241 -129.798171)
					(end 384.328162 -129.81305)
				)
				(arc
					(start 385.140962 -129.81305)
					(mid 385.176883 -129.798171)
					(end 385.191762 -129.76225)
				)
				(arc
					(start 385.191762 -129.55905)
					(mid 385.176883 -129.523129)
					(end 385.140962 -129.50825)
				)
			)
		)
	)
	(zone
		(layers "In1.Cu" "In2.Cu")
		(hatch none 0.5)
		(connect_pads
			(clearance 0)
		)
		(min_thickness 0.25)
		(keepout
			(tracks not_allowed)
			(vias allowed)
			(pads allowed)
			(copperpour not_allowed)
			(footprints allowed)
		)
		(placement
			(enabled no)
			(sheetname "")
		)
		(fill yes
			(thermal_gap 0.5)
			(thermal_bridge_width 0.5)
			(island_removal_mode 0)
		)
		(polygon
			(pts
				(xy 389.293862 -132.14985) (xy 391.656062 -132.14985) (xy 391.656062 -135.35025) (xy 389.293862 -135.35025)
			)
		)
	)
	(zone
		(layers "In1.Cu" "In2.Cu")
		(hatch none 0.5)
		(connect_pads
			(clearance 0)
		)
		(min_thickness 0.25)
		(keepout
			(tracks not_allowed)
			(vias allowed)
			(pads allowed)
			(copperpour not_allowed)
			(footprints allowed)
		)
		(placement
			(enabled no)
			(sheetname "")
		)
		(fill yes
			(thermal_gap 0.5)
			(thermal_bridge_width 0.5)
			(island_removal_mode 0)
		)
		(polygon
			(pts
				(arc
					(start 352.778314 -14.508226)
					(mid 352.742393 -14.523105)
					(end 352.727514 -14.559026)
				)
				(arc
					(start 352.727514 -14.762226)
					(mid 352.742393 -14.798147)
					(end 352.778314 -14.813026)
				)
				(arc
					(start 353.591114 -14.813026)
					(mid 353.627035 -14.798147)
					(end 353.641914 -14.762226)
				)
				(arc
					(start 353.641914 -14.559026)
					(mid 353.627035 -14.523105)
					(end 353.591114 -14.508226)
				)
			)
		)
	)
	(zone
		(layers "In1.Cu" "In2.Cu")
		(hatch none 0.5)
		(connect_pads
			(clearance 0)
		)
		(min_thickness 0.25)
		(keepout
			(tracks not_allowed)
			(vias allowed)
			(pads allowed)
			(copperpour not_allowed)
			(footprints allowed)
		)
		(placement
			(enabled no)
			(sheetname "")
		)
		(fill yes
			(thermal_gap 0.5)
			(thermal_bridge_width 0.5)
			(island_removal_mode 0)
		)
		(polygon
			(pts
				(xy 326.193912 -243.339874) (xy 328.556112 -243.339874) (xy 328.556112 -246.540274) (xy 326.193912 -246.540274)
			)
		)
	)
	(zone
		(layers "In1.Cu" "In2.Cu")
		(hatch none 0.5)
		(connect_pads
			(clearance 0)
		)
		(min_thickness 0.25)
		(keepout
			(tracks not_allowed)
			(vias allowed)
			(pads allowed)
			(copperpour not_allowed)
			(footprints allowed)
		)
		(placement
			(enabled no)
			(sheetname "")
		)
		(fill yes
			(thermal_gap 0.5)
			(thermal_bridge_width 0.5)
			(island_removal_mode 0)
		)
		(polygon
			(pts
				(xy 483.943914 -128.33985) (xy 486.306114 -128.33985) (xy 486.306114 -131.54025) (xy 483.943914 -131.54025)
			)
		)
	)
	(zone
		(layers "In1.Cu" "In2.Cu")
		(hatch none 0.5)
		(connect_pads
			(clearance 0)
		)
		(min_thickness 0.25)
		(keepout
			(tracks not_allowed)
			(vias allowed)
			(pads allowed)
			(copperpour not_allowed)
			(footprints allowed)
		)
		(placement
			(enabled no)
			(sheetname "")
		)
		(fill yes
			(thermal_gap 0.5)
			(thermal_bridge_width 0.5)
			(island_removal_mode 0)
		)
		(polygon
			(pts
				(arc
					(start 63.606934 -15.067026)
					(mid 63.571013 -15.081905)
					(end 63.556134 -15.117826)
				)
				(arc
					(start 63.556134 -15.321026)
					(mid 63.571013 -15.356947)
					(end 63.606934 -15.371826)
				)
				(arc
					(start 64.419734 -15.371826)
					(mid 64.455655 -15.356947)
					(end 64.470534 -15.321026)
				)
				(arc
					(start 64.470534 -15.117826)
					(mid 64.455655 -15.081905)
					(end 64.419734 -15.067026)
				)
			)
		)
	)
	(zone
		(layers "In1.Cu" "In2.Cu")
		(hatch none 0.5)
		(connect_pads
			(clearance 0)
		)
		(min_thickness 0.25)
		(keepout
			(tracks not_allowed)
			(vias allowed)
			(pads allowed)
			(copperpour not_allowed)
			(footprints allowed)
		)
		(placement
			(enabled no)
			(sheetname "")
		)
		(fill yes
			(thermal_gap 0.5)
			(thermal_bridge_width 0.5)
			(island_removal_mode 0)
		)
		(polygon
			(pts
				(arc
					(start 158.256986 -244.508274)
					(mid 158.221065 -244.523153)
					(end 158.206186 -244.559074)
				)
				(arc
					(start 158.206186 -244.762274)
					(mid 158.221065 -244.798195)
					(end 158.256986 -244.813074)
				)
				(arc
					(start 159.069786 -244.813074)
					(mid 159.105707 -244.798195)
					(end 159.120586 -244.762274)
				)
				(arc
					(start 159.120586 -244.559074)
					(mid 159.105707 -244.523153)
					(end 159.069786 -244.508274)
				)
			)
		)
	)
	(zone
		(layers "In1.Cu" "In2.Cu")
		(hatch none 0.5)
		(connect_pads
			(clearance 0)
		)
		(min_thickness 0.25)
		(keepout
			(tracks not_allowed)
			(vias allowed)
			(pads allowed)
			(copperpour not_allowed)
			(footprints allowed)
		)
		(placement
			(enabled no)
			(sheetname "")
		)
		(fill yes
			(thermal_gap 0.5)
			(thermal_bridge_width 0.5)
			(island_removal_mode 0)
		)
		(polygon
			(pts
				(arc
					(start 478.978214 -15.067026)
					(mid 478.942293 -15.081905)
					(end 478.927414 -15.117826)
				)
				(arc
					(start 478.927414 -15.321026)
					(mid 478.942293 -15.356947)
					(end 478.978214 -15.371826)
				)
				(arc
					(start 479.791014 -15.371826)
					(mid 479.826935 -15.356947)
					(end 479.841814 -15.321026)
				)
				(arc
					(start 479.841814 -15.117826)
					(mid 479.826935 -15.081905)
					(end 479.791014 -15.067026)
				)
			)
		)
	)
	(zone
		(layers "In1.Cu" "In2.Cu")
		(hatch none 0.5)
		(connect_pads
			(clearance 0)
		)
		(min_thickness 0.25)
		(keepout
			(tracks not_allowed)
			(vias allowed)
			(pads allowed)
			(copperpour not_allowed)
			(footprints allowed)
		)
		(placement
			(enabled no)
			(sheetname "")
		)
		(fill yes
			(thermal_gap 0.5)
			(thermal_bridge_width 0.5)
			(island_removal_mode 0)
		)
		(polygon
			(pts
				(arc
					(start 189.807088 -129.50825)
					(mid 189.771167 -129.523129)
					(end 189.756288 -129.55905)
				)
				(arc
					(start 189.756288 -129.76225)
					(mid 189.771167 -129.798171)
					(end 189.807088 -129.81305)
				)
				(arc
					(start 190.619888 -129.81305)
					(mid 190.655809 -129.798171)
					(end 190.670688 -129.76225)
				)
				(arc
					(start 190.670688 -129.55905)
					(mid 190.655809 -129.523129)
					(end 190.619888 -129.50825)
				)
			)
		)
	)
	(zone
		(layers "In1.Cu" "In2.Cu")
		(hatch none 0.5)
		(connect_pads
			(clearance 0)
		)
		(min_thickness 0.25)
		(keepout
			(tracks not_allowed)
			(vias allowed)
			(pads allowed)
			(copperpour not_allowed)
			(footprints allowed)
		)
		(placement
			(enabled no)
			(sheetname "")
		)
		(fill yes
			(thermal_gap 0.5)
			(thermal_bridge_width 0.5)
			(island_removal_mode 0)
		)
		(polygon
			(pts
				(arc
					(start 158.256986 -15.067026)
					(mid 158.221065 -15.081905)
					(end 158.206186 -15.117826)
				)
				(arc
					(start 158.206186 -15.321026)
					(mid 158.221065 -15.356947)
					(end 158.256986 -15.371826)
				)
				(arc
					(start 159.069786 -15.371826)
					(mid 159.105707 -15.356947)
					(end 159.120586 -15.321026)
				)
				(arc
					(start 159.120586 -15.117826)
					(mid 159.105707 -15.081905)
					(end 159.069786 -15.067026)
				)
			)
		)
	)
	(zone
		(layers "In1.Cu" "In2.Cu")
		(hatch none 0.5)
		(connect_pads
			(clearance 0)
		)
		(min_thickness 0.25)
		(keepout
			(tracks not_allowed)
			(vias allowed)
			(pads allowed)
			(copperpour not_allowed)
			(footprints allowed)
		)
		(placement
			(enabled no)
			(sheetname "")
		)
		(fill yes
			(thermal_gap 0.5)
			(thermal_bridge_width 0.5)
			(island_removal_mode 0)
		)
		(polygon
			(pts
				(arc
					(start 321.228212 -244.508274)
					(mid 321.192291 -244.523153)
					(end 321.177412 -244.559074)
				)
				(arc
					(start 321.177412 -244.762274)
					(mid 321.192291 -244.798195)
					(end 321.228212 -244.813074)
				)
				(arc
					(start 322.041012 -244.813074)
					(mid 322.076933 -244.798195)
					(end 322.091812 -244.762274)
				)
				(arc
					(start 322.091812 -244.559074)
					(mid 322.076933 -244.523153)
					(end 322.041012 -244.508274)
				)
			)
		)
	)
	(zone
		(layers "In1.Cu" "In2.Cu")
		(hatch none 0.5)
		(connect_pads
			(clearance 0)
		)
		(min_thickness 0.25)
		(keepout
			(tracks not_allowed)
			(vias allowed)
			(pads allowed)
			(copperpour not_allowed)
			(footprints allowed)
		)
		(placement
			(enabled no)
			(sheetname "")
		)
		(fill yes
			(thermal_gap 0.5)
			(thermal_bridge_width 0.5)
			(island_removal_mode 0)
		)
		(polygon
			(pts
				(xy 452.393812 -247.149874) (xy 454.756012 -247.149874) (xy 454.756012 -250.350274) (xy 452.393812 -250.350274)
			)
		)
	)
	(zone
		(layers "In1.Cu" "In2.Cu")
		(hatch none 0.5)
		(connect_pads
			(clearance 0)
		)
		(min_thickness 0.25)
		(keepout
			(tracks not_allowed)
			(vias allowed)
			(pads allowed)
			(copperpour not_allowed)
			(footprints allowed)
		)
		(placement
			(enabled no)
			(sheetname "")
		)
		(fill yes
			(thermal_gap 0.5)
			(thermal_bridge_width 0.5)
			(island_removal_mode 0)
		)
		(polygon
			(pts
				(xy 483.943914 -132.14985) (xy 486.306114 -132.14985) (xy 486.306114 -135.35025) (xy 483.943914 -135.35025)
			)
		)
	)
	(zone
		(layers "In1.Cu" "In2.Cu")
		(hatch none 0.5)
		(connect_pads
			(clearance 0)
		)
		(min_thickness 0.25)
		(keepout
			(tracks not_allowed)
			(vias allowed)
			(pads allowed)
			(copperpour not_allowed)
			(footprints allowed)
		)
		(placement
			(enabled no)
			(sheetname "")
		)
		(fill yes
			(thermal_gap 0.5)
			(thermal_bridge_width 0.5)
			(island_removal_mode 0)
		)
		(polygon
			(pts
				(xy 155.043886 -13.339826) (xy 157.406086 -13.339826) (xy 157.406086 -16.540226) (xy 155.043886 -16.540226)
			)
		)
	)
	(zone
		(layers "In1.Cu" "In2.Cu")
		(hatch none 0.5)
		(connect_pads
			(clearance 0)
		)
		(min_thickness 0.25)
		(keepout
			(tracks not_allowed)
			(vias allowed)
			(pads allowed)
			(copperpour not_allowed)
			(footprints allowed)
		)
		(placement
			(enabled no)
			(sheetname "")
		)
		(fill yes
			(thermal_gap 0.5)
			(thermal_bridge_width 0.5)
			(island_removal_mode 0)
		)
		(polygon
			(pts
				(arc
					(start 63.606934 -14.508226)
					(mid 63.571013 -14.523105)
					(end 63.556134 -14.559026)
				)
				(arc
					(start 63.556134 -14.762226)
					(mid 63.571013 -14.798147)
					(end 63.606934 -14.813026)
				)
				(arc
					(start 64.419734 -14.813026)
					(mid 64.455655 -14.798147)
					(end 64.470534 -14.762226)
				)
				(arc
					(start 64.470534 -14.559026)
					(mid 64.455655 -14.523105)
					(end 64.419734 -14.508226)
				)
			)
		)
	)
	(zone
		(layers "In1.Cu" "In2.Cu")
		(hatch none 0.5)
		(connect_pads
			(clearance 0)
		)
		(min_thickness 0.25)
		(keepout
			(tracks not_allowed)
			(vias allowed)
			(pads allowed)
			(copperpour not_allowed)
			(footprints allowed)
		)
		(placement
			(enabled no)
			(sheetname "")
		)
		(fill yes
			(thermal_gap 0.5)
			(thermal_bridge_width 0.5)
			(island_removal_mode 0)
		)
		(polygon
			(pts
				(arc
					(start 447.428112 -245.067074)
					(mid 447.392191 -245.081953)
					(end 447.377312 -245.117874)
				)
				(arc
					(start 447.377312 -245.321074)
					(mid 447.392191 -245.356995)
					(end 447.428112 -245.371874)
				)
				(arc
					(start 448.240912 -245.371874)
					(mid 448.276833 -245.356995)
					(end 448.291712 -245.321074)
				)
				(arc
					(start 448.291712 -245.117874)
					(mid 448.276833 -245.081953)
					(end 448.240912 -245.067074)
				)
			)
		)
	)
	(zone
		(layers "In1.Cu" "In2.Cu")
		(hatch none 0.5)
		(connect_pads
			(clearance 0)
		)
		(min_thickness 0.25)
		(keepout
			(tracks not_allowed)
			(vias allowed)
			(pads allowed)
			(copperpour not_allowed)
			(footprints allowed)
		)
		(placement
			(enabled no)
			(sheetname "")
		)
		(fill yes
			(thermal_gap 0.5)
			(thermal_bridge_width 0.5)
			(island_removal_mode 0)
		)
		(polygon
			(pts
				(arc
					(start 126.706884 -244.508274)
					(mid 126.670963 -244.523153)
					(end 126.656084 -244.559074)
				)
				(arc
					(start 126.656084 -244.762274)
					(mid 126.670963 -244.798195)
					(end 126.706884 -244.813074)
				)
				(arc
					(start 127.519684 -244.813074)
					(mid 127.555605 -244.798195)
					(end 127.570484 -244.762274)
				)
				(arc
					(start 127.570484 -244.559074)
					(mid 127.555605 -244.523153)
					(end 127.519684 -244.508274)
				)
			)
		)
	)
	(zone
		(layers "In1.Cu" "In2.Cu")
		(hatch none 0.5)
		(connect_pads
			(clearance 0)
		)
		(min_thickness 0.25)
		(keepout
			(tracks not_allowed)
			(vias allowed)
			(pads allowed)
			(copperpour not_allowed)
			(footprints allowed)
		)
		(placement
			(enabled no)
			(sheetname "")
		)
		(fill yes
			(thermal_gap 0.5)
			(thermal_bridge_width 0.5)
			(island_removal_mode 0)
		)
		(polygon
			(pts
				(xy 483.943914 -247.149874) (xy 486.306114 -247.149874) (xy 486.306114 -250.350274) (xy 483.943914 -250.350274)
			)
		)
	)
	(zone
		(layers "In1.Cu" "In2.Cu")
		(hatch none 0.5)
		(connect_pads
			(clearance 0)
		)
		(min_thickness 0.25)
		(keepout
			(tracks not_allowed)
			(vias allowed)
			(pads allowed)
			(copperpour not_allowed)
			(footprints allowed)
		)
		(placement
			(enabled no)
			(sheetname "")
		)
		(fill yes
			(thermal_gap 0.5)
			(thermal_bridge_width 0.5)
			(island_removal_mode 0)
		)
		(polygon
			(pts
				(arc
					(start 95.157036 -244.508274)
					(mid 95.121115 -244.523153)
					(end 95.106236 -244.559074)
				)
				(arc
					(start 95.106236 -244.762274)
					(mid 95.121115 -244.798195)
					(end 95.157036 -244.813074)
				)
				(arc
					(start 95.969836 -244.813074)
					(mid 96.005757 -244.798195)
					(end 96.020636 -244.762274)
				)
				(arc
					(start 96.020636 -244.559074)
					(mid 96.005757 -244.523153)
					(end 95.969836 -244.508274)
				)
			)
		)
	)
	(zone
		(layers "In1.Cu" "In2.Cu")
		(hatch none 0.5)
		(connect_pads
			(clearance 0)
		)
		(min_thickness 0.25)
		(keepout
			(tracks not_allowed)
			(vias allowed)
			(pads allowed)
			(copperpour not_allowed)
			(footprints allowed)
		)
		(placement
			(enabled no)
			(sheetname "")
		)
		(fill yes
			(thermal_gap 0.5)
			(thermal_bridge_width 0.5)
			(island_removal_mode 0)
		)
		(polygon
			(pts
				(xy 420.843964 -13.339826) (xy 423.206164 -13.339826) (xy 423.206164 -16.540226) (xy 420.843964 -16.540226)
			)
		)
	)
	(zone
		(layers "In1.Cu" "In2.Cu")
		(hatch none 0.5)
		(connect_pads
			(clearance 0)
		)
		(min_thickness 0.25)
		(keepout
			(tracks not_allowed)
			(vias allowed)
			(pads allowed)
			(copperpour not_allowed)
			(footprints allowed)
		)
		(placement
			(enabled no)
			(sheetname "")
		)
		(fill yes
			(thermal_gap 0.5)
			(thermal_bridge_width 0.5)
			(island_removal_mode 0)
		)
		(polygon
			(pts
				(arc
					(start 384.328162 -245.067074)
					(mid 384.292241 -245.081953)
					(end 384.277362 -245.117874)
				)
				(arc
					(start 384.277362 -245.321074)
					(mid 384.292241 -245.356995)
					(end 384.328162 -245.371874)
				)
				(arc
					(start 385.140962 -245.371874)
					(mid 385.176883 -245.356995)
					(end 385.191762 -245.321074)
				)
				(arc
					(start 385.191762 -245.117874)
					(mid 385.176883 -245.081953)
					(end 385.140962 -245.067074)
				)
			)
		)
	)
	(zone
		(layers "In1.Cu" "In2.Cu")
		(hatch none 0.5)
		(connect_pads
			(clearance 0)
		)
		(min_thickness 0.25)
		(keepout
			(tracks not_allowed)
			(vias allowed)
			(pads allowed)
			(copperpour not_allowed)
			(footprints allowed)
		)
		(placement
			(enabled no)
			(sheetname "")
		)
		(fill yes
			(thermal_gap 0.5)
			(thermal_bridge_width 0.5)
			(island_removal_mode 0)
		)
		(polygon
			(pts
				(arc
					(start 158.256986 -245.067074)
					(mid 158.221065 -245.081953)
					(end 158.206186 -245.117874)
				)
				(arc
					(start 158.206186 -245.321074)
					(mid 158.221065 -245.356995)
					(end 158.256986 -245.371874)
				)
				(arc
					(start 159.069786 -245.371874)
					(mid 159.105707 -245.356995)
					(end 159.120586 -245.321074)
				)
				(arc
					(start 159.120586 -245.117874)
					(mid 159.105707 -245.081953)
					(end 159.069786 -245.067074)
				)
			)
		)
	)
	(zone
		(layers "In1.Cu" "In2.Cu")
		(hatch none 0.5)
		(connect_pads
			(clearance 0)
		)
		(min_thickness 0.25)
		(keepout
			(tracks not_allowed)
			(vias allowed)
			(pads allowed)
			(copperpour not_allowed)
			(footprints allowed)
		)
		(placement
			(enabled no)
			(sheetname "")
		)
		(fill yes
			(thermal_gap 0.5)
			(thermal_bridge_width 0.5)
			(island_removal_mode 0)
		)
		(polygon
			(pts
				(xy 28.843986 -243.339874) (xy 31.206186 -243.339874) (xy 31.206186 -246.540274) (xy 28.843986 -246.540274)
			)
		)
	)
	(zone
		(layers "In1.Cu" "In2.Cu")
		(hatch none 0.5)
		(connect_pads
			(clearance 0)
		)
		(min_thickness 0.25)
		(keepout
			(tracks not_allowed)
			(vias allowed)
			(pads allowed)
			(copperpour not_allowed)
			(footprints allowed)
		)
		(placement
			(enabled no)
			(sheetname "")
		)
		(fill yes
			(thermal_gap 0.5)
			(thermal_bridge_width 0.5)
			(island_removal_mode 0)
		)
		(polygon
			(pts
				(xy 326.193912 -13.339826) (xy 328.556112 -13.339826) (xy 328.556112 -16.540226) (xy 326.193912 -16.540226)
			)
		)
	)
	(zone
		(layers "In1.Cu" "In2.Cu")
		(hatch none 0.5)
		(connect_pads
			(clearance 0)
		)
		(min_thickness 0.25)
		(keepout
			(tracks not_allowed)
			(vias allowed)
			(pads allowed)
			(copperpour not_allowed)
			(footprints allowed)
		)
		(placement
			(enabled no)
			(sheetname "")
		)
		(fill yes
			(thermal_gap 0.5)
			(thermal_bridge_width 0.5)
			(island_removal_mode 0)
		)
		(polygon
			(pts
				(xy 60.393834 -13.339826) (xy 62.756034 -13.339826) (xy 62.756034 -16.540226) (xy 60.393834 -16.540226)
			)
		)
	)
	(zone
		(layers "In1.Cu" "In2.Cu")
		(hatch none 0.5)
		(connect_pads
			(clearance 0)
		)
		(min_thickness 0.25)
		(keepout
			(tracks not_allowed)
			(vias allowed)
			(pads allowed)
			(copperpour not_allowed)
			(footprints allowed)
		)
		(placement
			(enabled no)
			(sheetname "")
		)
		(fill yes
			(thermal_gap 0.5)
			(thermal_bridge_width 0.5)
			(island_removal_mode 0)
		)
		(polygon
			(pts
				(arc
					(start 63.606934 -130.06705)
					(mid 63.571013 -130.081929)
					(end 63.556134 -130.11785)
				)
				(arc
					(start 63.556134 -130.32105)
					(mid 63.571013 -130.356971)
					(end 63.606934 -130.37185)
				)
				(arc
					(start 64.419734 -130.37185)
					(mid 64.455655 -130.356971)
					(end 64.470534 -130.32105)
				)
				(arc
					(start 64.470534 -130.11785)
					(mid 64.455655 -130.081929)
					(end 64.419734 -130.06705)
				)
			)
		)
	)
	(zone
		(layers "In1.Cu" "In2.Cu")
		(hatch none 0.5)
		(connect_pads
			(clearance 0)
		)
		(min_thickness 0.25)
		(keepout
			(tracks not_allowed)
			(vias allowed)
			(pads allowed)
			(copperpour not_allowed)
			(footprints allowed)
		)
		(placement
			(enabled no)
			(sheetname "")
		)
		(fill yes
			(thermal_gap 0.5)
			(thermal_bridge_width 0.5)
			(island_removal_mode 0)
		)
		(polygon
			(pts
				(xy 28.843986 -17.149826) (xy 31.206186 -17.149826) (xy 31.206186 -20.350226) (xy 28.843986 -20.350226)
			)
		)
	)
	(zone
		(layers "In1.Cu" "In2.Cu")
		(hatch none 0.5)
		(connect_pads
			(clearance 0)
		)
		(min_thickness 0.25)
		(keepout
			(tracks not_allowed)
			(vias allowed)
			(pads allowed)
			(copperpour not_allowed)
			(footprints allowed)
		)
		(placement
			(enabled no)
			(sheetname "")
		)
		(fill yes
			(thermal_gap 0.5)
			(thermal_bridge_width 0.5)
			(island_removal_mode 0)
		)
		(polygon
			(pts
				(xy 357.744014 -243.339874) (xy 360.106214 -243.339874) (xy 360.106214 -246.540274) (xy 357.744014 -246.540274)
			)
		)
	)
	(zone
		(layers "In1.Cu" "In2.Cu")
		(hatch none 0.5)
		(connect_pads
			(clearance 0)
		)
		(min_thickness 0.25)
		(keepout
			(tracks not_allowed)
			(vias allowed)
			(pads allowed)
			(copperpour not_allowed)
			(footprints allowed)
		)
		(placement
			(enabled no)
			(sheetname "")
		)
		(fill yes
			(thermal_gap 0.5)
			(thermal_bridge_width 0.5)
			(island_removal_mode 0)
		)
		(polygon
			(pts
				(arc
					(start 32.057086 -15.067026)
					(mid 32.021165 -15.081905)
					(end 32.006286 -15.117826)
				)
				(arc
					(start 32.006286 -15.321026)
					(mid 32.021165 -15.356947)
					(end 32.057086 -15.371826)
				)
				(arc
					(start 32.869886 -15.371826)
					(mid 32.905807 -15.356947)
					(end 32.920686 -15.321026)
				)
				(arc
					(start 32.920686 -15.117826)
					(mid 32.905807 -15.081905)
					(end 32.869886 -15.067026)
				)
			)
		)
	)
	(zone
		(layers "In1.Cu" "In2.Cu")
		(hatch none 0.5)
		(connect_pads
			(clearance 0)
		)
		(min_thickness 0.25)
		(keepout
			(tracks not_allowed)
			(vias allowed)
			(pads allowed)
			(copperpour not_allowed)
			(footprints allowed)
		)
		(placement
			(enabled no)
			(sheetname "")
		)
		(fill yes
			(thermal_gap 0.5)
			(thermal_bridge_width 0.5)
			(island_removal_mode 0)
		)
		(polygon
			(pts
				(arc
					(start 384.328162 -244.508274)
					(mid 384.292241 -244.523153)
					(end 384.277362 -244.559074)
				)
				(arc
					(start 384.277362 -244.762274)
					(mid 384.292241 -244.798195)
					(end 384.328162 -244.813074)
				)
				(arc
					(start 385.140962 -244.813074)
					(mid 385.176883 -244.798195)
					(end 385.191762 -244.762274)
				)
				(arc
					(start 385.191762 -244.559074)
					(mid 385.176883 -244.523153)
					(end 385.140962 -244.508274)
				)
			)
		)
	)
	(zone
		(layers "In1.Cu" "In2.Cu")
		(hatch none 0.5)
		(connect_pads
			(clearance 0)
		)
		(min_thickness 0.25)
		(keepout
			(tracks not_allowed)
			(vias allowed)
			(pads allowed)
			(copperpour not_allowed)
			(footprints allowed)
		)
		(placement
			(enabled no)
			(sheetname "")
		)
		(fill yes
			(thermal_gap 0.5)
			(thermal_bridge_width 0.5)
			(island_removal_mode 0)
		)
		(polygon
			(pts
				(arc
					(start 32.057086 -244.508274)
					(mid 32.021165 -244.523153)
					(end 32.006286 -244.559074)
				)
				(arc
					(start 32.006286 -244.762274)
					(mid 32.021165 -244.798195)
					(end 32.057086 -244.813074)
				)
				(arc
					(start 32.869886 -244.813074)
					(mid 32.905807 -244.798195)
					(end 32.920686 -244.762274)
				)
				(arc
					(start 32.920686 -244.559074)
					(mid 32.905807 -244.523153)
					(end 32.869886 -244.508274)
				)
			)
		)
	)
	(zone
		(layers "In1.Cu" "In2.Cu")
		(hatch none 0.5)
		(connect_pads
			(clearance 0)
		)
		(min_thickness 0.25)
		(keepout
			(tracks not_allowed)
			(vias allowed)
			(pads allowed)
			(copperpour not_allowed)
			(footprints allowed)
		)
		(placement
			(enabled no)
			(sheetname "")
		)
		(fill yes
			(thermal_gap 0.5)
			(thermal_bridge_width 0.5)
			(island_removal_mode 0)
		)
		(polygon
			(pts
				(arc
					(start 321.228212 -129.50825)
					(mid 321.192291 -129.523129)
					(end 321.177412 -129.55905)
				)
				(arc
					(start 321.177412 -129.76225)
					(mid 321.192291 -129.798171)
					(end 321.228212 -129.81305)
				)
				(arc
					(start 322.041012 -129.81305)
					(mid 322.076933 -129.798171)
					(end 322.091812 -129.76225)
				)
				(arc
					(start 322.091812 -129.55905)
					(mid 322.076933 -129.523129)
					(end 322.041012 -129.50825)
				)
			)
		)
	)
	(zone
		(layers "In1.Cu" "In2.Cu")
		(hatch none 0.5)
		(connect_pads
			(clearance 0)
		)
		(min_thickness 0.25)
		(keepout
			(tracks not_allowed)
			(vias allowed)
			(pads allowed)
			(copperpour not_allowed)
			(footprints allowed)
		)
		(placement
			(enabled no)
			(sheetname "")
		)
		(fill yes
			(thermal_gap 0.5)
			(thermal_bridge_width 0.5)
			(island_removal_mode 0)
		)
		(polygon
			(pts
				(arc
					(start 189.807088 -245.067074)
					(mid 189.771167 -245.081953)
					(end 189.756288 -245.117874)
				)
				(arc
					(start 189.756288 -245.321074)
					(mid 189.771167 -245.356995)
					(end 189.807088 -245.371874)
				)
				(arc
					(start 190.619888 -245.371874)
					(mid 190.655809 -245.356995)
					(end 190.670688 -245.321074)
				)
				(arc
					(start 190.670688 -245.117874)
					(mid 190.655809 -245.081953)
					(end 190.619888 -245.067074)
				)
			)
		)
	)
	(zone
		(layers "In1.Cu" "In2.Cu")
		(hatch none 0.5)
		(connect_pads
			(clearance 0)
		)
		(min_thickness 0.25)
		(keepout
			(tracks not_allowed)
			(vias allowed)
			(pads allowed)
			(copperpour not_allowed)
			(footprints allowed)
		)
		(placement
			(enabled no)
			(sheetname "")
		)
		(fill yes
			(thermal_gap 0.5)
			(thermal_bridge_width 0.5)
			(island_removal_mode 0)
		)
		(polygon
			(pts
				(xy 60.393834 -243.339874) (xy 62.756034 -243.339874) (xy 62.756034 -246.540274) (xy 60.393834 -246.540274)
			)
		)
	)
	(zone
		(layers "In1.Cu" "In2.Cu")
		(hatch none 0.5)
		(connect_pads
			(clearance 0)
		)
		(min_thickness 0.25)
		(keepout
			(tracks not_allowed)
			(vias allowed)
			(pads allowed)
			(copperpour not_allowed)
			(footprints allowed)
		)
		(placement
			(enabled no)
			(sheetname "")
		)
		(fill yes
			(thermal_gap 0.5)
			(thermal_bridge_width 0.5)
			(island_removal_mode 0)
		)
		(polygon
			(pts
				(arc
					(start 32.057086 -14.508226)
					(mid 32.021165 -14.523105)
					(end 32.006286 -14.559026)
				)
				(arc
					(start 32.006286 -14.762226)
					(mid 32.021165 -14.798147)
					(end 32.057086 -14.813026)
				)
				(arc
					(start 32.869886 -14.813026)
					(mid 32.905807 -14.798147)
					(end 32.920686 -14.762226)
				)
				(arc
					(start 32.920686 -14.559026)
					(mid 32.905807 -14.523105)
					(end 32.869886 -14.508226)
				)
			)
		)
	)
	(zone
		(layers "In1.Cu" "In2.Cu")
		(hatch none 0.5)
		(connect_pads
			(clearance 0)
		)
		(min_thickness 0.25)
		(keepout
			(tracks not_allowed)
			(vias allowed)
			(pads allowed)
			(copperpour not_allowed)
			(footprints allowed)
		)
		(placement
			(enabled no)
			(sheetname "")
		)
		(fill yes
			(thermal_gap 0.5)
			(thermal_bridge_width 0.5)
			(island_removal_mode 0)
		)
		(polygon
			(pts
				(arc
					(start 478.978214 -244.508274)
					(mid 478.942293 -244.523153)
					(end 478.927414 -244.559074)
				)
				(arc
					(start 478.927414 -244.762274)
					(mid 478.942293 -244.798195)
					(end 478.978214 -244.813074)
				)
				(arc
					(start 479.791014 -244.813074)
					(mid 479.826935 -244.798195)
					(end 479.841814 -244.762274)
				)
				(arc
					(start 479.841814 -244.559074)
					(mid 479.826935 -244.523153)
					(end 479.791014 -244.508274)
				)
			)
		)
	)
	(zone
		(layers "In1.Cu" "In2.Cu")
		(hatch none 0.5)
		(connect_pads
			(clearance 0)
		)
		(min_thickness 0.25)
		(keepout
			(tracks not_allowed)
			(vias allowed)
			(pads allowed)
			(copperpour not_allowed)
			(footprints allowed)
		)
		(placement
			(enabled no)
			(sheetname "")
		)
		(fill yes
			(thermal_gap 0.5)
			(thermal_bridge_width 0.5)
			(island_removal_mode 0)
		)
		(polygon
			(pts
				(arc
					(start 447.428112 -130.06705)
					(mid 447.392191 -130.081929)
					(end 447.377312 -130.11785)
				)
				(arc
					(start 447.377312 -130.32105)
					(mid 447.392191 -130.356971)
					(end 447.428112 -130.37185)
				)
				(arc
					(start 448.240912 -130.37185)
					(mid 448.276833 -130.356971)
					(end 448.291712 -130.32105)
				)
				(arc
					(start 448.291712 -130.11785)
					(mid 448.276833 -130.081929)
					(end 448.240912 -130.06705)
				)
			)
		)
	)
	(zone
		(layers "In1.Cu" "In2.Cu")
		(hatch none 0.5)
		(connect_pads
			(clearance 0)
		)
		(min_thickness 0.25)
		(keepout
			(tracks not_allowed)
			(vias allowed)
			(pads allowed)
			(copperpour not_allowed)
			(footprints allowed)
		)
		(placement
			(enabled no)
			(sheetname "")
		)
		(fill yes
			(thermal_gap 0.5)
			(thermal_bridge_width 0.5)
			(island_removal_mode 0)
		)
		(polygon
			(pts
				(arc
					(start 63.606934 -245.067074)
					(mid 63.571013 -245.081953)
					(end 63.556134 -245.117874)
				)
				(arc
					(start 63.556134 -245.321074)
					(mid 63.571013 -245.356995)
					(end 63.606934 -245.371874)
				)
				(arc
					(start 64.419734 -245.371874)
					(mid 64.455655 -245.356995)
					(end 64.470534 -245.321074)
				)
				(arc
					(start 64.470534 -245.117874)
					(mid 64.455655 -245.081953)
					(end 64.419734 -245.067074)
				)
			)
		)
	)
	(zone
		(layers "In1.Cu" "In2.Cu")
		(hatch none 0.5)
		(connect_pads
			(clearance 0)
		)
		(min_thickness 0.25)
		(keepout
			(tracks not_allowed)
			(vias allowed)
			(pads allowed)
			(copperpour not_allowed)
			(footprints allowed)
		)
		(placement
			(enabled no)
			(sheetname "")
		)
		(fill yes
			(thermal_gap 0.5)
			(thermal_bridge_width 0.5)
			(island_removal_mode 0)
		)
		(polygon
			(pts
				(arc
					(start 352.778314 -130.06705)
					(mid 352.742393 -130.081929)
					(end 352.727514 -130.11785)
				)
				(arc
					(start 352.727514 -130.32105)
					(mid 352.742393 -130.356971)
					(end 352.778314 -130.37185)
				)
				(arc
					(start 353.591114 -130.37185)
					(mid 353.627035 -130.356971)
					(end 353.641914 -130.32105)
				)
				(arc
					(start 353.641914 -130.11785)
					(mid 353.627035 -130.081929)
					(end 353.591114 -130.06705)
				)
			)
		)
	)
	(zone
		(layers "In1.Cu" "In2.Cu")
		(hatch none 0.5)
		(connect_pads
			(clearance 0)
		)
		(min_thickness 0.25)
		(keepout
			(tracks not_allowed)
			(vias allowed)
			(pads allowed)
			(copperpour not_allowed)
			(footprints allowed)
		)
		(placement
			(enabled no)
			(sheetname "")
		)
		(fill yes
			(thermal_gap 0.5)
			(thermal_bridge_width 0.5)
			(island_removal_mode 0)
		)
		(polygon
			(pts
				(arc
					(start 189.807088 -14.508226)
					(mid 189.771167 -14.523105)
					(end 189.756288 -14.559026)
				)
				(arc
					(start 189.756288 -14.762226)
					(mid 189.771167 -14.798147)
					(end 189.807088 -14.813026)
				)
				(arc
					(start 190.619888 -14.813026)
					(mid 190.655809 -14.798147)
					(end 190.670688 -14.762226)
				)
				(arc
					(start 190.670688 -14.559026)
					(mid 190.655809 -14.523105)
					(end 190.619888 -14.508226)
				)
			)
		)
	)
	(zone
		(layers "In1.Cu" "In2.Cu")
		(hatch none 0.5)
		(connect_pads
			(clearance 0)
		)
		(min_thickness 0.25)
		(keepout
			(tracks not_allowed)
			(vias allowed)
			(pads allowed)
			(copperpour not_allowed)
			(footprints allowed)
		)
		(placement
			(enabled no)
			(sheetname "")
		)
		(fill yes
			(thermal_gap 0.5)
			(thermal_bridge_width 0.5)
			(island_removal_mode 0)
		)
		(polygon
			(pts
				(arc
					(start 352.778314 -245.067074)
					(mid 352.742393 -245.081953)
					(end 352.727514 -245.117874)
				)
				(arc
					(start 352.727514 -245.321074)
					(mid 352.742393 -245.356995)
					(end 352.778314 -245.371874)
				)
				(arc
					(start 353.591114 -245.371874)
					(mid 353.627035 -245.356995)
					(end 353.641914 -245.321074)
				)
				(arc
					(start 353.641914 -245.117874)
					(mid 353.627035 -245.081953)
					(end 353.591114 -245.067074)
				)
			)
		)
	)
	(zone
		(layers "In1.Cu" "In2.Cu")
		(hatch none 0.5)
		(connect_pads
			(clearance 0)
		)
		(min_thickness 0.25)
		(keepout
			(tracks not_allowed)
			(vias allowed)
			(pads allowed)
			(copperpour not_allowed)
			(footprints allowed)
		)
		(placement
			(enabled no)
			(sheetname "")
		)
		(fill yes
			(thermal_gap 0.5)
			(thermal_bridge_width 0.5)
			(island_removal_mode 0)
		)
		(polygon
			(pts
				(arc
					(start 321.228212 -14.508226)
					(mid 321.192291 -14.523105)
					(end 321.177412 -14.559026)
				)
				(arc
					(start 321.177412 -14.762226)
					(mid 321.192291 -14.798147)
					(end 321.228212 -14.813026)
				)
				(arc
					(start 322.041012 -14.813026)
					(mid 322.076933 -14.798147)
					(end 322.091812 -14.762226)
				)
				(arc
					(start 322.091812 -14.559026)
					(mid 322.076933 -14.523105)
					(end 322.041012 -14.508226)
				)
			)
		)
	)
	(zone
		(layers "In1.Cu" "In2.Cu")
		(hatch none 0.5)
		(connect_pads
			(clearance 0)
		)
		(min_thickness 0.25)
		(keepout
			(tracks not_allowed)
			(vias allowed)
			(pads allowed)
			(copperpour not_allowed)
			(footprints allowed)
		)
		(placement
			(enabled no)
			(sheetname "")
		)
		(fill yes
			(thermal_gap 0.5)
			(thermal_bridge_width 0.5)
			(island_removal_mode 0)
		)
		(polygon
			(pts
				(xy 60.393834 -128.33985) (xy 62.756034 -128.33985) (xy 62.756034 -131.54025) (xy 60.393834 -131.54025)
			)
		)
	)
	(zone
		(layers "In1.Cu" "In2.Cu")
		(hatch none 0.5)
		(connect_pads
			(clearance 0)
		)
		(min_thickness 0.25)
		(keepout
			(tracks not_allowed)
			(vias allowed)
			(pads allowed)
			(copperpour not_allowed)
			(footprints allowed)
		)
		(placement
			(enabled no)
			(sheetname "")
		)
		(fill yes
			(thermal_gap 0.5)
			(thermal_bridge_width 0.5)
			(island_removal_mode 0)
		)
		(polygon
			(pts
				(arc
					(start 189.807088 -130.06705)
					(mid 189.771167 -130.081929)
					(end 189.756288 -130.11785)
				)
				(arc
					(start 189.756288 -130.32105)
					(mid 189.771167 -130.356971)
					(end 189.807088 -130.37185)
				)
				(arc
					(start 190.619888 -130.37185)
					(mid 190.655809 -130.356971)
					(end 190.670688 -130.32105)
				)
				(arc
					(start 190.670688 -130.11785)
					(mid 190.655809 -130.081929)
					(end 190.619888 -130.06705)
				)
			)
		)
	)
	(zone
		(layers "In1.Cu" "In2.Cu")
		(hatch none 0.5)
		(connect_pads
			(clearance 0)
		)
		(min_thickness 0.25)
		(keepout
			(tracks not_allowed)
			(vias allowed)
			(pads allowed)
			(copperpour not_allowed)
			(footprints allowed)
		)
		(placement
			(enabled no)
			(sheetname "")
		)
		(fill yes
			(thermal_gap 0.5)
			(thermal_bridge_width 0.5)
			(island_removal_mode 0)
		)
		(polygon
			(pts
				(xy 357.744014 -247.149874) (xy 360.106214 -247.149874) (xy 360.106214 -250.350274) (xy 357.744014 -250.350274)
			)
		)
	)
	(zone
		(layers "In1.Cu" "In2.Cu")
		(hatch none 0.5)
		(connect_pads
			(clearance 0)
		)
		(min_thickness 0.25)
		(keepout
			(tracks not_allowed)
			(vias allowed)
			(pads allowed)
			(copperpour not_allowed)
			(footprints allowed)
		)
		(placement
			(enabled no)
			(sheetname "")
		)
		(fill yes
			(thermal_gap 0.5)
			(thermal_bridge_width 0.5)
			(island_removal_mode 0)
		)
		(polygon
			(pts
				(arc
					(start 321.228212 -130.06705)
					(mid 321.192291 -130.081929)
					(end 321.177412 -130.11785)
				)
				(arc
					(start 321.177412 -130.32105)
					(mid 321.192291 -130.356971)
					(end 321.228212 -130.37185)
				)
				(arc
					(start 322.041012 -130.37185)
					(mid 322.076933 -130.356971)
					(end 322.091812 -130.32105)
				)
				(arc
					(start 322.091812 -130.11785)
					(mid 322.076933 -130.081929)
					(end 322.041012 -130.06705)
				)
			)
		)
	)
	(zone
		(layers "In1.Cu" "In2.Cu")
		(hatch none 0.5)
		(connect_pads
			(clearance 0)
		)
		(min_thickness 0.25)
		(keepout
			(tracks not_allowed)
			(vias allowed)
			(pads allowed)
			(copperpour not_allowed)
			(footprints allowed)
		)
		(placement
			(enabled no)
			(sheetname "")
		)
		(fill yes
			(thermal_gap 0.5)
			(thermal_bridge_width 0.5)
			(island_removal_mode 0)
		)
		(polygon
			(pts
				(arc
					(start 415.878264 -14.508226)
					(mid 415.842343 -14.523105)
					(end 415.827464 -14.559026)
				)
				(arc
					(start 415.827464 -14.762226)
					(mid 415.842343 -14.798147)
					(end 415.878264 -14.813026)
				)
				(arc
					(start 416.691064 -14.813026)
					(mid 416.726985 -14.798147)
					(end 416.741864 -14.762226)
				)
				(arc
					(start 416.741864 -14.559026)
					(mid 416.726985 -14.523105)
					(end 416.691064 -14.508226)
				)
			)
		)
	)
	(zone
		(layers "In1.Cu" "In2.Cu")
		(hatch none 0.5)
		(connect_pads
			(clearance 0)
		)
		(min_thickness 0.25)
		(keepout
			(tracks not_allowed)
			(vias allowed)
			(pads allowed)
			(copperpour not_allowed)
			(footprints allowed)
		)
		(placement
			(enabled no)
			(sheetname "")
		)
		(fill yes
			(thermal_gap 0.5)
			(thermal_bridge_width 0.5)
			(island_removal_mode 0)
		)
		(polygon
			(pts
				(xy 420.843964 -247.149874) (xy 423.206164 -247.149874) (xy 423.206164 -250.350274) (xy 420.843964 -250.350274)
			)
		)
	)
	(zone
		(layers "In1.Cu" "In2.Cu")
		(hatch none 0.5)
		(connect_pads
			(clearance 0)
		)
		(min_thickness 0.25)
		(keepout
			(tracks not_allowed)
			(vias allowed)
			(pads allowed)
			(copperpour not_allowed)
			(footprints allowed)
		)
		(placement
			(enabled no)
			(sheetname "")
		)
		(fill yes
			(thermal_gap 0.5)
			(thermal_bridge_width 0.5)
			(island_removal_mode 0)
		)
		(polygon
			(pts
				(xy 389.293862 -13.339826) (xy 391.656062 -13.339826) (xy 391.656062 -16.540226) (xy 389.293862 -16.540226)
			)
		)
	)
	(zone
		(layers "In1.Cu" "In2.Cu")
		(hatch none 0.5)
		(connect_pads
			(clearance 0)
		)
		(min_thickness 0.25)
		(keepout
			(tracks not_allowed)
			(vias allowed)
			(pads allowed)
			(copperpour not_allowed)
			(footprints allowed)
		)
		(placement
			(enabled no)
			(sheetname "")
		)
		(fill yes
			(thermal_gap 0.5)
			(thermal_bridge_width 0.5)
			(island_removal_mode 0)
		)
		(polygon
			(pts
				(xy 123.493784 -132.14985) (xy 125.855984 -132.14985) (xy 125.855984 -135.35025) (xy 123.493784 -135.35025)
			)
		)
	)
	(zone
		(layers "In1.Cu" "In2.Cu")
		(hatch none 0.5)
		(connect_pads
			(clearance 0)
		)
		(min_thickness 0.25)
		(keepout
			(tracks not_allowed)
			(vias allowed)
			(pads allowed)
			(copperpour not_allowed)
			(footprints allowed)
		)
		(placement
			(enabled no)
			(sheetname "")
		)
		(fill yes
			(thermal_gap 0.5)
			(thermal_bridge_width 0.5)
			(island_removal_mode 0)
		)
		(polygon
			(pts
				(xy 326.193912 -247.149874) (xy 328.556112 -247.149874) (xy 328.556112 -250.350274) (xy 326.193912 -250.350274)
			)
		)
	)
	(zone
		(layers "In1.Cu" "In2.Cu")
		(hatch none 0.5)
		(connect_pads
			(clearance 0)
		)
		(min_thickness 0.25)
		(keepout
			(tracks not_allowed)
			(vias allowed)
			(pads allowed)
			(copperpour not_allowed)
			(footprints allowed)
		)
		(placement
			(enabled no)
			(sheetname "")
		)
		(fill yes
			(thermal_gap 0.5)
			(thermal_bridge_width 0.5)
			(island_removal_mode 0)
		)
		(polygon
			(pts
				(xy 60.393834 -17.149826) (xy 62.756034 -17.149826) (xy 62.756034 -20.350226) (xy 60.393834 -20.350226)
			)
		)
	)
	(zone
		(layers "In1.Cu" "In2.Cu")
		(hatch none 0.5)
		(connect_pads
			(clearance 0)
		)
		(min_thickness 0.25)
		(keepout
			(tracks not_allowed)
			(vias allowed)
			(pads allowed)
			(copperpour not_allowed)
			(footprints allowed)
		)
		(placement
			(enabled no)
			(sheetname "")
		)
		(fill yes
			(thermal_gap 0.5)
			(thermal_bridge_width 0.5)
			(island_removal_mode 0)
		)
		(polygon
			(pts
				(xy 28.843986 -247.149874) (xy 31.206186 -247.149874) (xy 31.206186 -250.350274) (xy 28.843986 -250.350274)
			)
		)
	)
	(zone
		(layers "In1.Cu" "In2.Cu")
		(hatch none 0.5)
		(connect_pads
			(clearance 0)
		)
		(min_thickness 0.25)
		(keepout
			(tracks not_allowed)
			(vias allowed)
			(pads allowed)
			(copperpour not_allowed)
			(footprints allowed)
		)
		(placement
			(enabled no)
			(sheetname "")
		)
		(fill yes
			(thermal_gap 0.5)
			(thermal_bridge_width 0.5)
			(island_removal_mode 0)
		)
		(polygon
			(pts
				(xy 28.843986 -13.339826) (xy 31.206186 -13.339826) (xy 31.206186 -16.540226) (xy 28.843986 -16.540226)
			)
		)
	)
	(zone
		(layers "In1.Cu" "In2.Cu")
		(hatch none 0.5)
		(connect_pads
			(clearance 0)
		)
		(min_thickness 0.25)
		(keepout
			(tracks not_allowed)
			(vias allowed)
			(pads allowed)
			(copperpour not_allowed)
			(footprints allowed)
		)
		(placement
			(enabled no)
			(sheetname "")
		)
		(fill yes
			(thermal_gap 0.5)
			(thermal_bridge_width 0.5)
			(island_removal_mode 0)
		)
		(polygon
			(pts
				(xy 357.744014 -132.14985) (xy 360.106214 -132.14985) (xy 360.106214 -135.35025) (xy 357.744014 -135.35025)
			)
		)
	)
	(zone
		(layers "In1.Cu" "In2.Cu")
		(hatch none 0.5)
		(connect_pads
			(clearance 0)
		)
		(min_thickness 0.25)
		(keepout
			(tracks not_allowed)
			(vias allowed)
			(pads allowed)
			(copperpour not_allowed)
			(footprints allowed)
		)
		(placement
			(enabled no)
			(sheetname "")
		)
		(fill yes
			(thermal_gap 0.5)
			(thermal_bridge_width 0.5)
			(island_removal_mode 0)
		)
		(polygon
			(pts
				(xy 123.493784 -243.339874) (xy 125.855984 -243.339874) (xy 125.855984 -246.540274) (xy 123.493784 -246.540274)
			)
		)
	)
	(zone
		(layers "In1.Cu" "In2.Cu")
		(hatch none 0.5)
		(connect_pads
			(clearance 0)
		)
		(min_thickness 0.25)
		(keepout
			(tracks not_allowed)
			(vias allowed)
			(pads allowed)
			(copperpour not_allowed)
			(footprints allowed)
		)
		(placement
			(enabled no)
			(sheetname "")
		)
		(fill yes
			(thermal_gap 0.5)
			(thermal_bridge_width 0.5)
			(island_removal_mode 0)
		)
		(polygon
			(pts
				(xy 186.593988 -128.33985) (xy 188.956188 -128.33985) (xy 188.956188 -131.54025) (xy 186.593988 -131.54025)
			)
		)
	)
	(zone
		(layers "In1.Cu" "In2.Cu")
		(hatch none 0.5)
		(connect_pads
			(clearance 0)
		)
		(min_thickness 0.25)
		(keepout
			(tracks not_allowed)
			(vias allowed)
			(pads allowed)
			(copperpour not_allowed)
			(footprints allowed)
		)
		(placement
			(enabled no)
			(sheetname "")
		)
		(fill yes
			(thermal_gap 0.5)
			(thermal_bridge_width 0.5)
			(island_removal_mode 0)
		)
		(polygon
			(pts
				(xy 420.843964 -132.14985) (xy 423.206164 -132.14985) (xy 423.206164 -135.35025) (xy 420.843964 -135.35025)
			)
		)
	)
	(zone
		(layers "In1.Cu" "In2.Cu")
		(hatch none 0.5)
		(connect_pads
			(clearance 0)
		)
		(min_thickness 0.25)
		(keepout
			(tracks not_allowed)
			(vias allowed)
			(pads allowed)
			(copperpour not_allowed)
			(footprints allowed)
		)
		(placement
			(enabled no)
			(sheetname "")
		)
		(fill yes
			(thermal_gap 0.5)
			(thermal_bridge_width 0.5)
			(island_removal_mode 0)
		)
		(polygon
			(pts
				(xy 186.593988 -13.339826) (xy 188.956188 -13.339826) (xy 188.956188 -16.540226) (xy 186.593988 -16.540226)
			)
		)
	)
	(zone
		(layers "In1.Cu" "In2.Cu")
		(hatch none 0.5)
		(connect_pads
			(clearance 0)
		)
		(min_thickness 0.25)
		(keepout
			(tracks not_allowed)
			(vias allowed)
			(pads allowed)
			(copperpour not_allowed)
			(footprints allowed)
		)
		(placement
			(enabled no)
			(sheetname "")
		)
		(fill yes
			(thermal_gap 0.5)
			(thermal_bridge_width 0.5)
			(island_removal_mode 0)
		)
		(polygon
			(pts
				(xy 60.393834 -247.149874) (xy 62.756034 -247.149874) (xy 62.756034 -250.350274) (xy 60.393834 -250.350274)
			)
		)
	)
	(zone
		(layers "In1.Cu" "In2.Cu")
		(hatch none 0.5)
		(connect_pads
			(clearance 0)
		)
		(min_thickness 0.25)
		(keepout
			(tracks not_allowed)
			(vias allowed)
			(pads allowed)
			(copperpour not_allowed)
			(footprints allowed)
		)
		(placement
			(enabled no)
			(sheetname "")
		)
		(fill yes
			(thermal_gap 0.5)
			(thermal_bridge_width 0.5)
			(island_removal_mode 0)
		)
		(polygon
			(pts
				(xy 91.943936 -128.33985) (xy 94.306136 -128.33985) (xy 94.306136 -131.54025) (xy 91.943936 -131.54025)
			)
		)
	)
	(zone
		(layers "In1.Cu" "In2.Cu")
		(hatch none 0.5)
		(connect_pads
			(clearance 0)
		)
		(min_thickness 0.25)
		(keepout
			(tracks not_allowed)
			(vias allowed)
			(pads allowed)
			(copperpour not_allowed)
			(footprints allowed)
		)
		(placement
			(enabled no)
			(sheetname "")
		)
		(fill yes
			(thermal_gap 0.5)
			(thermal_bridge_width 0.5)
			(island_removal_mode 0)
		)
		(polygon
			(pts
				(arc
					(start 63.606934 -244.508274)
					(mid 63.571013 -244.523153)
					(end 63.556134 -244.559074)
				)
				(arc
					(start 63.556134 -244.762274)
					(mid 63.571013 -244.798195)
					(end 63.606934 -244.813074)
				)
				(arc
					(start 64.419734 -244.813074)
					(mid 64.455655 -244.798195)
					(end 64.470534 -244.762274)
				)
				(arc
					(start 64.470534 -244.559074)
					(mid 64.455655 -244.523153)
					(end 64.419734 -244.508274)
				)
			)
		)
	)
	(zone
		(layers "In1.Cu" "In2.Cu")
		(hatch none 0.5)
		(connect_pads
			(clearance 0)
		)
		(min_thickness 0.25)
		(keepout
			(tracks not_allowed)
			(vias allowed)
			(pads allowed)
			(copperpour not_allowed)
			(footprints allowed)
		)
		(placement
			(enabled no)
			(sheetname "")
		)
		(fill yes
			(thermal_gap 0.5)
			(thermal_bridge_width 0.5)
			(island_removal_mode 0)
		)
		(polygon
			(pts
				(xy 28.843986 -128.33985) (xy 31.206186 -128.33985) (xy 31.206186 -131.54025) (xy 28.843986 -131.54025)
			)
		)
	)
	(zone
		(layers "In1.Cu" "In2.Cu")
		(hatch none 0.5)
		(connect_pads
			(clearance 0)
		)
		(min_thickness 0.25)
		(keepout
			(tracks not_allowed)
			(vias allowed)
			(pads allowed)
			(copperpour not_allowed)
			(footprints allowed)
		)
		(placement
			(enabled no)
			(sheetname "")
		)
		(fill yes
			(thermal_gap 0.5)
			(thermal_bridge_width 0.5)
			(island_removal_mode 0)
		)
		(polygon
			(pts
				(arc
					(start 352.778314 -129.50825)
					(mid 352.742393 -129.523129)
					(end 352.727514 -129.55905)
				)
				(arc
					(start 352.727514 -129.76225)
					(mid 352.742393 -129.798171)
					(end 352.778314 -129.81305)
				)
				(arc
					(start 353.591114 -129.81305)
					(mid 353.627035 -129.798171)
					(end 353.641914 -129.76225)
				)
				(arc
					(start 353.641914 -129.55905)
					(mid 353.627035 -129.523129)
					(end 353.591114 -129.50825)
				)
			)
		)
	)
	(zone
		(layers "In1.Cu" "In2.Cu")
		(hatch none 0.5)
		(connect_pads
			(clearance 0)
		)
		(min_thickness 0.25)
		(keepout
			(tracks not_allowed)
			(vias allowed)
			(pads allowed)
			(copperpour not_allowed)
			(footprints allowed)
		)
		(placement
			(enabled no)
			(sheetname "")
		)
		(fill yes
			(thermal_gap 0.5)
			(thermal_bridge_width 0.5)
			(island_removal_mode 0)
		)
		(polygon
			(pts
				(arc
					(start 189.807088 -15.067026)
					(mid 189.771167 -15.081905)
					(end 189.756288 -15.117826)
				)
				(arc
					(start 189.756288 -15.321026)
					(mid 189.771167 -15.356947)
					(end 189.807088 -15.371826)
				)
				(arc
					(start 190.619888 -15.371826)
					(mid 190.655809 -15.356947)
					(end 190.670688 -15.321026)
				)
				(arc
					(start 190.670688 -15.117826)
					(mid 190.655809 -15.081905)
					(end 190.619888 -15.067026)
				)
			)
		)
	)
	(zone
		(layers "In1.Cu" "In2.Cu")
		(hatch none 0.5)
		(connect_pads
			(clearance 0)
		)
		(min_thickness 0.25)
		(keepout
			(tracks not_allowed)
			(vias allowed)
			(pads allowed)
			(copperpour not_allowed)
			(footprints allowed)
		)
		(placement
			(enabled no)
			(sheetname "")
		)
		(fill yes
			(thermal_gap 0.5)
			(thermal_bridge_width 0.5)
			(island_removal_mode 0)
		)
		(polygon
			(pts
				(xy 420.843964 -17.149826) (xy 423.206164 -17.149826) (xy 423.206164 -20.350226) (xy 420.843964 -20.350226)
			)
		)
	)
	(zone
		(layers "In1.Cu" "In2.Cu")
		(hatch none 0.5)
		(connect_pads
			(clearance 0)
		)
		(min_thickness 0.25)
		(keepout
			(tracks not_allowed)
			(vias allowed)
			(pads allowed)
			(copperpour not_allowed)
			(footprints allowed)
		)
		(placement
			(enabled no)
			(sheetname "")
		)
		(fill yes
			(thermal_gap 0.5)
			(thermal_bridge_width 0.5)
			(island_removal_mode 0)
		)
		(polygon
			(pts
				(arc
					(start 158.256986 -14.508226)
					(mid 158.221065 -14.523105)
					(end 158.206186 -14.559026)
				)
				(arc
					(start 158.206186 -14.762226)
					(mid 158.221065 -14.798147)
					(end 158.256986 -14.813026)
				)
				(arc
					(start 159.069786 -14.813026)
					(mid 159.105707 -14.798147)
					(end 159.120586 -14.762226)
				)
				(arc
					(start 159.120586 -14.559026)
					(mid 159.105707 -14.523105)
					(end 159.069786 -14.508226)
				)
			)
		)
	)
	(zone
		(layers "In1.Cu" "In2.Cu")
		(hatch none 0.5)
		(connect_pads
			(clearance 0)
		)
		(min_thickness 0.25)
		(keepout
			(tracks not_allowed)
			(vias allowed)
			(pads allowed)
			(copperpour not_allowed)
			(footprints allowed)
		)
		(placement
			(enabled no)
			(sheetname "")
		)
		(fill yes
			(thermal_gap 0.5)
			(thermal_bridge_width 0.5)
			(island_removal_mode 0)
		)
		(polygon
			(pts
				(xy 91.943936 -17.149826) (xy 94.306136 -17.149826) (xy 94.306136 -20.350226) (xy 91.943936 -20.350226)
			)
		)
	)
	(zone
		(layers "In1.Cu" "In2.Cu")
		(hatch none 0.5)
		(connect_pads
			(clearance 0)
		)
		(min_thickness 0.25)
		(keepout
			(tracks not_allowed)
			(vias allowed)
			(pads allowed)
			(copperpour not_allowed)
			(footprints allowed)
		)
		(placement
			(enabled no)
			(sheetname "")
		)
		(fill yes
			(thermal_gap 0.5)
			(thermal_bridge_width 0.5)
			(island_removal_mode 0)
		)
		(polygon
			(pts
				(arc
					(start 158.256986 -129.50825)
					(mid 158.221065 -129.523129)
					(end 158.206186 -129.55905)
				)
				(arc
					(start 158.206186 -129.76225)
					(mid 158.221065 -129.798171)
					(end 158.256986 -129.81305)
				)
				(arc
					(start 159.069786 -129.81305)
					(mid 159.105707 -129.798171)
					(end 159.120586 -129.76225)
				)
				(arc
					(start 159.120586 -129.55905)
					(mid 159.105707 -129.523129)
					(end 159.069786 -129.50825)
				)
			)
		)
	)
	(zone
		(layers "In1.Cu" "In3.Cu" "In4.Cu" "In6.Cu")
		(hatch none 0.5)
		(connect_pads
			(clearance 0)
		)
		(min_thickness 0.25)
		(keepout
			(tracks not_allowed)
			(vias allowed)
			(pads allowed)
			(copperpour not_allowed)
			(footprints allowed)
		)
		(placement
			(enabled no)
			(sheetname "")
		)
		(fill yes
			(thermal_gap 0.5)
			(thermal_bridge_width 0.5)
			(island_removal_mode 0)
		)
		(polygon
			(pts
				(arc
					(start 287.83661 -206.843122)
					(mid 288.38525 -206.294482)
					(end 287.83661 -205.745842)
				)
				(arc
					(start 286.436562 -205.745842)
					(mid 285.887922 -206.294482)
					(end 286.436562 -206.843122)
				)
			)
		)
	)
	(zone
		(layers "In1.Cu" "In3.Cu" "In4.Cu" "In6.Cu")
		(hatch none 0.5)
		(connect_pads
			(clearance 0)
		)
		(min_thickness 0.25)
		(keepout
			(tracks not_allowed)
			(vias allowed)
			(pads allowed)
			(copperpour not_allowed)
			(footprints allowed)
		)
		(placement
			(enabled no)
			(sheetname "")
		)
		(fill yes
			(thermal_gap 0.5)
			(thermal_bridge_width 0.5)
			(island_removal_mode 0)
		)
		(polygon
			(pts
				(arc
					(start 323.951346 -132.922264)
					(mid 324.43674 -132.437251)
					(end 323.9516 -131.951984)
				)
				(arc
					(start 322.6816 -131.951984)
					(mid 322.19646 -132.437124)
					(end 322.6816 -132.922264)
				)
			)
		)
	)
	(zone
		(layers "In1.Cu" "In3.Cu" "In4.Cu" "In6.Cu")
		(hatch none 0.5)
		(connect_pads
			(clearance 0)
		)
		(min_thickness 0.25)
		(keepout
			(tracks not_allowed)
			(vias allowed)
			(pads allowed)
			(copperpour not_allowed)
			(footprints allowed)
		)
		(placement
			(enabled no)
			(sheetname "")
		)
		(fill yes
			(thermal_gap 0.5)
			(thermal_bridge_width 0.5)
			(island_removal_mode 0)
		)
		(polygon
			(pts
				(arc
					(start 287.83661 -210.443064)
					(mid 288.38525 -209.894424)
					(end 287.83661 -209.345784)
				)
				(arc
					(start 286.436562 -209.345784)
					(mid 285.887922 -209.894424)
					(end 286.436562 -210.443064)
				)
			)
		)
	)
	(zone
		(layers "In1.Cu" "In3.Cu" "In4.Cu" "In6.Cu")
		(hatch none 0.5)
		(connect_pads
			(clearance 0)
		)
		(min_thickness 0.25)
		(keepout
			(tracks not_allowed)
			(vias allowed)
			(pads allowed)
			(copperpour not_allowed)
			(footprints allowed)
		)
		(placement
			(enabled no)
			(sheetname "")
		)
		(fill yes
			(thermal_gap 0.5)
			(thermal_bridge_width 0.5)
			(island_removal_mode 0)
		)
		(polygon
			(pts
				(arc
					(start 279.636728 -212.243162)
					(mid 280.185368 -211.694522)
					(end 279.636728 -211.145882)
				)
				(arc
					(start 278.23668 -211.145882)
					(mid 277.68804 -211.694522)
					(end 278.23668 -212.243162)
				)
			)
		)
	)
	(zone
		(layers "In1.Cu" "In3.Cu" "In4.Cu" "In6.Cu")
		(hatch none 0.5)
		(connect_pads
			(clearance 0)
		)
		(min_thickness 0.25)
		(keepout
			(tracks not_allowed)
			(vias allowed)
			(pads allowed)
			(copperpour not_allowed)
			(footprints allowed)
		)
		(placement
			(enabled no)
			(sheetname "")
		)
		(fill yes
			(thermal_gap 0.5)
			(thermal_bridge_width 0.5)
			(island_removal_mode 0)
		)
		(polygon
			(pts
				(arc
					(start 286.836612 -139.843002)
					(mid 287.385252 -139.294362)
					(end 286.836612 -138.745722)
				)
				(arc
					(start 285.436564 -138.745722)
					(mid 284.887924 -139.294362)
					(end 285.436564 -139.843002)
				)
			)
		)
	)
	(zone
		(layers "In1.Cu" "In3.Cu" "In4.Cu" "In6.Cu")
		(hatch none 0.5)
		(connect_pads
			(clearance 0)
		)
		(min_thickness 0.25)
		(keepout
			(tracks not_allowed)
			(vias allowed)
			(pads allowed)
			(copperpour not_allowed)
			(footprints allowed)
		)
		(placement
			(enabled no)
			(sheetname "")
		)
		(fill yes
			(thermal_gap 0.5)
			(thermal_bridge_width 0.5)
			(island_removal_mode 0)
		)
		(polygon
			(pts
				(arc
					(start 280.636726 -181.64302)
					(mid 281.185366 -181.09438)
					(end 280.636726 -180.54574)
				)
				(arc
					(start 279.236678 -180.54574)
					(mid 278.688038 -181.09438)
					(end 279.236678 -181.64302)
				)
			)
		)
	)
	(zone
		(layers "In1.Cu" "In3.Cu" "In4.Cu" "In6.Cu")
		(hatch none 0.5)
		(connect_pads
			(clearance 0)
		)
		(min_thickness 0.25)
		(keepout
			(tracks not_allowed)
			(vias allowed)
			(pads allowed)
			(copperpour not_allowed)
			(footprints allowed)
		)
		(placement
			(enabled no)
			(sheetname "")
		)
		(fill yes
			(thermal_gap 0.5)
			(thermal_bridge_width 0.5)
			(island_removal_mode 0)
		)
		(polygon
			(pts
				(arc
					(start 418.724842 -248.115328)
					(mid 418.239829 -247.629934)
					(end 417.754562 -248.115074)
				)
				(arc
					(start 417.754562 -249.385074)
					(mid 418.239702 -249.870214)
					(end 418.724842 -249.385074)
				)
			)
		)
	)
	(zone
		(layers "In1.Cu" "In3.Cu" "In4.Cu" "In6.Cu")
		(hatch none 0.5)
		(connect_pads
			(clearance 0)
		)
		(min_thickness 0.25)
		(keepout
			(tracks not_allowed)
			(vias allowed)
			(pads allowed)
			(copperpour not_allowed)
			(footprints allowed)
		)
		(placement
			(enabled no)
			(sheetname "")
		)
		(fill yes
			(thermal_gap 0.5)
			(thermal_bridge_width 0.5)
			(island_removal_mode 0)
		)
		(polygon
			(pts
				(arc
					(start 286.836612 -223.042988)
					(mid 287.385252 -222.494348)
					(end 286.836612 -221.945708)
				)
				(arc
					(start 285.436564 -221.945708)
					(mid 284.887924 -222.494348)
					(end 285.436564 -223.042988)
				)
			)
		)
	)
	(zone
		(layers "In1.Cu" "In3.Cu" "In4.Cu" "In6.Cu")
		(hatch none 0.5)
		(connect_pads
			(clearance 0)
		)
		(min_thickness 0.25)
		(keepout
			(tracks not_allowed)
			(vias allowed)
			(pads allowed)
			(copperpour not_allowed)
			(footprints allowed)
		)
		(placement
			(enabled no)
			(sheetname "")
		)
		(fill yes
			(thermal_gap 0.5)
			(thermal_bridge_width 0.5)
			(island_removal_mode 0)
		)
		(polygon
			(pts
				(arc
					(start 279.636728 -139.843002)
					(mid 280.185368 -139.294362)
					(end 279.636728 -138.745722)
				)
				(arc
					(start 278.23668 -138.745722)
					(mid 277.68804 -139.294362)
					(end 278.23668 -139.843002)
				)
			)
		)
	)
	(zone
		(layers "In1.Cu" "In3.Cu" "In4.Cu" "In6.Cu")
		(hatch none 0.5)
		(connect_pads
			(clearance 0)
		)
		(min_thickness 0.25)
		(keepout
			(tracks not_allowed)
			(vias allowed)
			(pads allowed)
			(copperpour not_allowed)
			(footprints allowed)
		)
		(placement
			(enabled no)
			(sheetname "")
		)
		(fill yes
			(thermal_gap 0.5)
			(thermal_bridge_width 0.5)
			(island_removal_mode 0)
		)
		(polygon
			(pts
				(arc
					(start 287.83661 -239.243108)
					(mid 288.38525 -238.694468)
					(end 287.83661 -238.145828)
				)
				(arc
					(start 286.436562 -238.145828)
					(mid 285.887922 -238.694468)
					(end 286.436562 -239.243108)
				)
			)
		)
	)
	(zone
		(layers "In1.Cu" "In3.Cu" "In4.Cu" "In6.Cu")
		(hatch none 0.5)
		(connect_pads
			(clearance 0)
		)
		(min_thickness 0.25)
		(keepout
			(tracks not_allowed)
			(vias allowed)
			(pads allowed)
			(copperpour not_allowed)
			(footprints allowed)
		)
		(placement
			(enabled no)
			(sheetname "")
		)
		(fill yes
			(thermal_gap 0.5)
			(thermal_bridge_width 0.5)
			(island_removal_mode 0)
		)
		(polygon
			(pts
				(arc
					(start 210.548728 -73.999852)
					(mid 210.000088 -73.451212)
					(end 209.451448 -73.999852)
				)
				(arc
					(start 209.451448 -75.399646)
					(mid 209.999961 -75.94854)
					(end 210.548728 -75.3999)
				)
			)
		)
	)
	(zone
		(layers "In1.Cu" "In3.Cu" "In4.Cu" "In6.Cu")
		(hatch none 0.5)
		(connect_pads
			(clearance 0)
		)
		(min_thickness 0.25)
		(keepout
			(tracks not_allowed)
			(vias allowed)
			(pads allowed)
			(copperpour not_allowed)
			(footprints allowed)
		)
		(placement
			(enabled no)
			(sheetname "")
		)
		(fill yes
			(thermal_gap 0.5)
			(thermal_bridge_width 0.5)
			(island_removal_mode 0)
		)
		(polygon
			(pts
				(arc
					(start 414.527492 -244.444774)
					(mid 414.042352 -243.959634)
					(end 413.557212 -244.444774)
				)
				(arc
					(start 413.557212 -245.58752)
					(mid 414.042225 -246.072914)
					(end 414.527492 -245.587774)
				)
			)
		)
	)
	(zone
		(layers "In1.Cu" "In3.Cu" "In4.Cu" "In6.Cu")
		(hatch none 0.5)
		(connect_pads
			(clearance 0)
		)
		(min_thickness 0.25)
		(keepout
			(tracks not_allowed)
			(vias allowed)
			(pads allowed)
			(copperpour not_allowed)
			(footprints allowed)
		)
		(placement
			(enabled no)
			(sheetname "")
		)
		(fill yes
			(thermal_gap 0.5)
			(thermal_bridge_width 0.5)
			(island_removal_mode 0)
		)
		(polygon
			(pts
				(arc
					(start 223.148652 -76.399898)
					(mid 222.600012 -75.851258)
					(end 222.051372 -76.399898)
				)
				(arc
					(start 222.051372 -77.799692)
					(mid 222.599885 -78.348586)
					(end 223.148652 -77.799946)
				)
			)
		)
	)
	(zone
		(layers "In1.Cu" "In3.Cu" "In4.Cu" "In6.Cu")
		(hatch none 0.5)
		(connect_pads
			(clearance 0)
		)
		(min_thickness 0.25)
		(keepout
			(tracks not_allowed)
			(vias allowed)
			(pads allowed)
			(copperpour not_allowed)
			(footprints allowed)
		)
		(placement
			(enabled no)
			(sheetname "")
		)
		(fill yes
			(thermal_gap 0.5)
			(thermal_bridge_width 0.5)
			(island_removal_mode 0)
		)
		(polygon
			(pts
				(arc
					(start 286.836612 -219.443046)
					(mid 287.385252 -218.894406)
					(end 286.836612 -218.345766)
				)
				(arc
					(start 285.436564 -218.345766)
					(mid 284.887924 -218.894406)
					(end 285.436564 -219.443046)
				)
			)
		)
	)
	(zone
		(layers "In1.Cu" "In3.Cu" "In4.Cu" "In6.Cu")
		(hatch none 0.5)
		(connect_pads
			(clearance 0)
		)
		(min_thickness 0.25)
		(keepout
			(tracks not_allowed)
			(vias allowed)
			(pads allowed)
			(copperpour not_allowed)
			(footprints allowed)
		)
		(placement
			(enabled no)
			(sheetname "")
		)
		(fill yes
			(thermal_gap 0.5)
			(thermal_bridge_width 0.5)
			(island_removal_mode 0)
		)
		(polygon
			(pts
				(arc
					(start 476.964756 -13.14196)
					(mid 476.479362 -13.626973)
					(end 476.964502 -14.11224)
				)
				(arc
					(start 478.107502 -14.11224)
					(mid 478.592642 -13.6271)
					(end 478.107502 -13.14196)
				)
			)
		)
	)
	(zone
		(layers "In1.Cu" "In3.Cu" "In4.Cu" "In6.Cu")
		(hatch none 0.5)
		(connect_pads
			(clearance 0)
		)
		(min_thickness 0.25)
		(keepout
			(tracks not_allowed)
			(vias allowed)
			(pads allowed)
			(copperpour not_allowed)
			(footprints allowed)
		)
		(placement
			(enabled no)
			(sheetname "")
		)
		(fill yes
			(thermal_gap 0.5)
			(thermal_bridge_width 0.5)
			(island_removal_mode 0)
		)
		(polygon
			(pts
				(arc
					(start 32.994092 -248.115328)
					(mid 32.509079 -247.629934)
					(end 32.023812 -248.115074)
				)
				(arc
					(start 32.023812 -249.385074)
					(mid 32.508952 -249.870214)
					(end 32.994092 -249.385074)
				)
			)
		)
	)
	(zone
		(layers "In1.Cu" "In3.Cu" "In4.Cu" "In6.Cu")
		(hatch none 0.5)
		(connect_pads
			(clearance 0)
		)
		(min_thickness 0.25)
		(keepout
			(tracks not_allowed)
			(vias allowed)
			(pads allowed)
			(copperpour not_allowed)
			(footprints allowed)
		)
		(placement
			(enabled no)
			(sheetname "")
		)
		(fill yes
			(thermal_gap 0.5)
			(thermal_bridge_width 0.5)
			(island_removal_mode 0)
		)
		(polygon
			(pts
				(arc
					(start 127.64389 -18.11528)
					(mid 127.158877 -17.629886)
					(end 126.67361 -18.115026)
				)
				(arc
					(start 126.67361 -19.385026)
					(mid 127.15875 -19.870166)
					(end 127.64389 -19.385026)
				)
			)
		)
	)
	(zone
		(layers "In1.Cu" "In3.Cu" "In4.Cu" "In6.Cu")
		(hatch none 0.5)
		(connect_pads
			(clearance 0)
		)
		(min_thickness 0.25)
		(keepout
			(tracks not_allowed)
			(vias allowed)
			(pads allowed)
			(copperpour not_allowed)
			(footprints allowed)
		)
		(placement
			(enabled no)
			(sheetname "")
		)
		(fill yes
			(thermal_gap 0.5)
			(thermal_bridge_width 0.5)
			(island_removal_mode 0)
		)
		(polygon
			(pts
				(arc
					(start 450.151246 -132.922264)
					(mid 450.63664 -132.437251)
					(end 450.1515 -131.951984)
				)
				(arc
					(start 448.8815 -131.951984)
					(mid 448.39636 -132.437124)
					(end 448.8815 -132.922264)
				)
			)
		)
	)
	(zone
		(layers "In1.Cu" "In3.Cu" "In4.Cu" "In6.Cu")
		(hatch none 0.5)
		(connect_pads
			(clearance 0)
		)
		(min_thickness 0.25)
		(keepout
			(tracks not_allowed)
			(vias allowed)
			(pads allowed)
			(copperpour not_allowed)
			(footprints allowed)
		)
		(placement
			(enabled no)
			(sheetname "")
		)
		(fill yes
			(thermal_gap 0.5)
			(thermal_bridge_width 0.5)
			(island_removal_mode 0)
		)
		(polygon
			(pts
				(arc
					(start 279.236678 -136.943338)
					(mid 278.685498 -137.494518)
					(end 279.236678 -138.045698)
				)
				(arc
					(start 280.636726 -138.045698)
					(mid 281.187906 -137.494518)
					(end 280.636726 -136.943338)
				)
				(xy 279.236932 -136.943338)
			)
		)
	)
	(zone
		(layers "In1.Cu" "In3.Cu" "In4.Cu" "In6.Cu")
		(hatch none 0.5)
		(connect_pads
			(clearance 0)
		)
		(min_thickness 0.25)
		(keepout
			(tracks not_allowed)
			(vias allowed)
			(pads allowed)
			(copperpour not_allowed)
			(footprints allowed)
		)
		(placement
			(enabled no)
			(sheetname "")
		)
		(fill yes
			(thermal_gap 0.5)
			(thermal_bridge_width 0.5)
			(island_removal_mode 0)
		)
		(polygon
			(pts
				(arc
					(start 279.636728 -233.843068)
					(mid 280.185368 -233.294428)
					(end 279.636728 -232.745788)
				)
				(arc
					(start 278.23668 -232.745788)
					(mid 277.68804 -233.294428)
					(end 278.23668 -233.843068)
				)
			)
		)
	)
	(zone
		(layers "In1.Cu" "In3.Cu" "In4.Cu" "In6.Cu")
		(hatch none 0.5)
		(connect_pads
			(clearance 0)
		)
		(min_thickness 0.25)
		(keepout
			(tracks not_allowed)
			(vias allowed)
			(pads allowed)
			(copperpour not_allowed)
			(footprints allowed)
		)
		(placement
			(enabled no)
			(sheetname "")
		)
		(fill yes
			(thermal_gap 0.5)
			(thermal_bridge_width 0.5)
			(island_removal_mode 0)
		)
		(polygon
			(pts
				(arc
					(start 350.764856 -128.141984)
					(mid 350.279462 -128.626997)
					(end 350.764602 -129.112264)
				)
				(arc
					(start 351.907602 -129.112264)
					(mid 352.392742 -128.627124)
					(end 351.907602 -128.141984)
				)
			)
		)
	)
	(zone
		(layers "In1.Cu" "In3.Cu" "In4.Cu" "In6.Cu")
		(hatch none 0.5)
		(connect_pads
			(clearance 0)
		)
		(min_thickness 0.25)
		(keepout
			(tracks not_allowed)
			(vias allowed)
			(pads allowed)
			(copperpour not_allowed)
			(footprints allowed)
		)
		(placement
			(enabled no)
			(sheetname "")
		)
		(fill yes
			(thermal_gap 0.5)
			(thermal_bridge_width 0.5)
			(island_removal_mode 0)
		)
		(polygon
			(pts
				(arc
					(start 476.964756 -128.141984)
					(mid 476.479362 -128.626997)
					(end 476.964502 -129.112264)
				)
				(arc
					(start 478.107502 -129.112264)
					(mid 478.592642 -128.627124)
					(end 478.107502 -128.141984)
				)
			)
		)
	)
	(zone
		(layers "In1.Cu" "In3.Cu" "In4.Cu" "In6.Cu")
		(hatch none 0.5)
		(connect_pads
			(clearance 0)
		)
		(min_thickness 0.25)
		(keepout
			(tracks not_allowed)
			(vias allowed)
			(pads allowed)
			(copperpour not_allowed)
			(footprints allowed)
		)
		(placement
			(enabled no)
			(sheetname "")
		)
		(fill yes
			(thermal_gap 0.5)
			(thermal_bridge_width 0.5)
			(island_removal_mode 0)
		)
		(polygon
			(pts
				(arc
					(start 445.414654 -128.141984)
					(mid 444.92926 -128.626997)
					(end 445.4144 -129.112264)
				)
				(arc
					(start 446.5574 -129.112264)
					(mid 447.04254 -128.627124)
					(end 446.5574 -128.141984)
				)
			)
		)
	)
	(zone
		(layers "In1.Cu" "In3.Cu" "In4.Cu" "In6.Cu")
		(hatch none 0.5)
		(connect_pads
			(clearance 0)
		)
		(min_thickness 0.25)
		(keepout
			(tracks not_allowed)
			(vias allowed)
			(pads allowed)
			(copperpour not_allowed)
			(footprints allowed)
		)
		(placement
			(enabled no)
			(sheetname "")
		)
		(fill yes
			(thermal_gap 0.5)
			(thermal_bridge_width 0.5)
			(island_removal_mode 0)
		)
		(polygon
			(pts
				(arc
					(start 413.864806 -13.14196)
					(mid 413.379412 -13.626973)
					(end 413.864552 -14.11224)
				)
				(arc
					(start 415.007552 -14.11224)
					(mid 415.492692 -13.6271)
					(end 415.007552 -13.14196)
				)
			)
		)
	)
	(zone
		(layers "In1.Cu" "In3.Cu" "In4.Cu" "In6.Cu")
		(hatch none 0.5)
		(connect_pads
			(clearance 0)
		)
		(min_thickness 0.25)
		(keepout
			(tracks not_allowed)
			(vias allowed)
			(pads allowed)
			(copperpour not_allowed)
			(footprints allowed)
		)
		(placement
			(enabled no)
			(sheetname "")
		)
		(fill yes
			(thermal_gap 0.5)
			(thermal_bridge_width 0.5)
			(island_removal_mode 0)
		)
		(polygon
			(pts
				(arc
					(start 279.636728 -201.443082)
					(mid 280.185368 -200.894442)
					(end 279.636728 -200.345802)
				)
				(arc
					(start 278.23668 -200.345802)
					(mid 277.68804 -200.894442)
					(end 278.23668 -201.443082)
				)
			)
		)
	)
	(zone
		(layers "In1.Cu" "In3.Cu" "In4.Cu" "In6.Cu")
		(hatch none 0.5)
		(connect_pads
			(clearance 0)
		)
		(min_thickness 0.25)
		(keepout
			(tracks not_allowed)
			(vias allowed)
			(pads allowed)
			(copperpour not_allowed)
			(footprints allowed)
		)
		(placement
			(enabled no)
			(sheetname "")
		)
		(fill yes
			(thermal_gap 0.5)
			(thermal_bridge_width 0.5)
			(island_removal_mode 0)
		)
		(polygon
			(pts
				(arc
					(start 286.836612 -136.24306)
					(mid 287.385252 -135.69442)
					(end 286.836612 -135.14578)
				)
				(arc
					(start 285.436564 -135.14578)
					(mid 284.887924 -135.69442)
					(end 285.436564 -136.24306)
				)
			)
		)
	)
	(zone
		(layers "In1.Cu" "In3.Cu" "In4.Cu" "In6.Cu")
		(hatch none 0.5)
		(connect_pads
			(clearance 0)
		)
		(min_thickness 0.25)
		(keepout
			(tracks not_allowed)
			(vias allowed)
			(pads allowed)
			(copperpour not_allowed)
			(footprints allowed)
		)
		(placement
			(enabled no)
			(sheetname "")
		)
		(fill yes
			(thermal_gap 0.5)
			(thermal_bridge_width 0.5)
			(island_removal_mode 0)
		)
		(polygon
			(pts
				(arc
					(start 219.54871 -76.399898)
					(mid 219.00007 -75.851258)
					(end 218.45143 -76.399898)
				)
				(arc
					(start 218.45143 -77.799692)
					(mid 218.999943 -78.348586)
					(end 219.54871 -77.799946)
				)
			)
		)
	)
	(zone
		(layers "In1.Cu" "In3.Cu" "In4.Cu" "In6.Cu")
		(hatch none 0.5)
		(connect_pads
			(clearance 0)
		)
		(min_thickness 0.25)
		(keepout
			(tracks not_allowed)
			(vias allowed)
			(pads allowed)
			(copperpour not_allowed)
			(footprints allowed)
		)
		(placement
			(enabled no)
			(sheetname "")
		)
		(fill yes
			(thermal_gap 0.5)
			(thermal_bridge_width 0.5)
			(island_removal_mode 0)
		)
		(polygon
			(pts
				(arc
					(start 351.427542 -244.317774)
					(mid 350.942402 -243.832634)
					(end 350.457262 -244.317774)
				)
				(arc
					(start 350.457262 -245.46052)
					(mid 350.942275 -245.945914)
					(end 351.427542 -245.460774)
				)
			)
		)
	)
	(zone
		(layers "In1.Cu" "In3.Cu" "In4.Cu" "In6.Cu")
		(hatch none 0.5)
		(connect_pads
			(clearance 0)
		)
		(min_thickness 0.25)
		(keepout
			(tracks not_allowed)
			(vias allowed)
			(pads allowed)
			(copperpour not_allowed)
			(footprints allowed)
		)
		(placement
			(enabled no)
			(sheetname "")
		)
		(fill yes
			(thermal_gap 0.5)
			(thermal_bridge_width 0.5)
			(island_removal_mode 0)
		)
		(polygon
			(pts
				(arc
					(start 221.348808 -77.600302)
					(mid 220.800295 -77.051408)
					(end 220.251528 -77.600048)
				)
				(arc
					(start 220.251528 -78.999842)
					(mid 220.800168 -79.548482)
					(end 221.348808 -78.999842)
				)
			)
		)
	)
	(zone
		(layers "In1.Cu" "In3.Cu" "In4.Cu" "In6.Cu")
		(hatch none 0.5)
		(connect_pads
			(clearance 0)
		)
		(min_thickness 0.25)
		(keepout
			(tracks not_allowed)
			(vias allowed)
			(pads allowed)
			(copperpour not_allowed)
			(footprints allowed)
		)
		(placement
			(enabled no)
			(sheetname "")
		)
		(fill yes
			(thermal_gap 0.5)
			(thermal_bridge_width 0.5)
			(island_removal_mode 0)
		)
		(polygon
			(pts
				(arc
					(start 97.870772 -129.419604)
					(mid 97.385759 -128.93421)
					(end 96.900492 -129.41935)
				)
				(arc
					(start 96.900492 -130.56235)
					(mid 97.385632 -131.04749)
					(end 97.870772 -130.56235)
				)
			)
		)
	)
	(zone
		(layers "In1.Cu" "In3.Cu" "In4.Cu" "In6.Cu")
		(hatch none 0.5)
		(connect_pads
			(clearance 0)
		)
		(min_thickness 0.25)
		(keepout
			(tracks not_allowed)
			(vias allowed)
			(pads allowed)
			(copperpour not_allowed)
			(footprints allowed)
		)
		(placement
			(enabled no)
			(sheetname "")
		)
		(fill yes
			(thermal_gap 0.5)
			(thermal_bridge_width 0.5)
			(island_removal_mode 0)
		)
		(polygon
			(pts
				(arc
					(start 280.636726 -221.243144)
					(mid 281.185366 -220.694504)
					(end 280.636726 -220.145864)
				)
				(arc
					(start 279.236678 -220.145864)
					(mid 278.688038 -220.694504)
					(end 279.236678 -221.243144)
				)
			)
		)
	)
	(zone
		(layers "In1.Cu" "In3.Cu" "In4.Cu" "In6.Cu")
		(hatch none 0.5)
		(connect_pads
			(clearance 0)
		)
		(min_thickness 0.25)
		(keepout
			(tracks not_allowed)
			(vias allowed)
			(pads allowed)
			(copperpour not_allowed)
			(footprints allowed)
		)
		(placement
			(enabled no)
			(sheetname "")
		)
		(fill yes
			(thermal_gap 0.5)
			(thermal_bridge_width 0.5)
			(island_removal_mode 0)
		)
		(polygon
			(pts
				(arc
					(start 280.636726 -141.6431)
					(mid 281.185366 -141.09446)
					(end 280.636726 -140.54582)
				)
				(arc
					(start 279.236678 -140.54582)
					(mid 278.688038 -141.09446)
					(end 279.236678 -141.6431)
				)
			)
		)
	)
	(zone
		(layers "In1.Cu" "In3.Cu" "In4.Cu" "In6.Cu")
		(hatch none 0.5)
		(connect_pads
			(clearance 0)
		)
		(min_thickness 0.25)
		(keepout
			(tracks not_allowed)
			(vias allowed)
			(pads allowed)
			(copperpour not_allowed)
			(footprints allowed)
		)
		(placement
			(enabled no)
			(sheetname "")
		)
		(fill yes
			(thermal_gap 0.5)
			(thermal_bridge_width 0.5)
			(island_removal_mode 0)
		)
		(polygon
			(pts
				(arc
					(start 287.83661 -192.4431)
					(mid 288.38525 -191.89446)
					(end 287.83661 -191.34582)
				)
				(arc
					(start 286.436562 -191.34582)
					(mid 285.887922 -191.89446)
					(end 286.436562 -192.4431)
				)
			)
		)
	)
	(zone
		(layers "In1.Cu" "In3.Cu" "In4.Cu" "In6.Cu")
		(hatch none 0.5)
		(connect_pads
			(clearance 0)
		)
		(min_thickness 0.25)
		(keepout
			(tracks not_allowed)
			(vias allowed)
			(pads allowed)
			(copperpour not_allowed)
			(footprints allowed)
		)
		(placement
			(enabled no)
			(sheetname "")
		)
		(fill yes
			(thermal_gap 0.5)
			(thermal_bridge_width 0.5)
			(island_removal_mode 0)
		)
		(polygon
			(pts
				(arc
					(start 34.770822 -129.419604)
					(mid 34.285809 -128.93421)
					(end 33.800542 -129.41935)
				)
				(arc
					(start 33.800542 -130.56235)
					(mid 34.285682 -131.04749)
					(end 34.770822 -130.56235)
				)
			)
		)
	)
	(zone
		(layers "In1.Cu" "In3.Cu" "In4.Cu" "In6.Cu")
		(hatch none 0.5)
		(connect_pads
			(clearance 0)
		)
		(min_thickness 0.25)
		(keepout
			(tracks not_allowed)
			(vias allowed)
			(pads allowed)
			(copperpour not_allowed)
			(footprints allowed)
		)
		(placement
			(enabled no)
			(sheetname "")
		)
		(fill yes
			(thermal_gap 0.5)
			(thermal_bridge_width 0.5)
			(island_removal_mode 0)
		)
		(polygon
			(pts
				(arc
					(start 280.636726 -214.043006)
					(mid 281.185366 -213.494366)
					(end 280.636726 -212.945726)
				)
				(arc
					(start 279.236678 -212.945726)
					(mid 278.688038 -213.494366)
					(end 279.236678 -214.043006)
				)
			)
		)
	)
	(zone
		(layers "In1.Cu" "In3.Cu" "In4.Cu" "In6.Cu")
		(hatch none 0.5)
		(connect_pads
			(clearance 0)
		)
		(min_thickness 0.25)
		(keepout
			(tracks not_allowed)
			(vias allowed)
			(pads allowed)
			(copperpour not_allowed)
			(footprints allowed)
		)
		(placement
			(enabled no)
			(sheetname "")
		)
		(fill yes
			(thermal_gap 0.5)
			(thermal_bridge_width 0.5)
			(island_removal_mode 0)
		)
		(polygon
			(pts
				(arc
					(start 190.744094 -248.115328)
					(mid 190.259081 -247.629934)
					(end 189.773814 -248.115074)
				)
				(arc
					(start 189.773814 -249.385074)
					(mid 190.258954 -249.870214)
					(end 190.744094 -249.385074)
				)
			)
		)
	)
	(zone
		(layers "In1.Cu" "In3.Cu" "In4.Cu" "In6.Cu")
		(hatch none 0.5)
		(connect_pads
			(clearance 0)
		)
		(min_thickness 0.25)
		(keepout
			(tracks not_allowed)
			(vias allowed)
			(pads allowed)
			(copperpour not_allowed)
			(footprints allowed)
		)
		(placement
			(enabled no)
			(sheetname "")
		)
		(fill yes
			(thermal_gap 0.5)
			(thermal_bridge_width 0.5)
			(island_removal_mode 0)
		)
		(polygon
			(pts
				(arc
					(start 287.83661 -214.043006)
					(mid 288.38525 -213.494366)
					(end 287.83661 -212.945726)
				)
				(arc
					(start 286.436562 -212.945726)
					(mid 285.887922 -213.494366)
					(end 286.436562 -214.043006)
				)
			)
		)
	)
	(zone
		(layers "In1.Cu" "In3.Cu" "In4.Cu" "In6.Cu")
		(hatch none 0.5)
		(connect_pads
			(clearance 0)
		)
		(min_thickness 0.25)
		(keepout
			(tracks not_allowed)
			(vias allowed)
			(pads allowed)
			(copperpour not_allowed)
			(footprints allowed)
		)
		(placement
			(enabled no)
			(sheetname "")
		)
		(fill yes
			(thermal_gap 0.5)
			(thermal_bridge_width 0.5)
			(island_removal_mode 0)
		)
		(polygon
			(pts
				(arc
					(start 287.83661 -199.642984)
					(mid 288.38525 -199.094344)
					(end 287.83661 -198.545704)
				)
				(arc
					(start 286.436562 -198.545704)
					(mid 285.887922 -199.094344)
					(end 286.436562 -199.642984)
				)
			)
		)
	)
	(zone
		(layers "In1.Cu" "In3.Cu" "In4.Cu" "In6.Cu")
		(hatch none 0.5)
		(connect_pads
			(clearance 0)
		)
		(min_thickness 0.25)
		(keepout
			(tracks not_allowed)
			(vias allowed)
			(pads allowed)
			(copperpour not_allowed)
			(footprints allowed)
		)
		(placement
			(enabled no)
			(sheetname "")
		)
		(fill yes
			(thermal_gap 0.5)
			(thermal_bridge_width 0.5)
			(island_removal_mode 0)
		)
		(polygon
			(pts
				(arc
					(start 354.231956 -16.95196)
					(mid 353.746562 -17.436973)
					(end 354.231702 -17.92224)
				)
				(arc
					(start 355.501702 -17.92224)
					(mid 355.986842 -17.4371)
					(end 355.501702 -16.95196)
				)
			)
		)
	)
	(zone
		(layers "In1.Cu" "In3.Cu" "In4.Cu" "In6.Cu")
		(hatch none 0.5)
		(connect_pads
			(clearance 0)
		)
		(min_thickness 0.25)
		(keepout
			(tracks not_allowed)
			(vias allowed)
			(pads allowed)
			(copperpour not_allowed)
			(footprints allowed)
		)
		(placement
			(enabled no)
			(sheetname "")
		)
		(fill yes
			(thermal_gap 0.5)
			(thermal_bridge_width 0.5)
			(island_removal_mode 0)
		)
		(polygon
			(pts
				(arc
					(start 210.548728 -70.39991)
					(mid 210.000088 -69.85127)
					(end 209.451448 -70.39991)
				)
				(arc
					(start 209.451448 -71.799704)
					(mid 209.999961 -72.348598)
					(end 210.548728 -71.799958)
				)
			)
		)
	)
	(zone
		(layers "In1.Cu" "In3.Cu" "In4.Cu" "In6.Cu")
		(hatch none 0.5)
		(connect_pads
			(clearance 0)
		)
		(min_thickness 0.25)
		(keepout
			(tracks not_allowed)
			(vias allowed)
			(pads allowed)
			(copperpour not_allowed)
			(footprints allowed)
		)
		(placement
			(enabled no)
			(sheetname "")
		)
		(fill yes
			(thermal_gap 0.5)
			(thermal_bridge_width 0.5)
			(island_removal_mode 0)
		)
		(polygon
			(pts
				(arc
					(start 215.948768 -76.399898)
					(mid 215.400128 -75.851258)
					(end 214.851488 -76.399898)
				)
				(arc
					(start 214.851488 -77.799692)
					(mid 215.400001 -78.348586)
					(end 215.948768 -77.799946)
				)
			)
		)
	)
	(zone
		(layers "In1.Cu" "In3.Cu" "In4.Cu" "In6.Cu")
		(hatch none 0.5)
		(connect_pads
			(clearance 0)
		)
		(min_thickness 0.25)
		(keepout
			(tracks not_allowed)
			(vias allowed)
			(pads allowed)
			(copperpour not_allowed)
			(footprints allowed)
		)
		(placement
			(enabled no)
			(sheetname "")
		)
		(fill yes
			(thermal_gap 0.5)
			(thermal_bridge_width 0.5)
			(island_removal_mode 0)
		)
		(polygon
			(pts
				(arc
					(start 280.636726 -210.443064)
					(mid 281.185366 -209.894424)
					(end 280.636726 -209.345784)
				)
				(arc
					(start 279.236678 -209.345784)
					(mid 278.688038 -209.894424)
					(end 279.236678 -210.443064)
				)
			)
		)
	)
	(zone
		(layers "In1.Cu" "In3.Cu" "In4.Cu" "In6.Cu")
		(hatch none 0.5)
		(connect_pads
			(clearance 0)
		)
		(min_thickness 0.25)
		(keepout
			(tracks not_allowed)
			(vias allowed)
			(pads allowed)
			(copperpour not_allowed)
			(footprints allowed)
		)
		(placement
			(enabled no)
			(sheetname "")
		)
		(fill yes
			(thermal_gap 0.5)
			(thermal_bridge_width 0.5)
			(island_removal_mode 0)
		)
		(polygon
			(pts
				(arc
					(start 286.836612 -226.643184)
					(mid 287.385252 -226.094544)
					(end 286.836612 -225.545904)
				)
				(arc
					(start 285.436564 -225.545904)
					(mid 284.887924 -226.094544)
					(end 285.436564 -226.643184)
				)
			)
		)
	)
	(zone
		(layers "In1.Cu" "In3.Cu" "In4.Cu" "In6.Cu")
		(hatch none 0.5)
		(connect_pads
			(clearance 0)
		)
		(min_thickness 0.25)
		(keepout
			(tracks not_allowed)
			(vias allowed)
			(pads allowed)
			(copperpour not_allowed)
			(footprints allowed)
		)
		(placement
			(enabled no)
			(sheetname "")
		)
		(fill yes
			(thermal_gap 0.5)
			(thermal_bridge_width 0.5)
			(island_removal_mode 0)
		)
		(polygon
			(pts
				(arc
					(start 286.836612 -237.44301)
					(mid 287.385252 -236.89437)
					(end 286.836612 -236.34573)
				)
				(arc
					(start 285.436564 -236.34573)
					(mid 284.887924 -236.89437)
					(end 285.436564 -237.44301)
				)
			)
		)
	)
	(zone
		(layers "In1.Cu" "In3.Cu" "In4.Cu" "In6.Cu")
		(hatch none 0.5)
		(connect_pads
			(clearance 0)
		)
		(min_thickness 0.25)
		(keepout
			(tracks not_allowed)
			(vias allowed)
			(pads allowed)
			(copperpour not_allowed)
			(footprints allowed)
		)
		(placement
			(enabled no)
			(sheetname "")
		)
		(fill yes
			(thermal_gap 0.5)
			(thermal_bridge_width 0.5)
			(island_removal_mode 0)
		)
		(polygon
			(pts
				(arc
					(start 286.836612 -132.643118)
					(mid 287.385252 -132.094478)
					(end 286.836612 -131.545838)
				)
				(arc
					(start 285.436564 -131.545838)
					(mid 284.887924 -132.094478)
					(end 285.436564 -132.643118)
				)
			)
		)
	)
	(zone
		(layers "In1.Cu" "In3.Cu" "In4.Cu" "In6.Cu")
		(hatch none 0.5)
		(connect_pads
			(clearance 0)
		)
		(min_thickness 0.25)
		(keepout
			(tracks not_allowed)
			(vias allowed)
			(pads allowed)
			(copperpour not_allowed)
			(footprints allowed)
		)
		(placement
			(enabled no)
			(sheetname "")
		)
		(fill yes
			(thermal_gap 0.5)
			(thermal_bridge_width 0.5)
			(island_removal_mode 0)
		)
		(polygon
			(pts
				(arc
					(start 382.314704 -128.141984)
					(mid 381.82931 -128.626997)
					(end 382.31445 -129.112264)
				)
				(arc
					(start 383.45745 -129.112264)
					(mid 383.94259 -128.627124)
					(end 383.45745 -128.141984)
				)
			)
		)
	)
	(zone
		(layers "In1.Cu" "In3.Cu" "In4.Cu" "In6.Cu")
		(hatch none 0.5)
		(connect_pads
			(clearance 0)
		)
		(min_thickness 0.25)
		(keepout
			(tracks not_allowed)
			(vias allowed)
			(pads allowed)
			(copperpour not_allowed)
			(footprints allowed)
		)
		(placement
			(enabled no)
			(sheetname "")
		)
		(fill yes
			(thermal_gap 0.5)
			(thermal_bridge_width 0.5)
			(island_removal_mode 0)
		)
		(polygon
			(pts
				(arc
					(start 192.520824 -244.419374)
					(mid 192.035684 -243.934234)
					(end 191.550544 -244.419374)
				)
				(arc
					(start 191.550544 -245.56212)
					(mid 192.035557 -246.047514)
					(end 192.520824 -245.562374)
				)
			)
		)
	)
	(zone
		(layers "In1.Cu" "In3.Cu" "In4.Cu" "In6.Cu")
		(hatch none 0.5)
		(connect_pads
			(clearance 0)
		)
		(min_thickness 0.25)
		(keepout
			(tracks not_allowed)
			(vias allowed)
			(pads allowed)
			(copperpour not_allowed)
			(footprints allowed)
		)
		(placement
			(enabled no)
			(sheetname "")
		)
		(fill yes
			(thermal_gap 0.5)
			(thermal_bridge_width 0.5)
			(island_removal_mode 0)
		)
		(polygon
			(pts
				(arc
					(start 66.32067 -129.419604)
					(mid 65.835657 -128.93421)
					(end 65.35039 -129.41935)
				)
				(arc
					(start 65.35039 -130.56235)
					(mid 65.83553 -131.04749)
					(end 66.32067 -130.56235)
				)
			)
		)
	)
	(zone
		(layers "In1.Cu" "In3.Cu" "In4.Cu" "In6.Cu")
		(hatch none 0.5)
		(connect_pads
			(clearance 0)
		)
		(min_thickness 0.25)
		(keepout
			(tracks not_allowed)
			(vias allowed)
			(pads allowed)
			(copperpour not_allowed)
			(footprints allowed)
		)
		(placement
			(enabled no)
			(sheetname "")
		)
		(fill yes
			(thermal_gap 0.5)
			(thermal_bridge_width 0.5)
			(island_removal_mode 0)
		)
		(polygon
			(pts
				(arc
					(start 66.32067 -14.41958)
					(mid 65.835657 -13.934186)
					(end 65.35039 -14.419326)
				)
				(arc
					(start 65.35039 -15.562326)
					(mid 65.83553 -16.047466)
					(end 66.32067 -15.562326)
				)
			)
		)
	)
	(zone
		(layers "In1.Cu" "In3.Cu" "In4.Cu" "In6.Cu")
		(hatch none 0.5)
		(connect_pads
			(clearance 0)
		)
		(min_thickness 0.25)
		(keepout
			(tracks not_allowed)
			(vias allowed)
			(pads allowed)
			(copperpour not_allowed)
			(footprints allowed)
		)
		(placement
			(enabled no)
			(sheetname "")
		)
		(fill yes
			(thermal_gap 0.5)
			(thermal_bridge_width 0.5)
			(island_removal_mode 0)
		)
		(polygon
			(pts
				(arc
					(start 279.636728 -187.04306)
					(mid 280.185368 -186.49442)
					(end 279.636728 -185.94578)
				)
				(arc
					(start 278.23668 -185.94578)
					(mid 277.68804 -186.49442)
					(end 278.23668 -187.04306)
				)
			)
		)
	)
	(zone
		(layers "In1.Cu" "In3.Cu" "In4.Cu" "In6.Cu")
		(hatch none 0.5)
		(connect_pads
			(clearance 0)
		)
		(min_thickness 0.25)
		(keepout
			(tracks not_allowed)
			(vias allowed)
			(pads allowed)
			(copperpour not_allowed)
			(footprints allowed)
		)
		(placement
			(enabled no)
			(sheetname "")
		)
		(fill yes
			(thermal_gap 0.5)
			(thermal_bridge_width 0.5)
			(island_removal_mode 0)
		)
		(polygon
			(pts
				(arc
					(start 280.636726 -199.642984)
					(mid 281.185366 -199.094344)
					(end 280.636726 -198.545704)
				)
				(arc
					(start 279.236678 -198.545704)
					(mid 278.688038 -199.094344)
					(end 279.236678 -199.642984)
				)
			)
		)
	)
	(zone
		(layers "In1.Cu" "In3.Cu" "In4.Cu" "In6.Cu")
		(hatch none 0.5)
		(connect_pads
			(clearance 0)
		)
		(min_thickness 0.25)
		(keepout
			(tracks not_allowed)
			(vias allowed)
			(pads allowed)
			(copperpour not_allowed)
			(footprints allowed)
		)
		(placement
			(enabled no)
			(sheetname "")
		)
		(fill yes
			(thermal_gap 0.5)
			(thermal_bridge_width 0.5)
			(island_removal_mode 0)
		)
		(polygon
			(pts
				(arc
					(start 319.8876 -244.312694)
					(mid 319.40246 -243.827554)
					(end 318.91732 -244.312694)
				)
				(arc
					(start 318.91732 -245.45544)
					(mid 319.402333 -245.940834)
					(end 319.8876 -245.455694)
				)
			)
		)
	)
	(zone
		(layers "In1.Cu" "In3.Cu" "In4.Cu" "In6.Cu")
		(hatch none 0.5)
		(connect_pads
			(clearance 0)
		)
		(min_thickness 0.25)
		(keepout
			(tracks not_allowed)
			(vias allowed)
			(pads allowed)
			(copperpour not_allowed)
			(footprints allowed)
		)
		(placement
			(enabled no)
			(sheetname "")
		)
		(fill yes
			(thermal_gap 0.5)
			(thermal_bridge_width 0.5)
			(island_removal_mode 0)
		)
		(polygon
			(pts
				(arc
					(start 280.636726 -134.442962)
					(mid 281.185366 -133.894322)
					(end 280.636726 -133.345682)
				)
				(arc
					(start 279.236678 -133.345682)
					(mid 278.688038 -133.894322)
					(end 279.236678 -134.442962)
				)
			)
		)
	)
	(zone
		(layers "In1.Cu" "In3.Cu" "In4.Cu" "In6.Cu")
		(hatch none 0.5)
		(connect_pads
			(clearance 0)
		)
		(min_thickness 0.25)
		(keepout
			(tracks not_allowed)
			(vias allowed)
			(pads allowed)
			(copperpour not_allowed)
			(footprints allowed)
		)
		(placement
			(enabled no)
			(sheetname "")
		)
		(fill yes
			(thermal_gap 0.5)
			(thermal_bridge_width 0.5)
			(island_removal_mode 0)
		)
		(polygon
			(pts
				(arc
					(start 286.836612 -176.243234)
					(mid 287.385252 -175.694594)
					(end 286.836612 -175.145954)
				)
				(arc
					(start 285.436564 -175.145954)
					(mid 284.887924 -175.694594)
					(end 285.436564 -176.243234)
				)
			)
		)
	)
	(zone
		(layers "In1.Cu" "In3.Cu" "In4.Cu" "In6.Cu")
		(hatch none 0.5)
		(connect_pads
			(clearance 0)
		)
		(min_thickness 0.25)
		(keepout
			(tracks not_allowed)
			(vias allowed)
			(pads allowed)
			(copperpour not_allowed)
			(footprints allowed)
		)
		(placement
			(enabled no)
			(sheetname "")
		)
		(fill yes
			(thermal_gap 0.5)
			(thermal_bridge_width 0.5)
			(island_removal_mode 0)
		)
		(polygon
			(pts
				(arc
					(start 286.836612 -215.843104)
					(mid 287.385252 -215.294464)
					(end 286.836612 -214.745824)
				)
				(arc
					(start 285.436564 -214.745824)
					(mid 284.887924 -215.294464)
					(end 285.436564 -215.843104)
				)
			)
		)
	)
	(zone
		(layers "In1.Cu" "In3.Cu" "In4.Cu" "In6.Cu")
		(hatch none 0.5)
		(connect_pads
			(clearance 0)
		)
		(min_thickness 0.25)
		(keepout
			(tracks not_allowed)
			(vias allowed)
			(pads allowed)
			(copperpour not_allowed)
			(footprints allowed)
		)
		(placement
			(enabled no)
			(sheetname "")
		)
		(fill yes
			(thermal_gap 0.5)
			(thermal_bridge_width 0.5)
			(island_removal_mode 0)
		)
		(polygon
			(pts
				(arc
					(start 286.836612 -201.443082)
					(mid 287.385252 -200.894442)
					(end 286.836612 -200.345802)
				)
				(arc
					(start 285.436564 -200.345802)
					(mid 284.887924 -200.894442)
					(end 285.436564 -201.443082)
				)
			)
		)
	)
	(zone
		(layers "In1.Cu" "In3.Cu" "In4.Cu" "In6.Cu")
		(hatch none 0.5)
		(connect_pads
			(clearance 0)
		)
		(min_thickness 0.25)
		(keepout
			(tracks not_allowed)
			(vias allowed)
			(pads allowed)
			(copperpour not_allowed)
			(footprints allowed)
		)
		(placement
			(enabled no)
			(sheetname "")
		)
		(fill yes
			(thermal_gap 0.5)
			(thermal_bridge_width 0.5)
			(island_removal_mode 0)
		)
		(polygon
			(pts
				(arc
					(start 280.636726 -192.4431)
					(mid 281.185366 -191.89446)
					(end 280.636726 -191.34582)
				)
				(arc
					(start 279.236678 -191.34582)
					(mid 278.688038 -191.89446)
					(end 279.236678 -192.4431)
				)
			)
		)
	)
	(zone
		(layers "In1.Cu" "In3.Cu" "In4.Cu" "In6.Cu")
		(hatch none 0.5)
		(connect_pads
			(clearance 0)
		)
		(min_thickness 0.25)
		(keepout
			(tracks not_allowed)
			(vias allowed)
			(pads allowed)
			(copperpour not_allowed)
			(footprints allowed)
		)
		(placement
			(enabled no)
			(sheetname "")
		)
		(fill yes
			(thermal_gap 0.5)
			(thermal_bridge_width 0.5)
			(island_removal_mode 0)
		)
		(polygon
			(pts
				(arc
					(start 159.193992 -248.115074)
					(mid 158.708852 -247.629934)
					(end 158.223712 -248.115074)
				)
				(arc
					(start 158.223712 -249.38482)
					(mid 158.708725 -249.870214)
					(end 159.193992 -249.385074)
				)
			)
		)
	)
	(zone
		(layers "In1.Cu" "In3.Cu" "In4.Cu" "In6.Cu")
		(hatch none 0.5)
		(connect_pads
			(clearance 0)
		)
		(min_thickness 0.25)
		(keepout
			(tracks not_allowed)
			(vias allowed)
			(pads allowed)
			(copperpour not_allowed)
			(footprints allowed)
		)
		(placement
			(enabled no)
			(sheetname "")
		)
		(fill yes
			(thermal_gap 0.5)
			(thermal_bridge_width 0.5)
			(island_removal_mode 0)
		)
		(polygon
			(pts
				(arc
					(start 324.07479 -248.115328)
					(mid 323.589777 -247.629934)
					(end 323.10451 -248.115074)
				)
				(arc
					(start 323.10451 -249.385074)
					(mid 323.58965 -249.870214)
					(end 324.07479 -249.385074)
				)
			)
		)
	)
	(zone
		(layers "In1.Cu" "In3.Cu" "In4.Cu" "In6.Cu")
		(hatch none 0.5)
		(connect_pads
			(clearance 0)
		)
		(min_thickness 0.25)
		(keepout
			(tracks not_allowed)
			(vias allowed)
			(pads allowed)
			(copperpour not_allowed)
			(footprints allowed)
		)
		(placement
			(enabled no)
			(sheetname "")
		)
		(fill yes
			(thermal_gap 0.5)
			(thermal_bridge_width 0.5)
			(island_removal_mode 0)
		)
		(polygon
			(pts
				(arc
					(start 97.870772 -244.419374)
					(mid 97.385632 -243.934234)
					(end 96.900492 -244.419374)
				)
				(arc
					(start 96.900492 -245.56212)
					(mid 97.385505 -246.047514)
					(end 97.870772 -245.562374)
				)
			)
		)
	)
	(zone
		(layers "In1.Cu" "In3.Cu" "In4.Cu" "In6.Cu")
		(hatch none 0.5)
		(connect_pads
			(clearance 0)
		)
		(min_thickness 0.25)
		(keepout
			(tracks not_allowed)
			(vias allowed)
			(pads allowed)
			(copperpour not_allowed)
			(footprints allowed)
		)
		(placement
			(enabled no)
			(sheetname "")
		)
		(fill yes
			(thermal_gap 0.5)
			(thermal_bridge_width 0.5)
			(island_removal_mode 0)
		)
		(polygon
			(pts
				(arc
					(start 279.636728 -183.443118)
					(mid 280.185368 -182.894478)
					(end 279.636728 -182.345838)
				)
				(arc
					(start 278.23668 -182.345838)
					(mid 277.68804 -182.894478)
					(end 278.23668 -183.443118)
				)
			)
		)
	)
	(zone
		(layers "In1.Cu" "In3.Cu" "In4.Cu" "In6.Cu")
		(hatch none 0.5)
		(connect_pads
			(clearance 0)
		)
		(min_thickness 0.25)
		(keepout
			(tracks not_allowed)
			(vias allowed)
			(pads allowed)
			(copperpour not_allowed)
			(footprints allowed)
		)
		(placement
			(enabled no)
			(sheetname "")
		)
		(fill yes
			(thermal_gap 0.5)
			(thermal_bridge_width 0.5)
			(island_removal_mode 0)
		)
		(polygon
			(pts
				(arc
					(start 215.948768 -65.600072)
					(mid 215.400128 -65.051432)
					(end 214.851488 -65.600072)
				)
				(arc
					(start 214.851488 -66.999612)
					(mid 215.400001 -67.548506)
					(end 215.948768 -66.999866)
				)
			)
		)
	)
	(zone
		(layers "In1.Cu" "In3.Cu" "In4.Cu" "In6.Cu")
		(hatch none 0.5)
		(connect_pads
			(clearance 0)
		)
		(min_thickness 0.25)
		(keepout
			(tracks not_allowed)
			(vias allowed)
			(pads allowed)
			(copperpour not_allowed)
			(footprints allowed)
		)
		(placement
			(enabled no)
			(sheetname "")
		)
		(fill yes
			(thermal_gap 0.5)
			(thermal_bridge_width 0.5)
			(island_removal_mode 0)
		)
		(polygon
			(pts
				(arc
					(start 323.951346 -17.92224)
					(mid 324.43674 -17.437227)
					(end 323.9516 -16.95196)
				)
				(arc
					(start 322.6816 -16.95196)
					(mid 322.19646 -17.4371)
					(end 322.6816 -17.92224)
				)
			)
		)
	)
	(zone
		(layers "In1.Cu" "In3.Cu" "In4.Cu" "In6.Cu")
		(hatch none 0.5)
		(connect_pads
			(clearance 0)
		)
		(min_thickness 0.25)
		(keepout
			(tracks not_allowed)
			(vias allowed)
			(pads allowed)
			(copperpour not_allowed)
			(footprints allowed)
		)
		(placement
			(enabled no)
			(sheetname "")
		)
		(fill yes
			(thermal_gap 0.5)
			(thermal_bridge_width 0.5)
			(island_removal_mode 0)
		)
		(polygon
			(pts
				(arc
					(start 97.870772 -14.41958)
					(mid 97.385759 -13.934186)
					(end 96.900492 -14.419326)
				)
				(arc
					(start 96.900492 -15.562326)
					(mid 97.385632 -16.047466)
					(end 97.870772 -15.562326)
				)
			)
		)
	)
	(zone
		(layers "In1.Cu" "In3.Cu" "In4.Cu" "In6.Cu")
		(hatch none 0.5)
		(connect_pads
			(clearance 0)
		)
		(min_thickness 0.25)
		(keepout
			(tracks not_allowed)
			(vias allowed)
			(pads allowed)
			(copperpour not_allowed)
			(footprints allowed)
		)
		(placement
			(enabled no)
			(sheetname "")
		)
		(fill yes
			(thermal_gap 0.5)
			(thermal_bridge_width 0.5)
			(island_removal_mode 0)
		)
		(polygon
			(pts
				(arc
					(start 280.636726 -188.843158)
					(mid 281.185366 -188.294518)
					(end 280.636726 -187.745878)
				)
				(arc
					(start 279.236678 -187.745878)
					(mid 278.688038 -188.294518)
					(end 279.236678 -188.843158)
				)
			)
		)
	)
	(zone
		(layers "In1.Cu" "In3.Cu" "In4.Cu" "In6.Cu")
		(hatch none 0.5)
		(connect_pads
			(clearance 0)
		)
		(min_thickness 0.25)
		(keepout
			(tracks not_allowed)
			(vias allowed)
			(pads allowed)
			(copperpour not_allowed)
			(footprints allowed)
		)
		(placement
			(enabled no)
			(sheetname "")
		)
		(fill yes
			(thermal_gap 0.5)
			(thermal_bridge_width 0.5)
			(island_removal_mode 0)
		)
		(polygon
			(pts
				(arc
					(start 279.636728 -205.043024)
					(mid 280.185368 -204.494384)
					(end 279.636728 -203.945744)
				)
				(arc
					(start 278.23668 -203.945744)
					(mid 277.68804 -204.494384)
					(end 278.23668 -205.043024)
				)
			)
		)
	)
	(zone
		(layers "In1.Cu" "In3.Cu" "In4.Cu" "In6.Cu")
		(hatch none 0.5)
		(connect_pads
			(clearance 0)
		)
		(min_thickness 0.25)
		(keepout
			(tracks not_allowed)
			(vias allowed)
			(pads allowed)
			(copperpour not_allowed)
			(footprints allowed)
		)
		(placement
			(enabled no)
			(sheetname "")
		)
		(fill yes
			(thermal_gap 0.5)
			(thermal_bridge_width 0.5)
			(island_removal_mode 0)
		)
		(polygon
			(pts
				(arc
					(start 212.348826 -76.399898)
					(mid 211.800186 -75.851258)
					(end 211.251546 -76.399898)
				)
				(arc
					(start 211.251546 -77.799692)
					(mid 211.800059 -78.348586)
					(end 212.348826 -77.799946)
				)
			)
		)
	)
	(zone
		(layers "In1.Cu" "In3.Cu" "In4.Cu" "In6.Cu")
		(hatch none 0.5)
		(connect_pads
			(clearance 0)
		)
		(min_thickness 0.25)
		(keepout
			(tracks not_allowed)
			(vias allowed)
			(pads allowed)
			(copperpour not_allowed)
			(footprints allowed)
		)
		(placement
			(enabled no)
			(sheetname "")
		)
		(fill yes
			(thermal_gap 0.5)
			(thermal_bridge_width 0.5)
			(island_removal_mode 0)
		)
		(polygon
			(pts
				(arc
					(start 286.836612 -233.843068)
					(mid 287.385252 -233.294428)
					(end 286.836612 -232.745788)
				)
				(arc
					(start 285.436564 -232.745788)
					(mid 284.887924 -233.294428)
					(end 285.436564 -233.843068)
				)
			)
		)
	)
	(zone
		(layers "In1.Cu" "In3.Cu" "In4.Cu" "In6.Cu")
		(hatch none 0.5)
		(connect_pads
			(clearance 0)
		)
		(min_thickness 0.25)
		(keepout
			(tracks not_allowed)
			(vias allowed)
			(pads allowed)
			(copperpour not_allowed)
			(footprints allowed)
		)
		(placement
			(enabled no)
			(sheetname "")
		)
		(fill yes
			(thermal_gap 0.5)
			(thermal_bridge_width 0.5)
			(island_removal_mode 0)
		)
		(polygon
			(pts
				(arc
					(start 280.636726 -224.843086)
					(mid 281.185366 -224.294446)
					(end 280.636726 -223.745806)
				)
				(arc
					(start 279.236678 -223.745806)
					(mid 278.688038 -224.294446)
					(end 279.236678 -224.843086)
				)
			)
		)
	)
	(zone
		(layers "In1.Cu" "In3.Cu" "In4.Cu" "In6.Cu")
		(hatch none 0.5)
		(connect_pads
			(clearance 0)
		)
		(min_thickness 0.25)
		(keepout
			(tracks not_allowed)
			(vias allowed)
			(pads allowed)
			(copperpour not_allowed)
			(footprints allowed)
		)
		(placement
			(enabled no)
			(sheetname "")
		)
		(fill yes
			(thermal_gap 0.5)
			(thermal_bridge_width 0.5)
			(island_removal_mode 0)
		)
		(polygon
			(pts
				(arc
					(start 33.800542 -245.56212)
					(mid 34.285555 -246.047514)
					(end 34.770822 -245.562374)
				)
				(arc
					(start 34.770822 -244.419374)
					(mid 34.285682 -243.934234)
					(end 33.800542 -244.419374)
				)
			)
		)
	)
	(zone
		(layers "In1.Cu" "In3.Cu" "In4.Cu" "In6.Cu")
		(hatch none 0.5)
		(connect_pads
			(clearance 0)
		)
		(min_thickness 0.25)
		(keepout
			(tracks not_allowed)
			(vias allowed)
			(pads allowed)
			(copperpour not_allowed)
			(footprints allowed)
		)
		(placement
			(enabled no)
			(sheetname "")
		)
		(fill yes
			(thermal_gap 0.5)
			(thermal_bridge_width 0.5)
			(island_removal_mode 0)
		)
		(polygon
			(pts
				(arc
					(start 279.636728 -194.243198)
					(mid 280.185368 -193.694558)
					(end 279.636728 -193.145918)
				)
				(arc
					(start 278.23668 -193.145918)
					(mid 277.68804 -193.694558)
					(end 278.23668 -194.243198)
				)
			)
		)
	)
	(zone
		(layers "In1.Cu" "In3.Cu" "In4.Cu" "In6.Cu")
		(hatch none 0.5)
		(connect_pads
			(clearance 0)
		)
		(min_thickness 0.25)
		(keepout
			(tracks not_allowed)
			(vias allowed)
			(pads allowed)
			(copperpour not_allowed)
			(footprints allowed)
		)
		(placement
			(enabled no)
			(sheetname "")
		)
		(fill yes
			(thermal_gap 0.5)
			(thermal_bridge_width 0.5)
			(island_removal_mode 0)
		)
		(polygon
			(pts
				(arc
					(start 287.83661 -188.843158)
					(mid 288.38525 -188.294518)
					(end 287.83661 -187.745878)
				)
				(arc
					(start 286.436562 -187.745878)
					(mid 285.887922 -188.294518)
					(end 286.436562 -188.843158)
				)
			)
		)
	)
	(zone
		(layers "In1.Cu" "In3.Cu" "In4.Cu" "In6.Cu")
		(hatch none 0.5)
		(connect_pads
			(clearance 0)
		)
		(min_thickness 0.25)
		(keepout
			(tracks not_allowed)
			(vias allowed)
			(pads allowed)
			(copperpour not_allowed)
			(footprints allowed)
		)
		(placement
			(enabled no)
			(sheetname "")
		)
		(fill yes
			(thermal_gap 0.5)
			(thermal_bridge_width 0.5)
			(island_removal_mode 0)
		)
		(polygon
			(pts
				(arc
					(start 354.231956 -131.951984)
					(mid 353.746562 -132.436997)
					(end 354.231702 -132.922264)
				)
				(arc
					(start 355.501702 -132.922264)
					(mid 355.986842 -132.437124)
					(end 355.501702 -131.951984)
				)
			)
		)
	)
	(zone
		(layers "In1.Cu" "In3.Cu" "In4.Cu" "In6.Cu")
		(hatch none 0.5)
		(connect_pads
			(clearance 0)
		)
		(min_thickness 0.25)
		(keepout
			(tracks not_allowed)
			(vias allowed)
			(pads allowed)
			(copperpour not_allowed)
			(footprints allowed)
		)
		(placement
			(enabled no)
			(sheetname "")
		)
		(fill yes
			(thermal_gap 0.5)
			(thermal_bridge_width 0.5)
			(island_removal_mode 0)
		)
		(polygon
			(pts
				(arc
					(start 65.35039 -245.56212)
					(mid 65.835403 -246.047514)
					(end 66.32067 -245.562374)
				)
				(arc
					(start 66.32067 -244.419374)
					(mid 65.83553 -243.934234)
					(end 65.35039 -244.419374)
				)
			)
		)
	)
	(zone
		(layers "In1.Cu" "In3.Cu" "In4.Cu" "In6.Cu")
		(hatch none 0.5)
		(connect_pads
			(clearance 0)
		)
		(min_thickness 0.25)
		(keepout
			(tracks not_allowed)
			(vias allowed)
			(pads allowed)
			(copperpour not_allowed)
			(footprints allowed)
		)
		(placement
			(enabled no)
			(sheetname "")
		)
		(fill yes
			(thermal_gap 0.5)
			(thermal_bridge_width 0.5)
			(island_removal_mode 0)
		)
		(polygon
			(pts
				(arc
					(start 446.0875 -244.312694)
					(mid 445.60236 -243.827554)
					(end 445.11722 -244.312694)
				)
				(arc
					(start 445.11722 -245.45544)
					(mid 445.602233 -245.940834)
					(end 446.0875 -245.455694)
				)
			)
		)
	)
	(zone
		(layers "In1.Cu" "In3.Cu" "In4.Cu" "In6.Cu")
		(hatch none 0.5)
		(connect_pads
			(clearance 0)
		)
		(min_thickness 0.25)
		(keepout
			(tracks not_allowed)
			(vias allowed)
			(pads allowed)
			(copperpour not_allowed)
			(footprints allowed)
		)
		(placement
			(enabled no)
			(sheetname "")
		)
		(fill yes
			(thermal_gap 0.5)
			(thermal_bridge_width 0.5)
			(island_removal_mode 0)
		)
		(polygon
			(pts
				(arc
					(start 287.83661 -196.043042)
					(mid 288.38525 -195.494402)
					(end 287.83661 -194.945762)
				)
				(arc
					(start 286.436562 -194.945762)
					(mid 285.887922 -195.494402)
					(end 286.436562 -196.043042)
				)
			)
		)
	)
	(zone
		(layers "In1.Cu" "In3.Cu" "In4.Cu" "In6.Cu")
		(hatch none 0.5)
		(connect_pads
			(clearance 0)
		)
		(min_thickness 0.25)
		(keepout
			(tracks not_allowed)
			(vias allowed)
			(pads allowed)
			(copperpour not_allowed)
			(footprints allowed)
		)
		(placement
			(enabled no)
			(sheetname "")
		)
		(fill yes
			(thermal_gap 0.5)
			(thermal_bridge_width 0.5)
			(island_removal_mode 0)
		)
		(polygon
			(pts
				(arc
					(start 219.54871 -65.600072)
					(mid 219.00007 -65.051432)
					(end 218.45143 -65.600072)
				)
				(arc
					(start 218.45143 -66.999612)
					(mid 218.999943 -67.548506)
					(end 219.54871 -66.999866)
				)
			)
		)
	)
	(zone
		(layers "In1.Cu" "In3.Cu" "In4.Cu" "In6.Cu")
		(hatch none 0.5)
		(connect_pads
			(clearance 0)
		)
		(min_thickness 0.25)
		(keepout
			(tracks not_allowed)
			(vias allowed)
			(pads allowed)
			(copperpour not_allowed)
			(footprints allowed)
		)
		(placement
			(enabled no)
			(sheetname "")
		)
		(fill yes
			(thermal_gap 0.5)
			(thermal_bridge_width 0.5)
			(island_removal_mode 0)
		)
		(polygon
			(pts
				(arc
					(start 280.636726 -232.043224)
					(mid 281.185366 -231.494584)
					(end 280.636726 -230.945944)
				)
				(arc
					(start 279.236678 -230.945944)
					(mid 278.688038 -231.494584)
					(end 279.236678 -232.043224)
				)
			)
		)
	)
	(zone
		(layers "In1.Cu" "In3.Cu" "In4.Cu" "In6.Cu")
		(hatch none 0.5)
		(connect_pads
			(clearance 0)
		)
		(min_thickness 0.25)
		(keepout
			(tracks not_allowed)
			(vias allowed)
			(pads allowed)
			(copperpour not_allowed)
			(footprints allowed)
		)
		(placement
			(enabled no)
			(sheetname "")
		)
		(fill yes
			(thermal_gap 0.5)
			(thermal_bridge_width 0.5)
			(island_removal_mode 0)
		)
		(polygon
			(pts
				(arc
					(start 319.214754 -13.14196)
					(mid 318.72936 -13.626973)
					(end 319.2145 -14.11224)
				)
				(arc
					(start 320.3575 -14.11224)
					(mid 320.84264 -13.6271)
					(end 320.3575 -13.14196)
				)
			)
		)
	)
	(zone
		(layers "In1.Cu" "In3.Cu" "In4.Cu" "In6.Cu")
		(hatch none 0.5)
		(connect_pads
			(clearance 0)
		)
		(min_thickness 0.25)
		(keepout
			(tracks not_allowed)
			(vias allowed)
			(pads allowed)
			(copperpour not_allowed)
			(footprints allowed)
		)
		(placement
			(enabled no)
			(sheetname "")
		)
		(fill yes
			(thermal_gap 0.5)
			(thermal_bridge_width 0.5)
			(island_removal_mode 0)
		)
		(polygon
			(pts
				(arc
					(start 279.636728 -226.643184)
					(mid 280.185368 -226.094544)
					(end 279.636728 -225.545904)
				)
				(arc
					(start 278.23668 -225.545904)
					(mid 277.68804 -226.094544)
					(end 278.23668 -226.643184)
				)
			)
		)
	)
	(zone
		(layers "In1.Cu" "In3.Cu" "In4.Cu" "In6.Cu")
		(hatch none 0.5)
		(connect_pads
			(clearance 0)
		)
		(min_thickness 0.25)
		(keepout
			(tracks not_allowed)
			(vias allowed)
			(pads allowed)
			(copperpour not_allowed)
			(footprints allowed)
		)
		(placement
			(enabled no)
			(sheetname "")
		)
		(fill yes
			(thermal_gap 0.5)
			(thermal_bridge_width 0.5)
			(island_removal_mode 0)
		)
		(polygon
			(pts
				(arc
					(start 129.42062 -14.41958)
					(mid 128.935607 -13.934186)
					(end 128.45034 -14.419326)
				)
				(arc
					(start 128.45034 -15.562326)
					(mid 128.93548 -16.047466)
					(end 129.42062 -15.562326)
				)
			)
		)
	)
	(zone
		(layers "In1.Cu" "In3.Cu" "In4.Cu" "In6.Cu")
		(hatch none 0.5)
		(connect_pads
			(clearance 0)
		)
		(min_thickness 0.25)
		(keepout
			(tracks not_allowed)
			(vias allowed)
			(pads allowed)
			(copperpour not_allowed)
			(footprints allowed)
		)
		(placement
			(enabled no)
			(sheetname "")
		)
		(fill yes
			(thermal_gap 0.5)
			(thermal_bridge_width 0.5)
			(island_removal_mode 0)
		)
		(polygon
			(pts
				(arc
					(start 477.637602 -244.312694)
					(mid 477.152462 -243.827554)
					(end 476.667322 -244.312694)
				)
				(arc
					(start 476.667322 -245.45544)
					(mid 477.152335 -245.940834)
					(end 477.637602 -245.455694)
				)
			)
		)
	)
	(zone
		(layers "In1.Cu" "In3.Cu" "In4.Cu" "In6.Cu")
		(hatch none 0.5)
		(connect_pads
			(clearance 0)
		)
		(min_thickness 0.25)
		(keepout
			(tracks not_allowed)
			(vias allowed)
			(pads allowed)
			(copperpour not_allowed)
			(footprints allowed)
		)
		(placement
			(enabled no)
			(sheetname "")
		)
		(fill yes
			(thermal_gap 0.5)
			(thermal_bridge_width 0.5)
			(island_removal_mode 0)
		)
		(polygon
			(pts
				(arc
					(start 34.770822 -14.41958)
					(mid 34.285809 -13.934186)
					(end 33.800542 -14.419326)
				)
				(arc
					(start 33.800542 -15.562326)
					(mid 34.285682 -16.047466)
					(end 34.770822 -15.562326)
				)
			)
		)
	)
	(zone
		(layers "In1.Cu" "In3.Cu" "In4.Cu" "In6.Cu")
		(hatch none 0.5)
		(connect_pads
			(clearance 0)
		)
		(min_thickness 0.25)
		(keepout
			(tracks not_allowed)
			(vias allowed)
			(pads allowed)
			(copperpour not_allowed)
			(footprints allowed)
		)
		(placement
			(enabled no)
			(sheetname "")
		)
		(fill yes
			(thermal_gap 0.5)
			(thermal_bridge_width 0.5)
			(island_removal_mode 0)
		)
		(polygon
			(pts
				(arc
					(start 287.83661 -178.043078)
					(mid 288.38525 -177.494438)
					(end 287.83661 -176.945798)
				)
				(arc
					(start 286.436562 -176.945798)
					(mid 285.887922 -177.494438)
					(end 286.436562 -178.043078)
				)
			)
		)
	)
	(zone
		(layers "In1.Cu" "In3.Cu" "In4.Cu" "In6.Cu")
		(hatch none 0.5)
		(connect_pads
			(clearance 0)
		)
		(min_thickness 0.25)
		(keepout
			(tracks not_allowed)
			(vias allowed)
			(pads allowed)
			(copperpour not_allowed)
			(footprints allowed)
		)
		(placement
			(enabled no)
			(sheetname "")
		)
		(fill yes
			(thermal_gap 0.5)
			(thermal_bridge_width 0.5)
			(island_removal_mode 0)
		)
		(polygon
			(pts
				(arc
					(start 350.764856 -13.14196)
					(mid 350.279462 -13.626973)
					(end 350.764602 -14.11224)
				)
				(arc
					(start 351.907602 -14.11224)
					(mid 352.392742 -13.6271)
					(end 351.907602 -13.14196)
				)
			)
		)
	)
	(zone
		(layers "In1.Cu" "In3.Cu" "In4.Cu" "In6.Cu")
		(hatch none 0.5)
		(connect_pads
			(clearance 0)
		)
		(min_thickness 0.25)
		(keepout
			(tracks not_allowed)
			(vias allowed)
			(pads allowed)
			(copperpour not_allowed)
			(footprints allowed)
		)
		(placement
			(enabled no)
			(sheetname "")
		)
		(fill yes
			(thermal_gap 0.5)
			(thermal_bridge_width 0.5)
			(island_removal_mode 0)
		)
		(polygon
			(pts
				(arc
					(start 214.14867 -70.39991)
					(mid 213.60003 -69.85127)
					(end 213.05139 -70.39991)
				)
				(arc
					(start 213.05139 -71.799704)
					(mid 213.599903 -72.348598)
					(end 214.14867 -71.799958)
				)
			)
		)
	)
	(zone
		(layers "In1.Cu" "In3.Cu" "In4.Cu" "In6.Cu")
		(hatch none 0.5)
		(connect_pads
			(clearance 0)
		)
		(min_thickness 0.25)
		(keepout
			(tracks not_allowed)
			(vias allowed)
			(pads allowed)
			(copperpour not_allowed)
			(footprints allowed)
		)
		(placement
			(enabled no)
			(sheetname "")
		)
		(fill yes
			(thermal_gap 0.5)
			(thermal_bridge_width 0.5)
			(island_removal_mode 0)
		)
		(polygon
			(pts
				(arc
					(start 192.520824 -129.419604)
					(mid 192.035811 -128.93421)
					(end 191.550544 -129.41935)
				)
				(arc
					(start 191.550544 -130.56235)
					(mid 192.035684 -131.04749)
					(end 192.520824 -130.56235)
				)
			)
		)
	)
	(zone
		(layers "In1.Cu" "In3.Cu" "In4.Cu" "In6.Cu")
		(hatch none 0.5)
		(connect_pads
			(clearance 0)
		)
		(min_thickness 0.25)
		(keepout
			(tracks not_allowed)
			(vias allowed)
			(pads allowed)
			(copperpour not_allowed)
			(footprints allowed)
		)
		(placement
			(enabled no)
			(sheetname "")
		)
		(fill yes
			(thermal_gap 0.5)
			(thermal_bridge_width 0.5)
			(island_removal_mode 0)
		)
		(polygon
			(pts
				(arc
					(start 96.094042 -18.11528)
					(mid 95.609029 -17.629886)
					(end 95.123762 -18.115026)
				)
				(arc
					(start 95.123762 -19.385026)
					(mid 95.608902 -19.870166)
					(end 96.094042 -19.385026)
				)
			)
		)
	)
	(zone
		(layers "In1.Cu" "In3.Cu" "In4.Cu" "In6.Cu")
		(hatch none 0.5)
		(connect_pads
			(clearance 0)
		)
		(min_thickness 0.25)
		(keepout
			(tracks not_allowed)
			(vias allowed)
			(pads allowed)
			(copperpour not_allowed)
			(footprints allowed)
		)
		(placement
			(enabled no)
			(sheetname "")
		)
		(fill yes
			(thermal_gap 0.5)
			(thermal_bridge_width 0.5)
			(island_removal_mode 0)
		)
		(polygon
			(pts
				(arc
					(start 287.83661 -221.243144)
					(mid 288.38525 -220.694504)
					(end 287.83661 -220.145864)
				)
				(arc
					(start 286.436562 -220.145864)
					(mid 285.887922 -220.694504)
					(end 286.436562 -221.243144)
				)
			)
		)
	)
	(zone
		(layers "In1.Cu" "In3.Cu" "In4.Cu" "In6.Cu")
		(hatch none 0.5)
		(connect_pads
			(clearance 0)
		)
		(min_thickness 0.25)
		(keepout
			(tracks not_allowed)
			(vias allowed)
			(pads allowed)
			(copperpour not_allowed)
			(footprints allowed)
		)
		(placement
			(enabled no)
			(sheetname "")
		)
		(fill yes
			(thermal_gap 0.5)
			(thermal_bridge_width 0.5)
			(island_removal_mode 0)
		)
		(polygon
			(pts
				(arc
					(start 413.864806 -128.141984)
					(mid 413.379412 -128.626997)
					(end 413.864552 -129.112264)
				)
				(arc
					(start 415.007552 -129.112264)
					(mid 415.492692 -128.627124)
					(end 415.007552 -128.141984)
				)
			)
		)
	)
	(zone
		(layers "In1.Cu" "In3.Cu" "In4.Cu" "In6.Cu")
		(hatch none 0.5)
		(connect_pads
			(clearance 0)
		)
		(min_thickness 0.25)
		(keepout
			(tracks not_allowed)
			(vias allowed)
			(pads allowed)
			(copperpour not_allowed)
			(footprints allowed)
		)
		(placement
			(enabled no)
			(sheetname "")
		)
		(fill yes
			(thermal_gap 0.5)
			(thermal_bridge_width 0.5)
			(island_removal_mode 0)
		)
		(polygon
			(pts
				(arc
					(start 284.236668 -145.243042)
					(mid 284.785308 -144.694402)
					(end 284.236668 -144.145762)
				)
				(arc
					(start 282.83662 -144.145762)
					(mid 282.28798 -144.694402)
					(end 282.83662 -145.243042)
				)
			)
		)
	)
	(zone
		(layers "In1.Cu" "In3.Cu" "In4.Cu" "In6.Cu")
		(hatch none 0.5)
		(connect_pads
			(clearance 0)
		)
		(min_thickness 0.25)
		(keepout
			(tracks not_allowed)
			(vias allowed)
			(pads allowed)
			(copperpour not_allowed)
			(footprints allowed)
		)
		(placement
			(enabled no)
			(sheetname "")
		)
		(fill yes
			(thermal_gap 0.5)
			(thermal_bridge_width 0.5)
			(island_removal_mode 0)
		)
		(polygon
			(pts
				(arc
					(start 355.624892 -248.115328)
					(mid 355.139879 -247.629934)
					(end 354.654612 -248.115074)
				)
				(arc
					(start 354.654612 -249.385074)
					(mid 355.139752 -249.870214)
					(end 355.624892 -249.385074)
				)
			)
		)
	)
	(zone
		(layers "In1.Cu" "In3.Cu" "In4.Cu" "In6.Cu")
		(hatch none 0.5)
		(connect_pads
			(clearance 0)
		)
		(min_thickness 0.25)
		(keepout
			(tracks not_allowed)
			(vias allowed)
			(pads allowed)
			(copperpour not_allowed)
			(footprints allowed)
		)
		(placement
			(enabled no)
			(sheetname "")
		)
		(fill yes
			(thermal_gap 0.5)
			(thermal_bridge_width 0.5)
			(island_removal_mode 0)
		)
		(polygon
			(pts
				(arc
					(start 286.836612 -205.043024)
					(mid 287.385252 -204.494384)
					(end 286.836612 -203.945744)
				)
				(arc
					(start 285.436564 -203.945744)
					(mid 284.887924 -204.494384)
					(end 285.436564 -205.043024)
				)
			)
		)
	)
	(zone
		(layers "In1.Cu" "In3.Cu" "In4.Cu" "In6.Cu")
		(hatch none 0.5)
		(connect_pads
			(clearance 0)
		)
		(min_thickness 0.25)
		(keepout
			(tracks not_allowed)
			(vias allowed)
			(pads allowed)
			(copperpour not_allowed)
			(footprints allowed)
		)
		(placement
			(enabled no)
			(sheetname "")
		)
		(fill yes
			(thermal_gap 0.5)
			(thermal_bridge_width 0.5)
			(island_removal_mode 0)
		)
		(polygon
			(pts
				(arc
					(start 127.64389 -133.11505)
					(mid 127.15875 -132.62991)
					(end 126.67361 -133.11505)
				)
				(arc
					(start 126.67361 -134.384796)
					(mid 127.158623 -134.87019)
					(end 127.64389 -134.38505)
				)
			)
		)
	)
	(zone
		(layers "In1.Cu" "In3.Cu" "In4.Cu" "In6.Cu")
		(hatch none 0.5)
		(connect_pads
			(clearance 0)
		)
		(min_thickness 0.25)
		(keepout
			(tracks not_allowed)
			(vias allowed)
			(pads allowed)
			(copperpour not_allowed)
			(footprints allowed)
		)
		(placement
			(enabled no)
			(sheetname "")
		)
		(fill yes
			(thermal_gap 0.5)
			(thermal_bridge_width 0.5)
			(island_removal_mode 0)
		)
		(polygon
			(pts
				(arc
					(start 280.636726 -228.443028)
					(mid 281.185366 -227.894388)
					(end 280.636726 -227.345748)
				)
				(arc
					(start 279.236678 -227.345748)
					(mid 278.688038 -227.894388)
					(end 279.236678 -228.443028)
				)
			)
		)
	)
	(zone
		(layers "In1.Cu" "In3.Cu" "In4.Cu" "In6.Cu")
		(hatch none 0.5)
		(connect_pads
			(clearance 0)
		)
		(min_thickness 0.25)
		(keepout
			(tracks not_allowed)
			(vias allowed)
			(pads allowed)
			(copperpour not_allowed)
			(footprints allowed)
		)
		(placement
			(enabled no)
			(sheetname "")
		)
		(fill yes
			(thermal_gap 0.5)
			(thermal_bridge_width 0.5)
			(island_removal_mode 0)
		)
		(polygon
			(pts
				(arc
					(start 279.636728 -215.843104)
					(mid 280.185368 -215.294464)
					(end 279.636728 -214.745824)
				)
				(arc
					(start 278.23668 -214.745824)
					(mid 277.68804 -215.294464)
					(end 278.23668 -215.843104)
				)
			)
		)
	)
	(zone
		(layers "In1.Cu" "In3.Cu" "In4.Cu" "In6.Cu")
		(hatch none 0.5)
		(connect_pads
			(clearance 0)
		)
		(min_thickness 0.25)
		(keepout
			(tracks not_allowed)
			(vias allowed)
			(pads allowed)
			(copperpour not_allowed)
			(footprints allowed)
		)
		(placement
			(enabled no)
			(sheetname "")
		)
		(fill yes
			(thermal_gap 0.5)
			(thermal_bridge_width 0.5)
			(island_removal_mode 0)
		)
		(polygon
			(pts
				(arc
					(start 217.748612 -77.600302)
					(mid 217.200099 -77.051408)
					(end 216.651332 -77.600048)
				)
				(arc
					(start 216.651332 -78.999842)
					(mid 217.199972 -79.548482)
					(end 217.748612 -78.999842)
				)
			)
		)
	)
	(zone
		(layers "In1.Cu" "In3.Cu" "In4.Cu" "In6.Cu")
		(hatch none 0.5)
		(connect_pads
			(clearance 0)
		)
		(min_thickness 0.25)
		(keepout
			(tracks not_allowed)
			(vias allowed)
			(pads allowed)
			(copperpour not_allowed)
			(footprints allowed)
		)
		(placement
			(enabled no)
			(sheetname "")
		)
		(fill yes
			(thermal_gap 0.5)
			(thermal_bridge_width 0.5)
			(island_removal_mode 0)
		)
		(polygon
			(pts
				(arc
					(start 159.193992 -18.11528)
					(mid 158.708979 -17.629886)
					(end 158.223712 -18.115026)
				)
				(arc
					(start 158.223712 -19.385026)
					(mid 158.708852 -19.870166)
					(end 159.193992 -19.385026)
				)
			)
		)
	)
	(zone
		(layers "In1.Cu" "In3.Cu" "In4.Cu" "In6.Cu")
		(hatch none 0.5)
		(connect_pads
			(clearance 0)
		)
		(min_thickness 0.25)
		(keepout
			(tracks not_allowed)
			(vias allowed)
			(pads allowed)
			(copperpour not_allowed)
			(footprints allowed)
		)
		(placement
			(enabled no)
			(sheetname "")
		)
		(fill yes
			(thermal_gap 0.5)
			(thermal_bridge_width 0.5)
			(island_removal_mode 0)
		)
		(polygon
			(pts
				(arc
					(start 280.636726 -196.043042)
					(mid 281.185366 -195.494402)
					(end 280.636726 -194.945762)
				)
				(arc
					(start 279.236678 -194.945762)
					(mid 278.688038 -195.494402)
					(end 279.236678 -196.043042)
				)
			)
		)
	)
	(zone
		(layers "In1.Cu" "In3.Cu" "In4.Cu" "In6.Cu")
		(hatch none 0.5)
		(connect_pads
			(clearance 0)
		)
		(min_thickness 0.25)
		(keepout
			(tracks not_allowed)
			(vias allowed)
			(pads allowed)
			(copperpour not_allowed)
			(footprints allowed)
		)
		(placement
			(enabled no)
			(sheetname "")
		)
		(fill yes
			(thermal_gap 0.5)
			(thermal_bridge_width 0.5)
			(island_removal_mode 0)
		)
		(polygon
			(pts
				(arc
					(start 319.214754 -128.141984)
					(mid 318.72936 -128.626997)
					(end 319.2145 -129.112264)
				)
				(arc
					(start 320.3575 -129.112264)
					(mid 320.84264 -128.627124)
					(end 320.3575 -128.141984)
				)
			)
		)
	)
	(zone
		(layers "In1.Cu" "In3.Cu" "In4.Cu" "In6.Cu")
		(hatch none 0.5)
		(connect_pads
			(clearance 0)
		)
		(min_thickness 0.25)
		(keepout
			(tracks not_allowed)
			(vias allowed)
			(pads allowed)
			(copperpour not_allowed)
			(footprints allowed)
		)
		(placement
			(enabled no)
			(sheetname "")
		)
		(fill yes
			(thermal_gap 0.5)
			(thermal_bridge_width 0.5)
			(island_removal_mode 0)
		)
		(polygon
			(pts
				(arc
					(start 287.83661 -134.442962)
					(mid 288.38525 -133.894322)
					(end 287.83661 -133.345682)
				)
				(arc
					(start 286.436562 -133.345682)
					(mid 285.887922 -133.894322)
					(end 286.436562 -134.442962)
				)
			)
		)
	)
	(zone
		(layers "In1.Cu" "In3.Cu" "In4.Cu" "In6.Cu")
		(hatch none 0.5)
		(connect_pads
			(clearance 0)
		)
		(min_thickness 0.25)
		(keepout
			(tracks not_allowed)
			(vias allowed)
			(pads allowed)
			(copperpour not_allowed)
			(footprints allowed)
		)
		(placement
			(enabled no)
			(sheetname "")
		)
		(fill yes
			(thermal_gap 0.5)
			(thermal_bridge_width 0.5)
			(island_removal_mode 0)
		)
		(polygon
			(pts
				(arc
					(start 212.348826 -65.600072)
					(mid 211.800186 -65.051432)
					(end 211.251546 -65.600072)
				)
				(arc
					(start 211.251546 -66.999612)
					(mid 211.800059 -67.548506)
					(end 212.348826 -66.999866)
				)
			)
		)
	)
	(zone
		(layers "In1.Cu" "In3.Cu" "In4.Cu" "In6.Cu")
		(hatch none 0.5)
		(connect_pads
			(clearance 0)
		)
		(min_thickness 0.25)
		(keepout
			(tracks not_allowed)
			(vias allowed)
			(pads allowed)
			(copperpour not_allowed)
			(footprints allowed)
		)
		(placement
			(enabled no)
			(sheetname "")
		)
		(fill yes
			(thermal_gap 0.5)
			(thermal_bridge_width 0.5)
			(island_removal_mode 0)
		)
		(polygon
			(pts
				(arc
					(start 192.520824 -14.41958)
					(mid 192.035811 -13.934186)
					(end 191.550544 -14.419326)
				)
				(arc
					(start 191.550544 -15.562326)
					(mid 192.035684 -16.047466)
					(end 192.520824 -15.562326)
				)
			)
		)
	)
	(zone
		(layers "In1.Cu" "In3.Cu" "In4.Cu" "In6.Cu")
		(hatch none 0.5)
		(connect_pads
			(clearance 0)
		)
		(min_thickness 0.25)
		(keepout
			(tracks not_allowed)
			(vias allowed)
			(pads allowed)
			(copperpour not_allowed)
			(footprints allowed)
		)
		(placement
			(enabled no)
			(sheetname "")
		)
		(fill yes
			(thermal_gap 0.5)
			(thermal_bridge_width 0.5)
			(island_removal_mode 0)
		)
		(polygon
			(pts
				(arc
					(start 64.54394 -248.115328)
					(mid 64.058927 -247.629934)
					(end 63.57366 -248.115074)
				)
				(arc
					(start 63.57366 -249.385074)
					(mid 64.0588 -249.870214)
					(end 64.54394 -249.385074)
				)
			)
		)
	)
	(zone
		(layers "In1.Cu" "In3.Cu" "In4.Cu" "In6.Cu")
		(hatch none 0.5)
		(connect_pads
			(clearance 0)
		)
		(min_thickness 0.25)
		(keepout
			(tracks not_allowed)
			(vias allowed)
			(pads allowed)
			(copperpour not_allowed)
			(footprints allowed)
		)
		(placement
			(enabled no)
			(sheetname "")
		)
		(fill yes
			(thermal_gap 0.5)
			(thermal_bridge_width 0.5)
			(island_removal_mode 0)
		)
		(polygon
			(pts
				(arc
					(start 480.431856 -131.951984)
					(mid 479.946462 -132.436997)
					(end 480.431602 -132.922264)
				)
				(arc
					(start 481.701602 -132.922264)
					(mid 482.186742 -132.437124)
					(end 481.701602 -131.951984)
				)
			)
		)
	)
	(zone
		(layers "In1.Cu" "In3.Cu" "In4.Cu" "In6.Cu")
		(hatch none 0.5)
		(connect_pads
			(clearance 0)
		)
		(min_thickness 0.25)
		(keepout
			(tracks not_allowed)
			(vias allowed)
			(pads allowed)
			(copperpour not_allowed)
			(footprints allowed)
		)
		(placement
			(enabled no)
			(sheetname "")
		)
		(fill yes
			(thermal_gap 0.5)
			(thermal_bridge_width 0.5)
			(island_removal_mode 0)
		)
		(polygon
			(pts
				(arc
					(start 286.836612 -143.442944)
					(mid 287.385252 -142.894304)
					(end 286.836612 -142.345664)
				)
				(arc
					(start 285.436564 -142.345664)
					(mid 284.887924 -142.894304)
					(end 285.436564 -143.442944)
				)
			)
		)
	)
	(zone
		(layers "In1.Cu" "In3.Cu" "In4.Cu" "In6.Cu")
		(hatch none 0.5)
		(connect_pads
			(clearance 0)
		)
		(min_thickness 0.25)
		(keepout
			(tracks not_allowed)
			(vias allowed)
			(pads allowed)
			(copperpour not_allowed)
			(footprints allowed)
		)
		(placement
			(enabled no)
			(sheetname "")
		)
		(fill yes
			(thermal_gap 0.5)
			(thermal_bridge_width 0.5)
			(island_removal_mode 0)
		)
		(polygon
			(pts
				(arc
					(start 286.836612 -183.443118)
					(mid 287.385252 -182.894478)
					(end 286.836612 -182.345838)
				)
				(arc
					(start 285.436564 -182.345838)
					(mid 284.887924 -182.894478)
					(end 285.436564 -183.443118)
				)
			)
		)
	)
	(zone
		(layers "In1.Cu" "In3.Cu" "In4.Cu" "In6.Cu")
		(hatch none 0.5)
		(connect_pads
			(clearance 0)
		)
		(min_thickness 0.25)
		(keepout
			(tracks not_allowed)
			(vias allowed)
			(pads allowed)
			(copperpour not_allowed)
			(footprints allowed)
		)
		(placement
			(enabled no)
			(sheetname "")
		)
		(fill yes
			(thermal_gap 0.5)
			(thermal_bridge_width 0.5)
			(island_removal_mode 0)
		)
		(polygon
			(pts
				(arc
					(start 280.636726 -185.243216)
					(mid 281.185366 -184.694576)
					(end 280.636726 -184.145936)
				)
				(arc
					(start 279.236678 -184.145936)
					(mid 278.688038 -184.694576)
					(end 279.236678 -185.243216)
				)
			)
		)
	)
	(zone
		(layers "In1.Cu" "In3.Cu" "In4.Cu" "In6.Cu")
		(hatch none 0.5)
		(connect_pads
			(clearance 0)
		)
		(min_thickness 0.25)
		(keepout
			(tracks not_allowed)
			(vias allowed)
			(pads allowed)
			(copperpour not_allowed)
			(footprints allowed)
		)
		(placement
			(enabled no)
			(sheetname "")
		)
		(fill yes
			(thermal_gap 0.5)
			(thermal_bridge_width 0.5)
			(island_removal_mode 0)
		)
		(polygon
			(pts
				(arc
					(start 481.824792 -248.115328)
					(mid 481.339779 -247.629934)
					(end 480.854512 -248.115074)
				)
				(arc
					(start 480.854512 -249.385074)
					(mid 481.339652 -249.870214)
					(end 481.824792 -249.385074)
				)
			)
		)
	)
	(zone
		(layers "In1.Cu" "In3.Cu" "In4.Cu" "In6.Cu")
		(hatch none 0.5)
		(connect_pads
			(clearance 0)
		)
		(min_thickness 0.25)
		(keepout
			(tracks not_allowed)
			(vias allowed)
			(pads allowed)
			(copperpour not_allowed)
			(footprints allowed)
		)
		(placement
			(enabled no)
			(sheetname "")
		)
		(fill yes
			(thermal_gap 0.5)
			(thermal_bridge_width 0.5)
			(island_removal_mode 0)
		)
		(polygon
			(pts
				(arc
					(start 286.836612 -179.843176)
					(mid 287.385252 -179.294536)
					(end 286.836612 -178.745896)
				)
				(arc
					(start 285.436564 -178.745896)
					(mid 284.887924 -179.294536)
					(end 285.436564 -179.843176)
				)
			)
		)
	)
	(zone
		(layers "In1.Cu" "In3.Cu" "In4.Cu" "In6.Cu")
		(hatch none 0.5)
		(connect_pads
			(clearance 0)
		)
		(min_thickness 0.25)
		(keepout
			(tracks not_allowed)
			(vias allowed)
			(pads allowed)
			(copperpour not_allowed)
			(footprints allowed)
		)
		(placement
			(enabled no)
			(sheetname "")
		)
		(fill yes
			(thermal_gap 0.5)
			(thermal_bridge_width 0.5)
			(island_removal_mode 0)
		)
		(polygon
			(pts
				(arc
					(start 129.42062 -244.419374)
					(mid 128.93548 -243.934234)
					(end 128.45034 -244.419374)
				)
				(arc
					(start 128.45034 -245.56212)
					(mid 128.935353 -246.047514)
					(end 129.42062 -245.562374)
				)
			)
		)
	)
	(zone
		(layers "In1.Cu" "In3.Cu" "In4.Cu" "In6.Cu")
		(hatch none 0.5)
		(connect_pads
			(clearance 0)
		)
		(min_thickness 0.25)
		(keepout
			(tracks not_allowed)
			(vias allowed)
			(pads allowed)
			(copperpour not_allowed)
			(footprints allowed)
		)
		(placement
			(enabled no)
			(sheetname "")
		)
		(fill yes
			(thermal_gap 0.5)
			(thermal_bridge_width 0.5)
			(island_removal_mode 0)
		)
		(polygon
			(pts
				(arc
					(start 279.636728 -237.44301)
					(mid 280.185368 -236.89437)
					(end 279.636728 -236.34573)
				)
				(arc
					(start 278.23668 -236.34573)
					(mid 277.68804 -236.89437)
					(end 278.23668 -237.44301)
				)
			)
		)
	)
	(zone
		(layers "In1.Cu" "In3.Cu" "In4.Cu" "In6.Cu")
		(hatch none 0.5)
		(connect_pads
			(clearance 0)
		)
		(min_thickness 0.25)
		(keepout
			(tracks not_allowed)
			(vias allowed)
			(pads allowed)
			(copperpour not_allowed)
			(footprints allowed)
		)
		(placement
			(enabled no)
			(sheetname "")
		)
		(fill yes
			(thermal_gap 0.5)
			(thermal_bridge_width 0.5)
			(island_removal_mode 0)
		)
		(polygon
			(pts
				(arc
					(start 280.636726 -239.243108)
					(mid 281.185366 -238.694468)
					(end 280.636726 -238.145828)
				)
				(arc
					(start 279.236678 -238.145828)
					(mid 278.688038 -238.694468)
					(end 279.236678 -239.243108)
				)
			)
		)
	)
	(zone
		(layers "In1.Cu" "In3.Cu" "In4.Cu" "In6.Cu")
		(hatch none 0.5)
		(connect_pads
			(clearance 0)
		)
		(min_thickness 0.25)
		(keepout
			(tracks not_allowed)
			(vias allowed)
			(pads allowed)
			(copperpour not_allowed)
			(footprints allowed)
		)
		(placement
			(enabled no)
			(sheetname "")
		)
		(fill yes
			(thermal_gap 0.5)
			(thermal_bridge_width 0.5)
			(island_removal_mode 0)
		)
		(polygon
			(pts
				(arc
					(start 279.636728 -197.84314)
					(mid 280.185368 -197.2945)
					(end 279.636728 -196.74586)
				)
				(arc
					(start 278.23668 -196.74586)
					(mid 277.68804 -197.2945)
					(end 278.23668 -197.84314)
				)
			)
		)
	)
	(zone
		(layers "In1.Cu" "In3.Cu" "In4.Cu" "In6.Cu")
		(hatch none 0.5)
		(connect_pads
			(clearance 0)
		)
		(min_thickness 0.25)
		(keepout
			(tracks not_allowed)
			(vias allowed)
			(pads allowed)
			(copperpour not_allowed)
			(footprints allowed)
		)
		(placement
			(enabled no)
			(sheetname "")
		)
		(fill yes
			(thermal_gap 0.5)
			(thermal_bridge_width 0.5)
			(island_removal_mode 0)
		)
		(polygon
			(pts
				(arc
					(start 387.17474 -248.115328)
					(mid 386.689727 -247.629934)
					(end 386.20446 -248.115074)
				)
				(arc
					(start 386.20446 -249.385074)
					(mid 386.6896 -249.870214)
					(end 387.17474 -249.385074)
				)
			)
		)
	)
	(zone
		(layers "In1.Cu" "In3.Cu" "In4.Cu" "In6.Cu")
		(hatch none 0.5)
		(connect_pads
			(clearance 0)
		)
		(min_thickness 0.25)
		(keepout
			(tracks not_allowed)
			(vias allowed)
			(pads allowed)
			(copperpour not_allowed)
			(footprints allowed)
		)
		(placement
			(enabled no)
			(sheetname "")
		)
		(fill yes
			(thermal_gap 0.5)
			(thermal_bridge_width 0.5)
			(island_removal_mode 0)
		)
		(polygon
			(pts
				(arc
					(start 286.836612 -194.243198)
					(mid 287.385252 -193.694558)
					(end 286.836612 -193.145918)
				)
				(arc
					(start 285.436564 -193.145918)
					(mid 284.887924 -193.694558)
					(end 285.436564 -194.243198)
				)
			)
		)
	)
	(zone
		(layers "In1.Cu" "In3.Cu" "In4.Cu" "In6.Cu")
		(hatch none 0.5)
		(connect_pads
			(clearance 0)
		)
		(min_thickness 0.25)
		(keepout
			(tracks not_allowed)
			(vias allowed)
			(pads allowed)
			(copperpour not_allowed)
			(footprints allowed)
		)
		(placement
			(enabled no)
			(sheetname "")
		)
		(fill yes
			(thermal_gap 0.5)
			(thermal_bridge_width 0.5)
			(island_removal_mode 0)
		)
		(polygon
			(pts
				(arc
					(start 280.636726 -235.643166)
					(mid 281.185366 -235.094526)
					(end 280.636726 -234.545886)
				)
				(arc
					(start 279.236678 -234.545886)
					(mid 278.688038 -235.094526)
					(end 279.236678 -235.643166)
				)
			)
		)
	)
	(zone
		(layers "In1.Cu" "In3.Cu" "In4.Cu" "In6.Cu")
		(hatch none 0.5)
		(connect_pads
			(clearance 0)
		)
		(min_thickness 0.25)
		(keepout
			(tracks not_allowed)
			(vias allowed)
			(pads allowed)
			(copperpour not_allowed)
			(footprints allowed)
		)
		(placement
			(enabled no)
			(sheetname "")
		)
		(fill yes
			(thermal_gap 0.5)
			(thermal_bridge_width 0.5)
			(island_removal_mode 0)
		)
		(polygon
			(pts
				(arc
					(start 96.094042 -133.11505)
					(mid 95.608902 -132.62991)
					(end 95.123762 -133.11505)
				)
				(arc
					(start 95.123762 -134.384796)
					(mid 95.608775 -134.87019)
					(end 96.094042 -134.38505)
				)
			)
		)
	)
	(zone
		(layers "In1.Cu" "In3.Cu" "In4.Cu" "In6.Cu")
		(hatch none 0.5)
		(connect_pads
			(clearance 0)
		)
		(min_thickness 0.25)
		(keepout
			(tracks not_allowed)
			(vias allowed)
			(pads allowed)
			(copperpour not_allowed)
			(footprints allowed)
		)
		(placement
			(enabled no)
			(sheetname "")
		)
		(fill yes
			(thermal_gap 0.5)
			(thermal_bridge_width 0.5)
			(island_removal_mode 0)
		)
		(polygon
			(pts
				(arc
					(start 286.836612 -197.84314)
					(mid 287.385252 -197.2945)
					(end 286.836612 -196.74586)
				)
				(arc
					(start 285.436564 -196.74586)
					(mid 284.887924 -197.2945)
					(end 285.436564 -197.84314)
				)
			)
		)
	)
	(zone
		(layers "In1.Cu" "In3.Cu" "In4.Cu" "In6.Cu")
		(hatch none 0.5)
		(connect_pads
			(clearance 0)
		)
		(min_thickness 0.25)
		(keepout
			(tracks not_allowed)
			(vias allowed)
			(pads allowed)
			(copperpour not_allowed)
			(footprints allowed)
		)
		(placement
			(enabled no)
			(sheetname "")
		)
		(fill yes
			(thermal_gap 0.5)
			(thermal_bridge_width 0.5)
			(island_removal_mode 0)
		)
		(polygon
			(pts
				(arc
					(start 450.151246 -17.92224)
					(mid 450.63664 -17.437227)
					(end 450.1515 -16.95196)
				)
				(arc
					(start 448.8815 -16.95196)
					(mid 448.39636 -17.4371)
					(end 448.8815 -17.92224)
				)
			)
		)
	)
	(zone
		(layers "In1.Cu" "In3.Cu" "In4.Cu" "In6.Cu")
		(hatch none 0.5)
		(connect_pads
			(clearance 0)
		)
		(min_thickness 0.25)
		(keepout
			(tracks not_allowed)
			(vias allowed)
			(pads allowed)
			(copperpour not_allowed)
			(footprints allowed)
		)
		(placement
			(enabled no)
			(sheetname "")
		)
		(fill yes
			(thermal_gap 0.5)
			(thermal_bridge_width 0.5)
			(island_removal_mode 0)
		)
		(polygon
			(pts
				(arc
					(start 287.83661 -203.24318)
					(mid 288.38525 -202.69454)
					(end 287.83661 -202.1459)
				)
				(arc
					(start 286.436562 -202.1459)
					(mid 285.887922 -202.69454)
					(end 286.436562 -203.24318)
				)
			)
		)
	)
	(zone
		(layers "In1.Cu" "In3.Cu" "In4.Cu" "In6.Cu")
		(hatch none 0.5)
		(connect_pads
			(clearance 0)
		)
		(min_thickness 0.25)
		(keepout
			(tracks not_allowed)
			(vias allowed)
			(pads allowed)
			(copperpour not_allowed)
			(footprints allowed)
		)
		(placement
			(enabled no)
			(sheetname "")
		)
		(fill yes
			(thermal_gap 0.5)
			(thermal_bridge_width 0.5)
			(island_removal_mode 0)
		)
		(polygon
			(pts
				(arc
					(start 286.436562 -223.682306)
					(mid 285.824422 -224.294446)
					(end 286.436562 -224.906586)
				)
				(arc
					(start 287.83661 -224.906586)
					(mid 288.44875 -224.294446)
					(end 287.83661 -223.682306)
				)
				(xy 286.436816 -223.682306)
			)
		)
	)
	(zone
		(layers "In1.Cu" "In3.Cu" "In4.Cu" "In6.Cu")
		(hatch none 0.5)
		(connect_pads
			(clearance 0)
		)
		(min_thickness 0.25)
		(keepout
			(tracks not_allowed)
			(vias allowed)
			(pads allowed)
			(copperpour not_allowed)
			(footprints allowed)
		)
		(placement
			(enabled no)
			(sheetname "")
		)
		(fill yes
			(thermal_gap 0.5)
			(thermal_bridge_width 0.5)
			(island_removal_mode 0)
		)
		(polygon
			(pts
				(arc
					(start 64.54394 -18.11528)
					(mid 64.058927 -17.629886)
					(end 63.57366 -18.115026)
				)
				(arc
					(start 63.57366 -19.385026)
					(mid 64.0588 -19.870166)
					(end 64.54394 -19.385026)
				)
			)
		)
	)
	(zone
		(layers "In1.Cu" "In3.Cu" "In4.Cu" "In6.Cu")
		(hatch none 0.5)
		(connect_pads
			(clearance 0)
		)
		(min_thickness 0.25)
		(keepout
			(tracks not_allowed)
			(vias allowed)
			(pads allowed)
			(copperpour not_allowed)
			(footprints allowed)
		)
		(placement
			(enabled no)
			(sheetname "")
		)
		(fill yes
			(thermal_gap 0.5)
			(thermal_bridge_width 0.5)
			(island_removal_mode 0)
		)
		(polygon
			(pts
				(arc
					(start 280.636726 -203.24318)
					(mid 281.185366 -202.69454)
					(end 280.636726 -202.1459)
				)
				(arc
					(start 279.236678 -202.1459)
					(mid 278.688038 -202.69454)
					(end 279.236678 -203.24318)
				)
			)
		)
	)
	(zone
		(layers "In1.Cu" "In3.Cu" "In4.Cu" "In6.Cu")
		(hatch none 0.5)
		(connect_pads
			(clearance 0)
		)
		(min_thickness 0.25)
		(keepout
			(tracks not_allowed)
			(vias allowed)
			(pads allowed)
			(copperpour not_allowed)
			(footprints allowed)
		)
		(placement
			(enabled no)
			(sheetname "")
		)
		(fill yes
			(thermal_gap 0.5)
			(thermal_bridge_width 0.5)
			(island_removal_mode 0)
		)
		(polygon
			(pts
				(arc
					(start 279.636728 -179.843176)
					(mid 280.185368 -179.294536)
					(end 279.636728 -178.745896)
				)
				(arc
					(start 278.23668 -178.745896)
					(mid 277.68804 -179.294536)
					(end 278.23668 -179.843176)
				)
			)
		)
	)
	(zone
		(layers "In1.Cu" "In3.Cu" "In4.Cu" "In6.Cu")
		(hatch none 0.5)
		(connect_pads
			(clearance 0)
		)
		(min_thickness 0.25)
		(keepout
			(tracks not_allowed)
			(vias allowed)
			(pads allowed)
			(copperpour not_allowed)
			(footprints allowed)
		)
		(placement
			(enabled no)
			(sheetname "")
		)
		(fill yes
			(thermal_gap 0.5)
			(thermal_bridge_width 0.5)
			(island_removal_mode 0)
		)
		(polygon
			(pts
				(arc
					(start 32.994092 -18.11528)
					(mid 32.509079 -17.629886)
					(end 32.023812 -18.115026)
				)
				(arc
					(start 32.023812 -19.385026)
					(mid 32.508952 -19.870166)
					(end 32.994092 -19.385026)
				)
			)
		)
	)
	(zone
		(layers "In1.Cu" "In3.Cu" "In4.Cu" "In6.Cu")
		(hatch none 0.5)
		(connect_pads
			(clearance 0)
		)
		(min_thickness 0.25)
		(keepout
			(tracks not_allowed)
			(vias allowed)
			(pads allowed)
			(copperpour not_allowed)
			(footprints allowed)
		)
		(placement
			(enabled no)
			(sheetname "")
		)
		(fill yes
			(thermal_gap 0.5)
			(thermal_bridge_width 0.5)
			(island_removal_mode 0)
		)
		(polygon
			(pts
				(arc
					(start 280.636726 -217.643202)
					(mid 281.185366 -217.094562)
					(end 280.636726 -216.545922)
				)
				(arc
					(start 279.236678 -216.545922)
					(mid 278.688038 -217.094562)
					(end 279.236678 -217.643202)
				)
			)
		)
	)
	(zone
		(layers "In1.Cu" "In3.Cu" "In4.Cu" "In6.Cu")
		(hatch none 0.5)
		(connect_pads
			(clearance 0)
		)
		(min_thickness 0.25)
		(keepout
			(tracks not_allowed)
			(vias allowed)
			(pads allowed)
			(copperpour not_allowed)
			(footprints allowed)
		)
		(placement
			(enabled no)
			(sheetname "")
		)
		(fill yes
			(thermal_gap 0.5)
			(thermal_bridge_width 0.5)
			(island_removal_mode 0)
		)
		(polygon
			(pts
				(arc
					(start 286.836612 -187.04306)
					(mid 287.385252 -186.49442)
					(end 286.836612 -185.94578)
				)
				(arc
					(start 285.436564 -185.94578)
					(mid 284.887924 -186.49442)
					(end 285.436564 -187.04306)
				)
			)
		)
	)
	(zone
		(layers "In1.Cu" "In3.Cu" "In4.Cu" "In6.Cu")
		(hatch none 0.5)
		(connect_pads
			(clearance 0)
		)
		(min_thickness 0.25)
		(keepout
			(tracks not_allowed)
			(vias allowed)
			(pads allowed)
			(copperpour not_allowed)
			(footprints allowed)
		)
		(placement
			(enabled no)
			(sheetname "")
		)
		(fill yes
			(thermal_gap 0.5)
			(thermal_bridge_width 0.5)
			(island_removal_mode 0)
		)
		(polygon
			(pts
				(arc
					(start 160.970722 -14.41958)
					(mid 160.485709 -13.934186)
					(end 160.000442 -14.419326)
				)
				(arc
					(start 160.000442 -15.562326)
					(mid 160.485582 -16.047466)
					(end 160.970722 -15.562326)
				)
			)
		)
	)
	(zone
		(layers "In1.Cu" "In3.Cu" "In4.Cu" "In6.Cu")
		(hatch none 0.5)
		(connect_pads
			(clearance 0)
		)
		(min_thickness 0.25)
		(keepout
			(tracks not_allowed)
			(vias allowed)
			(pads allowed)
			(copperpour not_allowed)
			(footprints allowed)
		)
		(placement
			(enabled no)
			(sheetname "")
		)
		(fill yes
			(thermal_gap 0.5)
			(thermal_bridge_width 0.5)
			(island_removal_mode 0)
		)
		(polygon
			(pts
				(arc
					(start 287.83661 -217.643202)
					(mid 288.38525 -217.094562)
					(end 287.83661 -216.545922)
				)
				(arc
					(start 286.436562 -216.545922)
					(mid 285.887922 -217.094562)
					(end 286.436562 -217.643202)
				)
			)
		)
	)
	(zone
		(layers "In1.Cu" "In3.Cu" "In4.Cu" "In6.Cu")
		(hatch none 0.5)
		(connect_pads
			(clearance 0)
		)
		(min_thickness 0.25)
		(keepout
			(tracks not_allowed)
			(vias allowed)
			(pads allowed)
			(copperpour not_allowed)
			(footprints allowed)
		)
		(placement
			(enabled no)
			(sheetname "")
		)
		(fill yes
			(thermal_gap 0.5)
			(thermal_bridge_width 0.5)
			(island_removal_mode 0)
		)
		(polygon
			(pts
				(arc
					(start 445.414654 -13.14196)
					(mid 444.92926 -13.626973)
					(end 445.4144 -14.11224)
				)
				(arc
					(start 446.5574 -14.11224)
					(mid 447.04254 -13.6271)
					(end 446.5574 -13.14196)
				)
			)
		)
	)
	(zone
		(layers "In1.Cu" "In3.Cu" "In4.Cu" "In6.Cu")
		(hatch none 0.5)
		(connect_pads
			(clearance 0)
		)
		(min_thickness 0.25)
		(keepout
			(tracks not_allowed)
			(vias allowed)
			(pads allowed)
			(copperpour not_allowed)
			(footprints allowed)
		)
		(placement
			(enabled no)
			(sheetname "")
		)
		(fill yes
			(thermal_gap 0.5)
			(thermal_bridge_width 0.5)
			(island_removal_mode 0)
		)
		(polygon
			(pts
				(arc
					(start 96.094042 -248.115328)
					(mid 95.609029 -247.629934)
					(end 95.123762 -248.115074)
				)
				(arc
					(start 95.123762 -249.385074)
					(mid 95.608902 -249.870214)
					(end 96.094042 -249.385074)
				)
			)
		)
	)
	(zone
		(layers "In1.Cu" "In3.Cu" "In4.Cu" "In6.Cu")
		(hatch none 0.5)
		(connect_pads
			(clearance 0)
		)
		(min_thickness 0.25)
		(keepout
			(tracks not_allowed)
			(vias allowed)
			(pads allowed)
			(copperpour not_allowed)
			(footprints allowed)
		)
		(placement
			(enabled no)
			(sheetname "")
		)
		(fill yes
			(thermal_gap 0.5)
			(thermal_bridge_width 0.5)
			(island_removal_mode 0)
		)
		(polygon
			(pts
				(arc
					(start 287.83661 -232.043224)
					(mid 288.38525 -231.494584)
					(end 287.83661 -230.945944)
				)
				(arc
					(start 286.436562 -230.945944)
					(mid 285.887922 -231.494584)
					(end 286.436562 -232.043224)
				)
			)
		)
	)
	(zone
		(layers "In1.Cu" "In3.Cu" "In4.Cu" "In6.Cu")
		(hatch none 0.5)
		(connect_pads
			(clearance 0)
		)
		(min_thickness 0.25)
		(keepout
			(tracks not_allowed)
			(vias allowed)
			(pads allowed)
			(copperpour not_allowed)
			(footprints allowed)
		)
		(placement
			(enabled no)
			(sheetname "")
		)
		(fill yes
			(thermal_gap 0.5)
			(thermal_bridge_width 0.5)
			(island_removal_mode 0)
		)
		(polygon
			(pts
				(arc
					(start 160.970722 -129.419604)
					(mid 160.485709 -128.93421)
					(end 160.000442 -129.41935)
				)
				(arc
					(start 160.000442 -130.56235)
					(mid 160.485582 -131.04749)
					(end 160.970722 -130.56235)
				)
			)
		)
	)
	(zone
		(layers "In1.Cu" "In3.Cu" "In4.Cu" "In6.Cu")
		(hatch none 0.5)
		(connect_pads
			(clearance 0)
		)
		(min_thickness 0.25)
		(keepout
			(tracks not_allowed)
			(vias allowed)
			(pads allowed)
			(copperpour not_allowed)
			(footprints allowed)
		)
		(placement
			(enabled no)
			(sheetname "")
		)
		(fill yes
			(thermal_gap 0.5)
			(thermal_bridge_width 0.5)
			(island_removal_mode 0)
		)
		(polygon
			(pts
				(arc
					(start 417.331906 -131.951984)
					(mid 416.846512 -132.436997)
					(end 417.331652 -132.922264)
				)
				(arc
					(start 418.601652 -132.922264)
					(mid 419.086792 -132.437124)
					(end 418.601652 -131.951984)
				)
			)
		)
	)
	(zone
		(layers "In1.Cu" "In3.Cu" "In4.Cu" "In6.Cu")
		(hatch none 0.5)
		(connect_pads
			(clearance 0)
		)
		(min_thickness 0.25)
		(keepout
			(tracks not_allowed)
			(vias allowed)
			(pads allowed)
			(copperpour not_allowed)
			(footprints allowed)
		)
		(placement
			(enabled no)
			(sheetname "")
		)
		(fill yes
			(thermal_gap 0.5)
			(thermal_bridge_width 0.5)
			(island_removal_mode 0)
		)
		(polygon
			(pts
				(arc
					(start 223.148652 -65.600326)
					(mid 222.600139 -65.051432)
					(end 222.051372 -65.600072)
				)
				(arc
					(start 222.051372 -66.999866)
					(mid 222.600012 -67.548506)
					(end 223.148652 -66.999866)
				)
			)
		)
	)
	(zone
		(layers "In1.Cu" "In3.Cu" "In4.Cu" "In6.Cu")
		(hatch none 0.5)
		(connect_pads
			(clearance 0)
		)
		(min_thickness 0.25)
		(keepout
			(tracks not_allowed)
			(vias allowed)
			(pads allowed)
			(copperpour not_allowed)
			(footprints allowed)
		)
		(placement
			(enabled no)
			(sheetname "")
		)
		(fill yes
			(thermal_gap 0.5)
			(thermal_bridge_width 0.5)
			(island_removal_mode 0)
		)
		(polygon
			(pts
				(arc
					(start 387.051296 -17.92224)
					(mid 387.53669 -17.437227)
					(end 387.05155 -16.95196)
				)
				(arc
					(start 385.78155 -16.95196)
					(mid 385.29641 -17.4371)
					(end 385.78155 -17.92224)
				)
			)
		)
	)
	(zone
		(layers "In1.Cu" "In3.Cu" "In4.Cu" "In6.Cu")
		(hatch none 0.5)
		(connect_pads
			(clearance 0)
		)
		(min_thickness 0.25)
		(keepout
			(tracks not_allowed)
			(vias allowed)
			(pads allowed)
			(copperpour not_allowed)
			(footprints allowed)
		)
		(placement
			(enabled no)
			(sheetname "")
		)
		(fill yes
			(thermal_gap 0.5)
			(thermal_bridge_width 0.5)
			(island_removal_mode 0)
		)
		(polygon
			(pts
				(arc
					(start 387.051296 -132.922264)
					(mid 387.53669 -132.437251)
					(end 387.05155 -131.951984)
				)
				(arc
					(start 385.78155 -131.951984)
					(mid 385.29641 -132.437124)
					(end 385.78155 -132.922264)
				)
			)
		)
	)
	(zone
		(layers "In1.Cu" "In3.Cu" "In4.Cu" "In6.Cu")
		(hatch none 0.5)
		(connect_pads
			(clearance 0)
		)
		(min_thickness 0.25)
		(keepout
			(tracks not_allowed)
			(vias allowed)
			(pads allowed)
			(copperpour not_allowed)
			(footprints allowed)
		)
		(placement
			(enabled no)
			(sheetname "")
		)
		(fill yes
			(thermal_gap 0.5)
			(thermal_bridge_width 0.5)
			(island_removal_mode 0)
		)
		(polygon
			(pts
				(arc
					(start 221.348808 -70.39991)
					(mid 220.800168 -69.85127)
					(end 220.251528 -70.39991)
				)
				(arc
					(start 220.251528 -71.799704)
					(mid 220.800041 -72.348598)
					(end 221.348808 -71.799958)
				)
			)
		)
	)
	(zone
		(layers "In1.Cu" "In3.Cu" "In4.Cu" "In6.Cu")
		(hatch none 0.5)
		(connect_pads
			(clearance 0)
		)
		(min_thickness 0.25)
		(keepout
			(tracks not_allowed)
			(vias allowed)
			(pads allowed)
			(copperpour not_allowed)
			(footprints allowed)
		)
		(placement
			(enabled no)
			(sheetname "")
		)
		(fill yes
			(thermal_gap 0.5)
			(thermal_bridge_width 0.5)
			(island_removal_mode 0)
		)
		(polygon
			(pts
				(arc
					(start 450.27469 -248.115328)
					(mid 449.789677 -247.629934)
					(end 449.30441 -248.115074)
				)
				(arc
					(start 449.30441 -249.385074)
					(mid 449.78955 -249.870214)
					(end 450.27469 -249.385074)
				)
			)
		)
	)
	(zone
		(layers "In1.Cu" "In3.Cu" "In4.Cu" "In6.Cu")
		(hatch none 0.5)
		(connect_pads
			(clearance 0)
		)
		(min_thickness 0.25)
		(keepout
			(tracks not_allowed)
			(vias allowed)
			(pads allowed)
			(copperpour not_allowed)
			(footprints allowed)
		)
		(placement
			(enabled no)
			(sheetname "")
		)
		(fill yes
			(thermal_gap 0.5)
			(thermal_bridge_width 0.5)
			(island_removal_mode 0)
		)
		(polygon
			(pts
				(arc
					(start 287.83661 -185.243216)
					(mid 288.38525 -184.694576)
					(end 287.83661 -184.145936)
				)
				(arc
					(start 286.436562 -184.145936)
					(mid 285.887922 -184.694576)
					(end 286.436562 -185.243216)
				)
			)
		)
	)
	(zone
		(layers "In1.Cu" "In3.Cu" "In4.Cu" "In6.Cu")
		(hatch none 0.5)
		(connect_pads
			(clearance 0)
		)
		(min_thickness 0.25)
		(keepout
			(tracks not_allowed)
			(vias allowed)
			(pads allowed)
			(copperpour not_allowed)
			(footprints allowed)
		)
		(placement
			(enabled no)
			(sheetname "")
		)
		(fill yes
			(thermal_gap 0.5)
			(thermal_bridge_width 0.5)
			(island_removal_mode 0)
		)
		(polygon
			(pts
				(arc
					(start 279.636728 -176.243234)
					(mid 280.185368 -175.694594)
					(end 279.636728 -175.145954)
				)
				(arc
					(start 278.23668 -175.145954)
					(mid 277.68804 -175.694594)
					(end 278.23668 -176.243234)
				)
			)
		)
	)
	(zone
		(layers "In1.Cu" "In3.Cu" "In4.Cu" "In6.Cu")
		(hatch none 0.5)
		(connect_pads
			(clearance 0)
		)
		(min_thickness 0.25)
		(keepout
			(tracks not_allowed)
			(vias allowed)
			(pads allowed)
			(copperpour not_allowed)
			(footprints allowed)
		)
		(placement
			(enabled no)
			(sheetname "")
		)
		(fill yes
			(thermal_gap 0.5)
			(thermal_bridge_width 0.5)
			(island_removal_mode 0)
		)
		(polygon
			(pts
				(arc
					(start 280.636726 -206.843122)
					(mid 281.185366 -206.294482)
					(end 280.636726 -205.745842)
				)
				(arc
					(start 279.236678 -205.745842)
					(mid 278.688038 -206.294482)
					(end 279.236678 -206.843122)
				)
			)
		)
	)
	(zone
		(layers "In1.Cu" "In3.Cu" "In4.Cu" "In6.Cu")
		(hatch none 0.5)
		(connect_pads
			(clearance 0)
		)
		(min_thickness 0.25)
		(keepout
			(tracks not_allowed)
			(vias allowed)
			(pads allowed)
			(copperpour not_allowed)
			(footprints allowed)
		)
		(placement
			(enabled no)
			(sheetname "")
		)
		(fill yes
			(thermal_gap 0.5)
			(thermal_bridge_width 0.5)
			(island_removal_mode 0)
		)
		(polygon
			(pts
				(arc
					(start 159.193992 -133.11505)
					(mid 158.708852 -132.62991)
					(end 158.223712 -133.11505)
				)
				(arc
					(start 158.223712 -134.384796)
					(mid 158.708725 -134.87019)
					(end 159.193992 -134.38505)
				)
			)
		)
	)
	(zone
		(layers "In1.Cu" "In3.Cu" "In4.Cu" "In6.Cu")
		(hatch none 0.5)
		(connect_pads
			(clearance 0)
		)
		(min_thickness 0.25)
		(keepout
			(tracks not_allowed)
			(vias allowed)
			(pads allowed)
			(copperpour not_allowed)
			(footprints allowed)
		)
		(placement
			(enabled no)
			(sheetname "")
		)
		(fill yes
			(thermal_gap 0.5)
			(thermal_bridge_width 0.5)
			(island_removal_mode 0)
		)
		(polygon
			(pts
				(arc
					(start 279.636728 -190.643002)
					(mid 280.185368 -190.094362)
					(end 279.636728 -189.545722)
				)
				(arc
					(start 278.23668 -189.545722)
					(mid 277.68804 -190.094362)
					(end 278.23668 -190.643002)
				)
			)
		)
	)
	(zone
		(layers "In1.Cu" "In3.Cu" "In4.Cu" "In6.Cu")
		(hatch none 0.5)
		(connect_pads
			(clearance 0)
		)
		(min_thickness 0.25)
		(keepout
			(tracks not_allowed)
			(vias allowed)
			(pads allowed)
			(copperpour not_allowed)
			(footprints allowed)
		)
		(placement
			(enabled no)
			(sheetname "")
		)
		(fill yes
			(thermal_gap 0.5)
			(thermal_bridge_width 0.5)
			(island_removal_mode 0)
		)
		(polygon
			(pts
				(arc
					(start 280.636726 -145.243042)
					(mid 281.185366 -144.694402)
					(end 280.636726 -144.145762)
				)
				(arc
					(start 279.236678 -144.145762)
					(mid 278.688038 -144.694402)
					(end 279.236678 -145.243042)
				)
			)
		)
	)
	(zone
		(layers "In1.Cu" "In3.Cu" "In4.Cu" "In6.Cu")
		(hatch none 0.5)
		(connect_pads
			(clearance 0)
		)
		(min_thickness 0.25)
		(keepout
			(tracks not_allowed)
			(vias allowed)
			(pads allowed)
			(copperpour not_allowed)
			(footprints allowed)
		)
		(placement
			(enabled no)
			(sheetname "")
		)
		(fill yes
			(thermal_gap 0.5)
			(thermal_bridge_width 0.5)
			(island_removal_mode 0)
		)
		(polygon
			(pts
				(arc
					(start 287.83661 -235.643166)
					(mid 288.38525 -235.094526)
					(end 287.83661 -234.545886)
				)
				(arc
					(start 286.436562 -234.545886)
					(mid 285.887922 -235.094526)
					(end 286.436562 -235.643166)
				)
			)
		)
	)
	(zone
		(layers "In1.Cu" "In3.Cu" "In4.Cu" "In6.Cu")
		(hatch none 0.5)
		(connect_pads
			(clearance 0)
		)
		(min_thickness 0.25)
		(keepout
			(tracks not_allowed)
			(vias allowed)
			(pads allowed)
			(copperpour not_allowed)
			(footprints allowed)
		)
		(placement
			(enabled no)
			(sheetname "")
		)
		(fill yes
			(thermal_gap 0.5)
			(thermal_bridge_width 0.5)
			(island_removal_mode 0)
		)
		(polygon
			(pts
				(arc
					(start 480.431856 -16.95196)
					(mid 479.946462 -17.436973)
					(end 480.431602 -17.92224)
				)
				(arc
					(start 481.701602 -17.92224)
					(mid 482.186742 -17.4371)
					(end 481.701602 -16.95196)
				)
			)
		)
	)
	(zone
		(layers "In1.Cu" "In3.Cu" "In4.Cu" "In6.Cu")
		(hatch none 0.5)
		(connect_pads
			(clearance 0)
		)
		(min_thickness 0.25)
		(keepout
			(tracks not_allowed)
			(vias allowed)
			(pads allowed)
			(copperpour not_allowed)
			(footprints allowed)
		)
		(placement
			(enabled no)
			(sheetname "")
		)
		(fill yes
			(thermal_gap 0.5)
			(thermal_bridge_width 0.5)
			(island_removal_mode 0)
		)
		(polygon
			(pts
				(arc
					(start 286.836612 -212.243162)
					(mid 287.385252 -211.694522)
					(end 286.836612 -211.145882)
				)
				(arc
					(start 285.436564 -211.145882)
					(mid 284.887924 -211.694522)
					(end 285.436564 -212.243162)
				)
			)
		)
	)
	(zone
		(layers "In1.Cu" "In3.Cu" "In4.Cu" "In6.Cu")
		(hatch none 0.5)
		(connect_pads
			(clearance 0)
		)
		(min_thickness 0.25)
		(keepout
			(tracks not_allowed)
			(vias allowed)
			(pads allowed)
			(copperpour not_allowed)
			(footprints allowed)
		)
		(placement
			(enabled no)
			(sheetname "")
		)
		(fill yes
			(thermal_gap 0.5)
			(thermal_bridge_width 0.5)
			(island_removal_mode 0)
		)
		(polygon
			(pts
				(arc
					(start 287.83661 -228.443028)
					(mid 288.38525 -227.894388)
					(end 287.83661 -227.345748)
				)
				(arc
					(start 286.436562 -227.345748)
					(mid 285.887922 -227.894388)
					(end 286.436562 -228.443028)
				)
			)
		)
	)
	(zone
		(layers "In1.Cu" "In3.Cu" "In4.Cu" "In6.Cu")
		(hatch none 0.5)
		(connect_pads
			(clearance 0)
		)
		(min_thickness 0.25)
		(keepout
			(tracks not_allowed)
			(vias allowed)
			(pads allowed)
			(copperpour not_allowed)
			(footprints allowed)
		)
		(placement
			(enabled no)
			(sheetname "")
		)
		(fill yes
			(thermal_gap 0.5)
			(thermal_bridge_width 0.5)
			(island_removal_mode 0)
		)
		(polygon
			(pts
				(arc
					(start 279.636728 -208.64322)
					(mid 280.185368 -208.09458)
					(end 279.636728 -207.54594)
				)
				(arc
					(start 278.23668 -207.54594)
					(mid 277.68804 -208.09458)
					(end 278.23668 -208.64322)
				)
			)
		)
	)
	(zone
		(layers "In1.Cu" "In3.Cu" "In4.Cu" "In6.Cu")
		(hatch none 0.5)
		(connect_pads
			(clearance 0)
		)
		(min_thickness 0.25)
		(keepout
			(tracks not_allowed)
			(vias allowed)
			(pads allowed)
			(copperpour not_allowed)
			(footprints allowed)
		)
		(placement
			(enabled no)
			(sheetname "")
		)
		(fill yes
			(thermal_gap 0.5)
			(thermal_bridge_width 0.5)
			(island_removal_mode 0)
		)
		(polygon
			(pts
				(arc
					(start 382.97739 -244.302534)
					(mid 382.49225 -243.817394)
					(end 382.00711 -244.302534)
				)
				(arc
					(start 382.00711 -245.44528)
					(mid 382.492123 -245.930674)
					(end 382.97739 -245.445534)
				)
			)
		)
	)
	(zone
		(layers "In1.Cu" "In3.Cu" "In4.Cu" "In6.Cu")
		(hatch none 0.5)
		(connect_pads
			(clearance 0)
		)
		(min_thickness 0.25)
		(keepout
			(tracks not_allowed)
			(vias allowed)
			(pads allowed)
			(copperpour not_allowed)
			(footprints allowed)
		)
		(placement
			(enabled no)
			(sheetname "")
		)
		(fill yes
			(thermal_gap 0.5)
			(thermal_bridge_width 0.5)
			(island_removal_mode 0)
		)
		(polygon
			(pts
				(arc
					(start 217.748612 -70.39991)
					(mid 217.199972 -69.85127)
					(end 216.651332 -70.39991)
				)
				(arc
					(start 216.651332 -71.799704)
					(mid 217.199845 -72.348598)
					(end 217.748612 -71.799958)
				)
			)
		)
	)
	(zone
		(layers "In1.Cu" "In3.Cu" "In4.Cu" "In6.Cu")
		(hatch none 0.5)
		(connect_pads
			(clearance 0)
		)
		(min_thickness 0.25)
		(keepout
			(tracks not_allowed)
			(vias allowed)
			(pads allowed)
			(copperpour not_allowed)
			(footprints allowed)
		)
		(placement
			(enabled no)
			(sheetname "")
		)
		(fill yes
			(thermal_gap 0.5)
			(thermal_bridge_width 0.5)
			(island_removal_mode 0)
		)
		(polygon
			(pts
				(arc
					(start 279.636728 -219.443046)
					(mid 280.185368 -218.894406)
					(end 279.636728 -218.345766)
				)
				(arc
					(start 278.23668 -218.345766)
					(mid 277.68804 -218.894406)
					(end 278.23668 -219.443046)
				)
			)
		)
	)
	(zone
		(layers "In1.Cu" "In3.Cu" "In4.Cu" "In6.Cu")
		(hatch none 0.5)
		(connect_pads
			(clearance 0)
		)
		(min_thickness 0.25)
		(keepout
			(tracks not_allowed)
			(vias allowed)
			(pads allowed)
			(copperpour not_allowed)
			(footprints allowed)
		)
		(placement
			(enabled no)
			(sheetname "")
		)
		(fill yes
			(thermal_gap 0.5)
			(thermal_bridge_width 0.5)
			(island_removal_mode 0)
		)
		(polygon
			(pts
				(arc
					(start 279.636728 -143.442944)
					(mid 280.185368 -142.894304)
					(end 279.636728 -142.345664)
				)
				(arc
					(start 278.23668 -142.345664)
					(mid 277.68804 -142.894304)
					(end 278.23668 -143.442944)
				)
			)
		)
	)
	(zone
		(layers "In1.Cu" "In3.Cu" "In4.Cu" "In6.Cu")
		(hatch none 0.5)
		(connect_pads
			(clearance 0)
		)
		(min_thickness 0.25)
		(keepout
			(tracks not_allowed)
			(vias allowed)
			(pads allowed)
			(copperpour not_allowed)
			(footprints allowed)
		)
		(placement
			(enabled no)
			(sheetname "")
		)
		(fill yes
			(thermal_gap 0.5)
			(thermal_bridge_width 0.5)
			(island_removal_mode 0)
		)
		(polygon
			(pts
				(arc
					(start 63.57366 -134.384796)
					(mid 64.058673 -134.87019)
					(end 64.54394 -134.38505)
				)
				(arc
					(start 64.54394 -133.11505)
					(mid 64.0588 -132.62991)
					(end 63.57366 -133.11505)
				)
			)
		)
	)
	(zone
		(layers "In1.Cu" "In3.Cu" "In4.Cu" "In6.Cu")
		(hatch none 0.5)
		(connect_pads
			(clearance 0)
		)
		(min_thickness 0.25)
		(keepout
			(tracks not_allowed)
			(vias allowed)
			(pads allowed)
			(copperpour not_allowed)
			(footprints allowed)
		)
		(placement
			(enabled no)
			(sheetname "")
		)
		(fill yes
			(thermal_gap 0.5)
			(thermal_bridge_width 0.5)
			(island_removal_mode 0)
		)
		(polygon
			(pts
				(arc
					(start 32.023812 -134.384796)
					(mid 32.508825 -134.87019)
					(end 32.994092 -134.38505)
				)
				(arc
					(start 32.994092 -133.11505)
					(mid 32.508952 -132.62991)
					(end 32.023812 -133.11505)
				)
			)
		)
	)
	(zone
		(layers "In1.Cu" "In3.Cu" "In4.Cu" "In6.Cu")
		(hatch none 0.5)
		(connect_pads
			(clearance 0)
		)
		(min_thickness 0.25)
		(keepout
			(tracks not_allowed)
			(vias allowed)
			(pads allowed)
			(copperpour not_allowed)
			(footprints allowed)
		)
		(placement
			(enabled no)
			(sheetname "")
		)
		(fill yes
			(thermal_gap 0.5)
			(thermal_bridge_width 0.5)
			(island_removal_mode 0)
		)
		(polygon
			(pts
				(arc
					(start 190.744094 -18.11528)
					(mid 190.259081 -17.629886)
					(end 189.773814 -18.115026)
				)
				(arc
					(start 189.773814 -19.385026)
					(mid 190.258954 -19.870166)
					(end 190.744094 -19.385026)
				)
			)
		)
	)
	(zone
		(layers "In1.Cu" "In3.Cu" "In4.Cu" "In6.Cu")
		(hatch none 0.5)
		(connect_pads
			(clearance 0)
		)
		(min_thickness 0.25)
		(keepout
			(tracks not_allowed)
			(vias allowed)
			(pads allowed)
			(copperpour not_allowed)
			(footprints allowed)
		)
		(placement
			(enabled no)
			(sheetname "")
		)
		(fill yes
			(thermal_gap 0.5)
			(thermal_bridge_width 0.5)
			(island_removal_mode 0)
		)
		(polygon
			(pts
				(arc
					(start 417.331906 -16.95196)
					(mid 416.846512 -17.436973)
					(end 417.331652 -17.92224)
				)
				(arc
					(start 418.601652 -17.92224)
					(mid 419.086792 -17.4371)
					(end 418.601652 -16.95196)
				)
			)
		)
	)
	(zone
		(layers "In1.Cu" "In3.Cu" "In4.Cu" "In6.Cu")
		(hatch none 0.5)
		(connect_pads
			(clearance 0)
		)
		(min_thickness 0.25)
		(keepout
			(tracks not_allowed)
			(vias allowed)
			(pads allowed)
			(copperpour not_allowed)
			(footprints allowed)
		)
		(placement
			(enabled no)
			(sheetname "")
		)
		(fill yes
			(thermal_gap 0.5)
			(thermal_bridge_width 0.5)
			(island_removal_mode 0)
		)
		(polygon
			(pts
				(arc
					(start 286.836612 -230.243126)
					(mid 287.385252 -229.694486)
					(end 286.836612 -229.145846)
				)
				(arc
					(start 285.436564 -229.145846)
					(mid 284.887924 -229.694486)
					(end 285.436564 -230.243126)
				)
			)
		)
	)
	(zone
		(layers "In1.Cu" "In3.Cu" "In4.Cu" "In6.Cu")
		(hatch none 0.5)
		(connect_pads
			(clearance 0)
		)
		(min_thickness 0.25)
		(keepout
			(tracks not_allowed)
			(vias allowed)
			(pads allowed)
			(copperpour not_allowed)
			(footprints allowed)
		)
		(placement
			(enabled no)
			(sheetname "")
		)
		(fill yes
			(thermal_gap 0.5)
			(thermal_bridge_width 0.5)
			(island_removal_mode 0)
		)
		(polygon
			(pts
				(arc
					(start 210.548728 -77.600302)
					(mid 210.000215 -77.051408)
					(end 209.451448 -77.600048)
				)
				(arc
					(start 209.451448 -78.999842)
					(mid 210.000088 -79.548482)
					(end 210.548728 -78.999842)
				)
			)
		)
	)
	(zone
		(layers "In1.Cu" "In3.Cu" "In4.Cu" "In6.Cu")
		(hatch none 0.5)
		(connect_pads
			(clearance 0)
		)
		(min_thickness 0.25)
		(keepout
			(tracks not_allowed)
			(vias allowed)
			(pads allowed)
			(copperpour not_allowed)
			(footprints allowed)
		)
		(placement
			(enabled no)
			(sheetname "")
		)
		(fill yes
			(thermal_gap 0.5)
			(thermal_bridge_width 0.5)
			(island_removal_mode 0)
		)
		(polygon
			(pts
				(arc
					(start 287.83661 -138.043158)
					(mid 288.38525 -137.494518)
					(end 287.83661 -136.945878)
				)
				(arc
					(start 286.436562 -136.945878)
					(mid 285.887922 -137.494518)
					(end 286.436562 -138.043158)
				)
			)
		)
	)
	(zone
		(layers "In1.Cu" "In3.Cu" "In4.Cu" "In6.Cu")
		(hatch none 0.5)
		(connect_pads
			(clearance 0)
		)
		(min_thickness 0.25)
		(keepout
			(tracks not_allowed)
			(vias allowed)
			(pads allowed)
			(copperpour not_allowed)
			(footprints allowed)
		)
		(placement
			(enabled no)
			(sheetname "")
		)
		(fill yes
			(thermal_gap 0.5)
			(thermal_bridge_width 0.5)
			(island_removal_mode 0)
		)
		(polygon
			(pts
				(arc
					(start 382.314704 -13.14196)
					(mid 381.82931 -13.626973)
					(end 382.31445 -14.11224)
				)
				(arc
					(start 383.45745 -14.11224)
					(mid 383.94259 -13.6271)
					(end 383.45745 -13.14196)
				)
			)
		)
	)
	(zone
		(layers "In1.Cu" "In3.Cu" "In4.Cu" "In6.Cu")
		(hatch none 0.5)
		(connect_pads
			(clearance 0)
		)
		(min_thickness 0.25)
		(keepout
			(tracks not_allowed)
			(vias allowed)
			(pads allowed)
			(copperpour not_allowed)
			(footprints allowed)
		)
		(placement
			(enabled no)
			(sheetname "")
		)
		(fill yes
			(thermal_gap 0.5)
			(thermal_bridge_width 0.5)
			(island_removal_mode 0)
		)
		(polygon
			(pts
				(arc
					(start 287.83661 -141.6431)
					(mid 288.38525 -141.09446)
					(end 287.83661 -140.54582)
				)
				(arc
					(start 286.436562 -140.54582)
					(mid 285.887922 -141.09446)
					(end 286.436562 -141.6431)
				)
			)
		)
	)
	(zone
		(layers "In1.Cu" "In3.Cu" "In4.Cu" "In6.Cu")
		(hatch none 0.5)
		(connect_pads
			(clearance 0)
		)
		(min_thickness 0.25)
		(keepout
			(tracks not_allowed)
			(vias allowed)
			(pads allowed)
			(copperpour not_allowed)
			(footprints allowed)
		)
		(placement
			(enabled no)
			(sheetname "")
		)
		(fill yes
			(thermal_gap 0.5)
			(thermal_bridge_width 0.5)
			(island_removal_mode 0)
		)
		(polygon
			(pts
				(arc
					(start 129.42062 -129.419604)
					(mid 128.935607 -128.93421)
					(end 128.45034 -129.41935)
				)
				(arc
					(start 128.45034 -130.56235)
					(mid 128.93548 -131.04749)
					(end 129.42062 -130.56235)
				)
			)
		)
	)
	(zone
		(layers "In1.Cu" "In3.Cu" "In4.Cu" "In6.Cu")
		(hatch none 0.5)
		(connect_pads
			(clearance 0)
		)
		(min_thickness 0.25)
		(keepout
			(tracks not_allowed)
			(vias allowed)
			(pads allowed)
			(copperpour not_allowed)
			(footprints allowed)
		)
		(placement
			(enabled no)
			(sheetname "")
		)
		(fill yes
			(thermal_gap 0.5)
			(thermal_bridge_width 0.5)
			(island_removal_mode 0)
		)
		(polygon
			(pts
				(arc
					(start 279.636728 -230.243126)
					(mid 280.185368 -229.694486)
					(end 279.636728 -229.145846)
				)
				(arc
					(start 278.23668 -229.145846)
					(mid 277.68804 -229.694486)
					(end 278.23668 -230.243126)
				)
			)
		)
	)
	(zone
		(net "P12V_CLIP")
		(layers "In1.Cu" "In3.Cu" "In4.Cu" "In6.Cu")
		(hatch none 0.5)
		(connect_pads
			(clearance 0.5)
		)
		(min_thickness 0.25)
		(fill yes
			(thermal_gap 0.5)
			(thermal_bridge_width 0.5)
			(island_removal_mode 0)
		)
		(polygon
			(pts
				(xy 152.351994 -327.2155) (xy 151.8285 -327.738994) (xy 151.8285 -330.913994) (xy 151.342598 -331.399896)
				(xy 104.225598 -331.399896) (xy 102.9335 -332.691994) (xy 102.9335 -346.123006) (xy 103.8225 -347.012006)
				(xy 103.8225 -364.190788) (xy 104.122982 -364.49127) (xy 109.211618 -364.49127) (xy 112.128808 -361.57408)
				(xy 122.995944 -361.57408) (xy 126.366524 -358.2035) (xy 160.5915 -358.2035) (xy 160.5915 -329.1205)
				(xy 157.909006 -329.1205) (xy 157.4165 -328.627994) (xy 157.4165 -327.357994) (xy 157.274006 -327.2155)
			)
		)
	)
	(zone
		(layers "In1.Cu" "In3.Cu" "In4.Cu" "In6.Cu")
		(hatch none 0.5)
		(connect_pads
			(clearance 0)
		)
		(min_thickness 0.25)
		(keepout
			(tracks not_allowed)
			(vias allowed)
			(pads allowed)
			(copperpour not_allowed)
			(footprints allowed)
		)
		(placement
			(enabled no)
			(sheetname "")
		)
		(fill yes
			(thermal_gap 0.5)
			(thermal_bridge_width 0.5)
			(island_removal_mode 0)
		)
		(polygon
			(pts
				(arc
					(start 286.836612 -190.643002)
					(mid 287.385252 -190.094362)
					(end 286.836612 -189.545722)
				)
				(arc
					(start 285.436564 -189.545722)
					(mid 284.887924 -190.094362)
					(end 285.436564 -190.643002)
				)
			)
		)
	)
	(zone
		(layers "In1.Cu" "In3.Cu" "In4.Cu" "In6.Cu")
		(hatch none 0.5)
		(connect_pads
			(clearance 0)
		)
		(min_thickness 0.25)
		(keepout
			(tracks not_allowed)
			(vias allowed)
			(pads allowed)
			(copperpour not_allowed)
			(footprints allowed)
		)
		(placement
			(enabled no)
			(sheetname "")
		)
		(fill yes
			(thermal_gap 0.5)
			(thermal_bridge_width 0.5)
			(island_removal_mode 0)
		)
		(polygon
			(pts
				(arc
					(start 287.83661 -145.243042)
					(mid 288.38525 -144.694402)
					(end 287.83661 -144.145762)
				)
				(arc
					(start 286.436562 -144.145762)
					(mid 285.887922 -144.694402)
					(end 286.436562 -145.243042)
				)
			)
		)
	)
	(zone
		(layers "In1.Cu" "In3.Cu" "In4.Cu" "In6.Cu")
		(hatch none 0.5)
		(connect_pads
			(clearance 0)
		)
		(min_thickness 0.25)
		(keepout
			(tracks not_allowed)
			(vias allowed)
			(pads allowed)
			(copperpour not_allowed)
			(footprints allowed)
		)
		(placement
			(enabled no)
			(sheetname "")
		)
		(fill yes
			(thermal_gap 0.5)
			(thermal_bridge_width 0.5)
			(island_removal_mode 0)
		)
		(polygon
			(pts
				(arc
					(start 279.636728 -223.042988)
					(mid 280.185368 -222.494348)
					(end 279.636728 -221.945708)
				)
				(arc
					(start 278.23668 -221.945708)
					(mid 277.68804 -222.494348)
					(end 278.23668 -223.042988)
				)
			)
		)
	)
	(zone
		(layers "In1.Cu" "In3.Cu" "In4.Cu" "In6.Cu")
		(hatch none 0.5)
		(connect_pads
			(clearance 0)
		)
		(min_thickness 0.25)
		(keepout
			(tracks not_allowed)
			(vias allowed)
			(pads allowed)
			(copperpour not_allowed)
			(footprints allowed)
		)
		(placement
			(enabled no)
			(sheetname "")
		)
		(fill yes
			(thermal_gap 0.5)
			(thermal_bridge_width 0.5)
			(island_removal_mode 0)
		)
		(polygon
			(pts
				(arc
					(start 190.744094 -133.115304)
					(mid 190.259081 -132.62991)
					(end 189.773814 -133.11505)
				)
				(arc
					(start 189.773814 -134.38505)
					(mid 190.258954 -134.87019)
					(end 190.744094 -134.38505)
				)
			)
		)
	)
	(zone
		(layers "In1.Cu" "In3.Cu" "In4.Cu" "In6.Cu")
		(hatch none 0.5)
		(connect_pads
			(clearance 0)
		)
		(min_thickness 0.25)
		(keepout
			(tracks not_allowed)
			(vias allowed)
			(pads allowed)
			(copperpour not_allowed)
			(footprints allowed)
		)
		(placement
			(enabled no)
			(sheetname "")
		)
		(fill yes
			(thermal_gap 0.5)
			(thermal_bridge_width 0.5)
			(island_removal_mode 0)
		)
		(polygon
			(pts
				(arc
					(start 287.83661 -181.64302)
					(mid 288.38525 -181.09438)
					(end 287.83661 -180.54574)
				)
				(arc
					(start 286.436562 -180.54574)
					(mid 285.887922 -181.09438)
					(end 286.436562 -181.64302)
				)
			)
		)
	)
	(zone
		(layers "In1.Cu" "In3.Cu" "In4.Cu" "In6.Cu")
		(hatch none 0.5)
		(connect_pads
			(clearance 0)
		)
		(min_thickness 0.25)
		(keepout
			(tracks not_allowed)
			(vias allowed)
			(pads allowed)
			(copperpour not_allowed)
			(footprints allowed)
		)
		(placement
			(enabled no)
			(sheetname "")
		)
		(fill yes
			(thermal_gap 0.5)
			(thermal_bridge_width 0.5)
			(island_removal_mode 0)
		)
		(polygon
			(pts
				(arc
					(start 214.14867 -77.600302)
					(mid 213.600157 -77.051408)
					(end 213.05139 -77.600048)
				)
				(arc
					(start 213.05139 -78.999842)
					(mid 213.60003 -79.548482)
					(end 214.14867 -78.999842)
				)
			)
		)
	)
	(zone
		(layers "In1.Cu" "In3.Cu" "In4.Cu" "In6.Cu")
		(hatch none 0.5)
		(connect_pads
			(clearance 0)
		)
		(min_thickness 0.25)
		(keepout
			(tracks not_allowed)
			(vias allowed)
			(pads allowed)
			(copperpour not_allowed)
			(footprints allowed)
		)
		(placement
			(enabled no)
			(sheetname "")
		)
		(fill yes
			(thermal_gap 0.5)
			(thermal_bridge_width 0.5)
			(island_removal_mode 0)
		)
		(polygon
			(pts
				(arc
					(start 160.970722 -244.419374)
					(mid 160.485582 -243.934234)
					(end 160.000442 -244.419374)
				)
				(arc
					(start 160.000442 -245.56212)
					(mid 160.485455 -246.047514)
					(end 160.970722 -245.562374)
				)
			)
		)
	)
	(zone
		(layers "In1.Cu" "In3.Cu" "In4.Cu" "In6.Cu")
		(hatch none 0.5)
		(connect_pads
			(clearance 0)
		)
		(min_thickness 0.25)
		(keepout
			(tracks not_allowed)
			(vias allowed)
			(pads allowed)
			(copperpour not_allowed)
			(footprints allowed)
		)
		(placement
			(enabled no)
			(sheetname "")
		)
		(fill yes
			(thermal_gap 0.5)
			(thermal_bridge_width 0.5)
			(island_removal_mode 0)
		)
		(polygon
			(pts
				(arc
					(start 279.636728 -132.643118)
					(mid 280.185368 -132.094478)
					(end 279.636728 -131.545838)
				)
				(arc
					(start 278.23668 -131.545838)
					(mid 277.68804 -132.094478)
					(end 278.23668 -132.643118)
				)
			)
		)
	)
	(zone
		(layers "In1.Cu" "In3.Cu" "In4.Cu" "In6.Cu")
		(hatch none 0.5)
		(connect_pads
			(clearance 0)
		)
		(min_thickness 0.25)
		(keepout
			(tracks not_allowed)
			(vias allowed)
			(pads allowed)
			(copperpour not_allowed)
			(footprints allowed)
		)
		(placement
			(enabled no)
			(sheetname "")
		)
		(fill yes
			(thermal_gap 0.5)
			(thermal_bridge_width 0.5)
			(island_removal_mode 0)
		)
		(polygon
			(pts
				(arc
					(start 286.836612 -208.64322)
					(mid 287.385252 -208.09458)
					(end 286.836612 -207.54594)
				)
				(arc
					(start 285.436564 -207.54594)
					(mid 284.887924 -208.09458)
					(end 285.436564 -208.64322)
				)
			)
		)
	)
	(zone
		(layers "In1.Cu" "In3.Cu" "In4.Cu" "In6.Cu")
		(hatch none 0.5)
		(connect_pads
			(clearance 0)
		)
		(min_thickness 0.25)
		(keepout
			(tracks not_allowed)
			(vias allowed)
			(pads allowed)
			(copperpour not_allowed)
			(footprints allowed)
		)
		(placement
			(enabled no)
			(sheetname "")
		)
		(fill yes
			(thermal_gap 0.5)
			(thermal_bridge_width 0.5)
			(island_removal_mode 0)
		)
		(polygon
			(pts
				(arc
					(start 280.636726 -178.043078)
					(mid 281.185366 -177.494438)
					(end 280.636726 -176.945798)
				)
				(arc
					(start 279.236678 -176.945798)
					(mid 278.688038 -177.494438)
					(end 279.236678 -178.043078)
				)
			)
		)
	)
	(zone
		(layers "In1.Cu" "In3.Cu" "In4.Cu" "In6.Cu")
		(hatch none 0.5)
		(connect_pads
			(clearance 0)
		)
		(min_thickness 0.25)
		(keepout
			(tracks not_allowed)
			(vias allowed)
			(pads allowed)
			(copperpour not_allowed)
			(footprints allowed)
		)
		(placement
			(enabled no)
			(sheetname "")
		)
		(fill yes
			(thermal_gap 0.5)
			(thermal_bridge_width 0.5)
			(island_removal_mode 0)
		)
		(polygon
			(pts
				(arc
					(start 279.636728 -136.24306)
					(mid 280.185368 -135.69442)
					(end 279.636728 -135.14578)
				)
				(arc
					(start 278.23668 -135.14578)
					(mid 277.68804 -135.69442)
					(end 278.23668 -136.24306)
				)
			)
		)
	)
	(zone
		(layers "In1.Cu" "In3.Cu" "In4.Cu" "In6.Cu")
		(hatch none 0.5)
		(connect_pads
			(clearance 0)
		)
		(min_thickness 0.25)
		(keepout
			(tracks not_allowed)
			(vias allowed)
			(pads allowed)
			(copperpour not_allowed)
			(footprints allowed)
		)
		(placement
			(enabled no)
			(sheetname "")
		)
		(fill yes
			(thermal_gap 0.5)
			(thermal_bridge_width 0.5)
			(island_removal_mode 0)
		)
		(polygon
			(pts
				(arc
					(start 127.64389 -248.115328)
					(mid 127.158877 -247.629934)
					(end 126.67361 -248.115074)
				)
				(arc
					(start 126.67361 -249.385074)
					(mid 127.15875 -249.870214)
					(end 127.64389 -249.385074)
				)
			)
		)
	)
	(zone
		(net "GND")
		(layer "In2.Cu")
		(hatch none 0.5)
		(connect_pads
			(clearance 0.5)
		)
		(min_thickness 0.25)
		(fill yes
			(thermal_gap 0.5)
			(thermal_bridge_width 0.5)
			(island_removal_mode 0)
		)
		(polygon
			(pts
				(arc
					(start 311.999884 -0.763016)
					(mid 311.832312 -0.832426)
					(end 311.762902 -0.999998)
				)
				(arc
					(start 311.762902 -47.200058)
					(mid 311.246527 -48.446697)
					(end 309.999888 -48.963072)
				)
				(arc
					(start 269.999968 -48.963072)
					(mid 269.832396 -49.032482)
					(end 269.762986 -49.200054)
				)
				(xy 269.762986 -61.722) (xy 271.03197 -61.722) (xy 271.03197 -50.232056)
				(arc
					(start 309.999888 -50.232056)
					(mid 312.143834 -49.344004)
					(end 313.031886 -47.200058)
				)
				(xy 313.031886 -2.032) (xy 489.418122 -2.032) (xy 489.418122 -96.413574) (xy 489.418122 -119.586502)
				(xy 489.418122 -340.619334) (xy 490.687106 -340.619334) (xy 490.687106 -118.73484) (xy 490.687106 -97.265236)
				(arc
					(start 490.687106 -0.999998)
					(mid 490.617696 -0.832426)
					(end 490.450124 -0.763016)
				)
			)
		)
	)
	(zone
		(layer "In2.Cu")
		(hatch none 0.5)
		(connect_pads
			(clearance 0)
		)
		(min_thickness 0.25)
		(keepout
			(tracks not_allowed)
			(vias allowed)
			(pads allowed)
			(copperpour not_allowed)
			(footprints allowed)
		)
		(placement
			(enabled no)
			(sheetname "")
		)
		(fill
			(thermal_gap 0.5)
			(thermal_bridge_width 0.5)
			(island_removal_mode 0)
		)
		(polygon
			(pts
				(xy 160.6042 -358.2162) (xy 160.6042 -329.1078) (xy 166.377874 -329.1078) (xy 166.377874 -358.2162)
			)
		)
	)
	(zone
		(net "GND")
		(layer "In2.Cu")
		(hatch none 0.5)
		(connect_pads
			(clearance 0.5)
		)
		(min_thickness 0.25)
		(fill yes
			(thermal_gap 0.5)
			(thermal_bridge_width 0.5)
			(island_removal_mode 0)
		)
		(polygon
			(pts
				(xy 73.279 -346.964) (xy 101.219 -346.964) (xy 101.9175 -346.2655) (xy 101.9175 -332.4225) (xy 100.965 -331.47)
				(xy 73.279 -331.47) (xy 72.771 -331.978) (xy 72.771 -346.456)
			)
		)
	)
	(zone
		(net "P12V_IN")
		(layer "In2.Cu")
		(hatch none 0.5)
		(connect_pads
			(clearance 0.5)
		)
		(min_thickness 0.25)
		(fill yes
			(thermal_gap 0.5)
			(thermal_bridge_width 0.5)
			(island_removal_mode 0)
		)
		(polygon
			(pts
				(xy 236.855 -69.9008) (xy 236.855 -72.7456) (xy 237.5662 -73.4568) (xy 237.5662 -103.0478) (xy 236.855 -103.759)
				(xy 225.2726 -115.3414) (xy 225.2726 -156.1338) (xy 224.409 -156.9974) (xy 224.409 -225.298) (xy 217.4875 -232.2195)
				(xy 217.4875 -291.1475) (xy 208.915 -299.72) (xy 208.915 -328.533506) (xy 207.709008 -329.739752)
				(xy 207.709008 -354.601272) (xy 208.013046 -354.90531) (xy 209.73669 -354.90531) (xy 212.043264 -352.598736)
				(xy 241.888264 -352.598736) (xy 242.1382 -352.3488) (xy 242.1382 -346.4814) (xy 241.7826 -346.1258)
				(xy 239.4712 -346.1258) (xy 238.7346 -345.3892) (xy 238.7346 -343.7128) (xy 239.116616 -343.330784)
				(xy 241.985292 -343.330784) (xy 242.036346 -343.27973) (xy 242.036346 -337.718654) (xy 242.443 -337.312)
				(xy 244.6274 -337.312) (xy 245.3386 -336.6008) (xy 245.3386 -322.8086) (xy 274.1168 -294.0304) (xy 274.1168 -64.0588)
				(xy 273.8374 -63.7794) (xy 266.7254 -63.7794) (xy 246.2276 -63.7794) (xy 237.0074 -63.7794) (xy 236.855 -63.9318)
				(xy 236.855 -65.9638)
			)
		)
	)
	(zone
		(net "P12V_IN")
		(layer "In2.Cu")
		(hatch none 0.5)
		(connect_pads
			(clearance 0.5)
		)
		(min_thickness 0.25)
		(fill yes
			(thermal_gap 0.5)
			(thermal_bridge_width 0.5)
			(island_removal_mode 0)
		)
		(polygon
			(pts
				(xy 135.1534 -374.777) (xy 136.652 -373.2784) (xy 136.652 -370.332) (xy 133.403594 -367.083594)
				(xy 128.953006 -367.083594) (xy 126.712726 -369.323874) (xy 126.6952 -369.3414) (xy 126.6952 -372.6942)
				(xy 128.778 -374.777)
			)
		)
	)
	(zone
		(net "GND")
		(layer "In2.Cu")
		(hatch none 0.5)
		(connect_pads
			(clearance 0.5)
		)
		(min_thickness 0.25)
		(fill yes
			(thermal_gap 0.5)
			(thermal_bridge_width 0.5)
			(island_removal_mode 0)
		)
		(polygon
			(pts
				(arc
					(start 0.999998 -0.763016)
					(mid 0.832426 -0.832426)
					(end 0.763016 -0.999998)
				)
				(xy 0.763016 -340.829138) (xy 0.763016 -356.170738)
				(arc
					(start 0.763016 -370.000022)
					(mid 0.832426 -370.167594)
					(end 0.999998 -370.237004)
				)
				(arc
					(start 1.999996 -370.237004)
					(mid 3.246635 -370.753379)
					(end 3.76301 -372.000018)
				)
				(arc
					(start 3.76301 -384.999992)
					(mid 3.83242 -385.167564)
					(end 3.999992 -385.236974)
				)
				(arc
					(start 15.249906 -385.236974)
					(mid 15.417478 -385.167564)
					(end 15.486888 -384.999992)
				)
				(arc
					(start 15.486888 -383.29997)
					(mid 16.003263 -382.053331)
					(end 17.249902 -381.536956)
				)
				(arc
					(start 23.750016 -381.536956)
					(mid 24.996655 -382.053331)
					(end 25.51303 -383.29997)
				)
				(arc
					(start 25.51303 -384.999992)
					(mid 25.58244 -385.167564)
					(end 25.750012 -385.236974)
				)
				(arc
					(start 71.300086 -385.236974)
					(mid 71.467658 -385.167564)
					(end 71.537068 -384.999992)
				)
				(arc
					(start 71.537068 -381)
					(mid 72.053443 -379.753361)
					(end 73.300082 -379.236986)
				)
				(arc
					(start 125.299978 -379.236986)
					(mid 126.546617 -379.753361)
					(end 127.062992 -381)
				)
				(arc
					(start 127.062992 -384.999992)
					(mid 127.132402 -385.167564)
					(end 127.299974 -385.236974)
				)
				(arc
					(start 172.850048 -385.236974)
					(mid 173.01762 -385.167564)
					(end 173.08703 -384.999992)
				)
				(arc
					(start 173.08703 -383.29997)
					(mid 173.603405 -382.053331)
					(end 174.850044 -381.536956)
				)
				(arc
					(start 181.349904 -381.536956)
					(mid 182.596543 -382.053331)
					(end 183.112918 -383.29997)
				)
				(arc
					(start 183.112918 -384.999992)
					(mid 183.182328 -385.167564)
					(end 183.3499 -385.236974)
				)
				(arc
					(start 197.000114 -385.236974)
					(mid 197.167686 -385.167564)
					(end 197.237096 -384.999992)
				)
				(arc
					(start 197.237096 -381)
					(mid 197.753471 -379.753361)
					(end 199.00011 -379.236986)
				)
				(arc
					(start 251.000006 -379.236986)
					(mid 252.246645 -379.753361)
					(end 252.76302 -381)
				)
				(arc
					(start 252.76302 -384.999992)
					(mid 252.83243 -385.167564)
					(end 253.000002 -385.236974)
				)
				(arc
					(start 269.036292 -385.236974)
					(mid 269.126761 -385.218921)
					(end 269.203424 -385.167632)
				)
				(arc
					(start 271.617694 -382.753362)
					(mid 271.668989 -382.676683)
					(end 271.687036 -382.58623)
				)
				(arc
					(start 271.687036 -361.00004)
					(mid 272.203411 -359.753401)
					(end 273.45005 -359.237026)
				)
				(arc
					(start 275.75002 -359.237026)
					(mid 276.996659 -359.753401)
					(end 277.513034 -361.00004)
				)
				(arc
					(start 277.513034 -382.58623)
					(mid 277.531087 -382.676699)
					(end 277.582376 -382.753362)
				)
				(arc
					(start 279.996646 -385.167632)
					(mid 280.07334 -385.218844)
					(end 280.163778 -385.236974)
				)
				(arc
					(start 306.649882 -385.236974)
					(mid 306.817454 -385.167564)
					(end 306.886864 -384.999992)
				)
				(arc
					(start 306.886864 -383.29997)
					(mid 307.403239 -382.053331)
					(end 308.649878 -381.536956)
				)
				(arc
					(start 315.149992 -381.536956)
					(mid 316.396631 -382.053331)
					(end 316.913006 -383.29997)
				)
				(arc
					(start 316.913006 -384.999992)
					(mid 316.982416 -385.167564)
					(end 317.149988 -385.236974)
				)
				(arc
					(start 362.700062 -385.236974)
					(mid 362.867634 -385.167564)
					(end 362.937044 -384.999992)
				)
				(arc
					(start 362.937044 -381)
					(mid 363.453419 -379.753361)
					(end 364.700058 -379.236986)
				)
				(arc
					(start 416.699954 -379.236986)
					(mid 417.946593 -379.753361)
					(end 418.462968 -381)
				)
				(arc
					(start 418.462968 -384.999992)
					(mid 418.532378 -385.167564)
					(end 418.69995 -385.236974)
				)
				(arc
					(start 464.250024 -385.236974)
					(mid 464.417596 -385.167564)
					(end 464.487006 -384.999992)
				)
				(arc
					(start 464.487006 -383.29997)
					(mid 465.003381 -382.053331)
					(end 466.25002 -381.536956)
				)
				(arc
					(start 472.74988 -381.536956)
					(mid 473.996519 -382.053331)
					(end 474.512894 -383.29997)
				)
				(arc
					(start 474.512894 -384.999992)
					(mid 474.582304 -385.167564)
					(end 474.749876 -385.236974)
				)
				(arc
					(start 487.449876 -385.236974)
					(mid 487.617448 -385.167564)
					(end 487.686858 -384.999992)
				)
				(arc
					(start 487.686858 -372.000018)
					(mid 488.203143 -370.753469)
					(end 489.449618 -370.237004)
				)
				(arc
					(start 490.450124 -370.237004)
					(mid 490.617696 -370.167594)
					(end 490.687106 -370.000022)
				)
				(xy 490.687106 -341.010494) (xy 489.418122 -341.010494)
				(arc
					(start 489.418122 -368.968274)
					(mid 487.294792 -369.867389)
					(end 486.417874 -372.000018)
				)
				(xy 486.417874 -383.96799) (xy 475.781878 -383.96799)
				(arc
					(start 475.781878 -383.29997)
					(mid 474.893826 -381.156024)
					(end 472.74988 -380.267972)
				)
				(arc
					(start 466.25002 -380.267972)
					(mid 464.106074 -381.156024)
					(end 463.218022 -383.29997)
				)
				(xy 463.218022 -383.96799) (xy 419.731952 -383.96799)
				(arc
					(start 419.731952 -381)
					(mid 418.8439 -378.856054)
					(end 416.699954 -377.968002)
				)
				(arc
					(start 364.700058 -377.968002)
					(mid 362.556112 -378.856054)
					(end 361.66806 -381)
				)
				(xy 361.66806 -383.96799) (xy 318.18199 -383.96799)
				(arc
					(start 318.18199 -383.29997)
					(mid 317.293938 -381.156024)
					(end 315.149992 -380.267972)
				)
				(arc
					(start 308.649878 -380.267972)
					(mid 306.505932 -381.156024)
					(end 305.61788 -383.29997)
				)
				(xy 305.61788 -383.96799) (xy 280.591514 -383.96799) (xy 278.782018 -382.158494)
				(arc
					(start 278.782018 -361.00004)
					(mid 277.893966 -358.856094)
					(end 275.75002 -357.968042)
				)
				(arc
					(start 273.45005 -357.968042)
					(mid 271.306104 -358.856094)
					(end 270.418052 -361.00004)
				)
				(xy 270.418052 -382.158494) (xy 268.608556 -383.96799) (xy 254.032004 -383.96799)
				(arc
					(start 254.032004 -381)
					(mid 253.143952 -378.856054)
					(end 251.000006 -377.968002)
				)
				(arc
					(start 199.00011 -377.968002)
					(mid 196.856164 -378.856054)
					(end 195.968112 -381)
				)
				(xy 195.968112 -383.96799) (xy 184.381902 -383.96799)
				(arc
					(start 184.381902 -383.29997)
					(mid 183.49385 -381.156024)
					(end 181.349904 -380.267972)
				)
				(arc
					(start 174.850044 -380.267972)
					(mid 172.706098 -381.156024)
					(end 171.818046 -383.29997)
				)
				(xy 171.818046 -383.96799) (xy 128.331976 -383.96799)
				(arc
					(start 128.331976 -381)
					(mid 127.443924 -378.856054)
					(end 125.299978 -377.968002)
				)
				(arc
					(start 73.300082 -377.968002)
					(mid 71.156136 -378.856054)
					(end 70.268084 -381)
				)
				(xy 70.268084 -383.96799) (xy 26.782014 -383.96799)
				(arc
					(start 26.782014 -383.29997)
					(mid 25.893962 -381.156024)
					(end 23.750016 -380.267972)
				)
				(arc
					(start 17.249902 -380.267972)
					(mid 15.105956 -381.156024)
					(end 14.217904 -383.29997)
				)
				(xy 14.217904 -383.96799) (xy 5.031994 -383.96799)
				(arc
					(start 5.031994 -372.000018)
					(mid 4.155228 -369.867417)
					(end 2.032 -368.968274)
				)
				(xy 2.032 -356.915974) (xy 2.032 -340.228174) (xy 2.032 -340.147402) (xy 2.032 -340.020402) (xy 2.032 -2.032)
				(xy 196.96811 -2.032)
				(arc
					(start 196.96811 -47.200058)
					(mid 197.856162 -49.344004)
					(end 200.000108 -50.232056)
				)
				(xy 204.968094 -50.232056)
				(arc
					(start 204.968094 -62.00013)
					(mid 205.856146 -64.143822)
					(end 207.999838 -65.031874)
				)
				(xy 226.37623 -65.031874) (xy 226.37623 -63.76289)
				(arc
					(start 207.999838 -63.76289)
					(mid 206.753453 -63.246515)
					(end 206.237078 -62.00013)
				)
				(arc
					(start 206.237078 -49.200054)
					(mid 206.167668 -49.032482)
					(end 206.000096 -48.963072)
				)
				(arc
					(start 200.000108 -48.963072)
					(mid 198.753469 -48.446697)
					(end 198.237094 -47.200058)
				)
				(arc
					(start 198.237094 -0.999998)
					(mid 198.167684 -0.832426)
					(end 198.000112 -0.763016)
				)
			)
		)
	)
	(zone
		(net "MB3_P12V_IN_R")
		(layer "In2.Cu")
		(hatch none 0.5)
		(connect_pads
			(clearance 0.5)
		)
		(min_thickness 0.25)
		(fill yes
			(thermal_gap 0.5)
			(thermal_bridge_width 0.5)
			(island_removal_mode 0)
		)
		(polygon
			(pts
				(xy 250.677172 -345.5162) (xy 250.677172 -353.90836) (xy 251.162566 -354.393754) (xy 258.230624 -354.393754)
				(xy 260.024372 -352.600006) (xy 260.024372 -338.985606) (xy 260.024372 -331.41158) (xy 260.024372 -330.585572)
				(xy 259.3594 -329.9206) (xy 249.9106 -329.9206) (xy 249.5804 -330.2508) (xy 249.5804 -330.835) (xy 249.5804 -344.424)
				(xy 250.6726 -345.5162)
			)
		)
	)
	(zone
		(net "P12V_IN")
		(layer "In2.Cu")
		(hatch none 0.5)
		(connect_pads
			(clearance 0.5)
		)
		(min_thickness 0.25)
		(fill yes
			(thermal_gap 0.5)
			(thermal_bridge_width 0.5)
			(island_removal_mode 0)
		)
		(polygon
			(pts
				(xy 47.719996 -363.601) (xy 47.719996 -361.315) (xy 47.338996 -360.934) (xy 47.312326 -360.934)
				(xy 46.406562 -360.028236) (xy 41.674796 -360.028236) (xy 40.769032 -360.934) (xy 35.908996 -360.934)
				(xy 33.749996 -363.093) (xy 33.749996 -366.8776) (xy 31.082996 -369.5446) (xy 28.974796 -369.5446)
				(xy 27.730196 -370.7892) (xy 25.799796 -370.7892) (xy 25.520396 -371.0686) (xy 25.520396 -373.446802)
				(xy 25.520396 -376.047) (xy 25.840436 -376.36704) (xy 25.840436 -379.352556) (xy 28.031948 -381.544068)
				(xy 32.316928 -381.544068) (xy 38.448996 -375.412) (xy 40.353996 -373.507) (xy 40.353996 -366.014)
				(xy 41.369996 -364.998) (xy 46.322996 -364.998)
			)
		)
	)
	(zone
		(layer "In2.Cu")
		(hatch none 0.5)
		(connect_pads
			(clearance 0.5)
		)
		(min_thickness 0.25)
		(fill
			(thermal_gap 0.5)
			(thermal_bridge_width 0.5)
			(island_removal_mode 0)
		)
		(polygon
			(pts
				(xy 109.601 -29.464) (xy 109.601 -34.417) (xy 109.855 -34.671) (xy 112.395 -34.671) (xy 112.649 -34.417)
				(xy 112.649 -30.353) (xy 114.3 -28.702) (xy 114.3 -19.7866) (xy 112.0902 -17.5768) (xy 107.8992 -17.5768)
				(xy 107.315 -18.161) (xy 107.315 -18.923) (xy 107.569 -19.177) (xy 109.093 -19.177) (xy 111.887 -21.971)
				(xy 111.887 -27.178)
			)
		)
	)
	(zone
		(net "P3V3_STBY_B")
		(layer "In2.Cu")
		(hatch none 0.5)
		(connect_pads
			(clearance 0.5)
		)
		(min_thickness 0.25)
		(fill yes
			(thermal_gap 0.5)
			(thermal_bridge_width 0.5)
			(island_removal_mode 0)
		)
		(polygon
			(pts
				(xy 290.520628 -299.085) (xy 296.179494 -299.085) (xy 296.97172 -299.877226) (xy 296.97172 -356.015036)
				(xy 294.841422 -358.145334) (xy 283.898848 -358.145334) (xy 283.866844 -358.113076) (xy 282.815792 -358.113076)
				(xy 278.614886 -353.91217) (xy 278.614886 -348.406212) (xy 289.744658 -337.27644) (xy 289.744658 -299.86097)
			)
		)
	)
	(zone
		(layers "In2.Cu" "In5.Cu")
		(hatch none 0.5)
		(connect_pads
			(clearance 0)
		)
		(min_thickness 0.25)
		(keepout
			(tracks not_allowed)
			(vias allowed)
			(pads allowed)
			(copperpour not_allowed)
			(footprints allowed)
		)
		(placement
			(enabled no)
			(sheetname "")
		)
		(fill yes
			(thermal_gap 0.5)
			(thermal_bridge_width 0.5)
			(island_removal_mode 0)
		)
		(polygon
			(pts
				(arc
					(start 445.414654 -128.141984)
					(mid 444.92926 -128.626997)
					(end 445.4144 -129.112264)
				)
				(arc
					(start 446.5574 -129.112264)
					(mid 446.899547 -128.971067)
					(end 447.04254 -128.629664)
				)
				(arc
					(start 446.8241 -128.629664)
					(mid 446.5574 -128.893836)
					(end 446.2907 -128.629664)
				)
				(arc
					(start 445.6811 -128.629664)
					(mid 445.4144 -128.893836)
					(end 445.1477 -128.629664)
				)
				(arc
					(start 445.1477 -128.627124)
					(mid 445.4144 -128.360424)
					(end 445.6811 -128.627124)
				)
				(arc
					(start 446.2907 -128.627124)
					(mid 446.5574 -128.360424)
					(end 446.8241 -128.627124)
				)
				(arc
					(start 447.04254 -128.627124)
					(mid 446.900446 -128.284078)
					(end 446.5574 -128.141984)
				)
			)
		)
	)
	(zone
		(layers "In2.Cu" "In5.Cu")
		(hatch none 0.5)
		(connect_pads
			(clearance 0)
		)
		(min_thickness 0.25)
		(keepout
			(tracks not_allowed)
			(vias allowed)
			(pads allowed)
			(copperpour not_allowed)
			(footprints allowed)
		)
		(placement
			(enabled no)
			(sheetname "")
		)
		(fill yes
			(thermal_gap 0.5)
			(thermal_bridge_width 0.5)
			(island_removal_mode 0)
		)
		(polygon
			(pts
				(arc
					(start 413.864806 -13.14196)
					(mid 413.379412 -13.626973)
					(end 413.864552 -14.11224)
				)
				(arc
					(start 415.007552 -14.11224)
					(mid 415.349699 -13.971043)
					(end 415.492692 -13.62964)
				)
				(arc
					(start 415.274252 -13.62964)
					(mid 415.007552 -13.893812)
					(end 414.740852 -13.62964)
				)
				(arc
					(start 414.131252 -13.62964)
					(mid 413.864552 -13.893812)
					(end 413.597852 -13.62964)
				)
				(arc
					(start 413.597852 -13.6271)
					(mid 413.864552 -13.3604)
					(end 414.131252 -13.6271)
				)
				(arc
					(start 414.740852 -13.6271)
					(mid 415.007552 -13.3604)
					(end 415.274252 -13.6271)
				)
				(arc
					(start 415.492692 -13.6271)
					(mid 415.350598 -13.284054)
					(end 415.007552 -13.14196)
				)
			)
		)
	)
	(zone
		(layers "In2.Cu" "In5.Cu")
		(hatch none 0.5)
		(connect_pads
			(clearance 0)
		)
		(min_thickness 0.25)
		(keepout
			(tracks not_allowed)
			(vias allowed)
			(pads allowed)
			(copperpour not_allowed)
			(footprints allowed)
		)
		(placement
			(enabled no)
			(sheetname "")
		)
		(fill yes
			(thermal_gap 0.5)
			(thermal_bridge_width 0.5)
			(island_removal_mode 0)
		)
		(polygon
			(pts
				(arc
					(start 446.0875 -244.312694)
					(mid 445.60236 -243.827554)
					(end 445.11722 -244.312694)
				)
				(arc
					(start 445.11722 -245.45544)
					(mid 445.600963 -245.940832)
					(end 446.0875 -245.458234)
				)
				(arc
					(start 445.86906 -245.458234)
					(mid 445.60236 -245.722406)
					(end 445.33566 -245.458234)
				)
				(arc
					(start 445.33566 -245.455694)
					(mid 445.60236 -245.188994)
					(end 445.86906 -245.455694)
				)
				(xy 446.0875 -245.455694) (xy 446.0875 -244.315234)
				(arc
					(start 445.86906 -244.315234)
					(mid 445.60236 -244.579406)
					(end 445.33566 -244.315234)
				)
				(arc
					(start 445.33566 -244.312694)
					(mid 445.60236 -244.045994)
					(end 445.86906 -244.312694)
				)
			)
		)
	)
	(zone
		(layers "In2.Cu" "In5.Cu")
		(hatch none 0.5)
		(connect_pads
			(clearance 0)
		)
		(min_thickness 0.25)
		(keepout
			(tracks not_allowed)
			(vias allowed)
			(pads allowed)
			(copperpour not_allowed)
			(footprints allowed)
		)
		(placement
			(enabled no)
			(sheetname "")
		)
		(fill yes
			(thermal_gap 0.5)
			(thermal_bridge_width 0.5)
			(island_removal_mode 0)
		)
		(polygon
			(pts
				(arc
					(start 350.764856 -13.14196)
					(mid 350.279462 -13.626973)
					(end 350.764602 -14.11224)
				)
				(arc
					(start 351.907602 -14.11224)
					(mid 352.249749 -13.971043)
					(end 352.392742 -13.62964)
				)
				(arc
					(start 352.174302 -13.62964)
					(mid 351.907602 -13.893812)
					(end 351.640902 -13.62964)
				)
				(arc
					(start 351.031302 -13.62964)
					(mid 350.764602 -13.893812)
					(end 350.497902 -13.62964)
				)
				(arc
					(start 350.497902 -13.6271)
					(mid 350.764602 -13.3604)
					(end 351.031302 -13.6271)
				)
				(arc
					(start 351.640902 -13.6271)
					(mid 351.907602 -13.3604)
					(end 352.174302 -13.6271)
				)
				(arc
					(start 352.392742 -13.6271)
					(mid 352.250648 -13.284054)
					(end 351.907602 -13.14196)
				)
			)
		)
	)
	(zone
		(layers "In2.Cu" "In5.Cu")
		(hatch none 0.5)
		(connect_pads
			(clearance 0)
		)
		(min_thickness 0.25)
		(keepout
			(tracks not_allowed)
			(vias allowed)
			(pads allowed)
			(copperpour not_allowed)
			(footprints allowed)
		)
		(placement
			(enabled no)
			(sheetname "")
		)
		(fill yes
			(thermal_gap 0.5)
			(thermal_bridge_width 0.5)
			(island_removal_mode 0)
		)
		(polygon
			(pts
				(arc
					(start 350.764856 -128.141984)
					(mid 350.279462 -128.626997)
					(end 350.764602 -129.112264)
				)
				(arc
					(start 351.907602 -129.112264)
					(mid 352.249749 -128.971067)
					(end 352.392742 -128.629664)
				)
				(arc
					(start 352.174302 -128.629664)
					(mid 351.907602 -128.893836)
					(end 351.640902 -128.629664)
				)
				(arc
					(start 351.031302 -128.629664)
					(mid 350.764602 -128.893836)
					(end 350.497902 -128.629664)
				)
				(arc
					(start 350.497902 -128.627124)
					(mid 350.764602 -128.360424)
					(end 351.031302 -128.627124)
				)
				(arc
					(start 351.640902 -128.627124)
					(mid 351.907602 -128.360424)
					(end 352.174302 -128.627124)
				)
				(arc
					(start 352.392742 -128.627124)
					(mid 352.250648 -128.284078)
					(end 351.907602 -128.141984)
				)
			)
		)
	)
	(zone
		(layers "In2.Cu" "In5.Cu")
		(hatch none 0.5)
		(connect_pads
			(clearance 0)
		)
		(min_thickness 0.25)
		(keepout
			(tracks not_allowed)
			(vias allowed)
			(pads allowed)
			(copperpour not_allowed)
			(footprints allowed)
		)
		(placement
			(enabled no)
			(sheetname "")
		)
		(fill yes
			(thermal_gap 0.5)
			(thermal_bridge_width 0.5)
			(island_removal_mode 0)
		)
		(polygon
			(pts
				(arc
					(start 97.870772 -129.41935)
					(mid 97.385632 -128.93421)
					(end 96.900492 -129.41935)
				)
				(arc
					(start 96.900492 -130.56235)
					(mid 97.384362 -131.047488)
					(end 97.870772 -130.56489)
				)
				(arc
					(start 97.652332 -130.56489)
					(mid 97.385632 -130.829062)
					(end 97.118932 -130.56489)
				)
				(arc
					(start 97.118932 -130.56235)
					(mid 97.385632 -130.29565)
					(end 97.652332 -130.56235)
				)
				(xy 97.870772 -130.56235) (xy 97.870772 -129.42189)
				(arc
					(start 97.652332 -129.42189)
					(mid 97.385632 -129.686062)
					(end 97.118932 -129.42189)
				)
				(arc
					(start 97.118932 -129.41935)
					(mid 97.385632 -129.15265)
					(end 97.652332 -129.41935)
				)
			)
		)
	)
	(zone
		(layers "In2.Cu" "In5.Cu")
		(hatch none 0.5)
		(connect_pads
			(clearance 0)
		)
		(min_thickness 0.25)
		(keepout
			(tracks not_allowed)
			(vias allowed)
			(pads allowed)
			(copperpour not_allowed)
			(footprints allowed)
		)
		(placement
			(enabled no)
			(sheetname "")
		)
		(fill yes
			(thermal_gap 0.5)
			(thermal_bridge_width 0.5)
			(island_removal_mode 0)
		)
		(polygon
			(pts
				(arc
					(start 319.214754 -13.14196)
					(mid 318.72936 -13.626973)
					(end 319.2145 -14.11224)
				)
				(arc
					(start 320.3575 -14.11224)
					(mid 320.699647 -13.971043)
					(end 320.84264 -13.62964)
				)
				(arc
					(start 320.6242 -13.62964)
					(mid 320.3575 -13.893812)
					(end 320.0908 -13.62964)
				)
				(arc
					(start 319.4812 -13.62964)
					(mid 319.2145 -13.893812)
					(end 318.9478 -13.62964)
				)
				(arc
					(start 318.9478 -13.6271)
					(mid 319.2145 -13.3604)
					(end 319.4812 -13.6271)
				)
				(arc
					(start 320.0908 -13.6271)
					(mid 320.3575 -13.3604)
					(end 320.6242 -13.6271)
				)
				(arc
					(start 320.84264 -13.6271)
					(mid 320.700546 -13.284054)
					(end 320.3575 -13.14196)
				)
			)
		)
	)
	(zone
		(layers "In2.Cu" "In5.Cu")
		(hatch none 0.5)
		(connect_pads
			(clearance 0)
		)
		(min_thickness 0.25)
		(keepout
			(tracks not_allowed)
			(vias allowed)
			(pads allowed)
			(copperpour not_allowed)
			(footprints allowed)
		)
		(placement
			(enabled no)
			(sheetname "")
		)
		(fill yes
			(thermal_gap 0.5)
			(thermal_bridge_width 0.5)
			(island_removal_mode 0)
		)
		(polygon
			(pts
				(arc
					(start 97.870772 -14.419326)
					(mid 97.385632 -13.934186)
					(end 96.900492 -14.419326)
				)
				(arc
					(start 96.900492 -15.562326)
					(mid 97.384362 -16.047464)
					(end 97.870772 -15.564866)
				)
				(arc
					(start 97.652332 -15.564866)
					(mid 97.385632 -15.829038)
					(end 97.118932 -15.564866)
				)
				(arc
					(start 97.118932 -15.562326)
					(mid 97.385632 -15.295626)
					(end 97.652332 -15.562326)
				)
				(xy 97.870772 -15.562326) (xy 97.870772 -14.421866)
				(arc
					(start 97.652332 -14.421866)
					(mid 97.385632 -14.686038)
					(end 97.118932 -14.421866)
				)
				(arc
					(start 97.118932 -14.419326)
					(mid 97.385632 -14.152626)
					(end 97.652332 -14.419326)
				)
			)
		)
	)
	(zone
		(layers "In2.Cu" "In5.Cu")
		(hatch none 0.5)
		(connect_pads
			(clearance 0)
		)
		(min_thickness 0.25)
		(keepout
			(tracks not_allowed)
			(vias allowed)
			(pads allowed)
			(copperpour not_allowed)
			(footprints allowed)
		)
		(placement
			(enabled no)
			(sheetname "")
		)
		(fill yes
			(thermal_gap 0.5)
			(thermal_bridge_width 0.5)
			(island_removal_mode 0)
		)
		(polygon
			(pts
				(arc
					(start 351.427542 -244.317774)
					(mid 350.942402 -243.832634)
					(end 350.457262 -244.317774)
				)
				(arc
					(start 350.457262 -245.46052)
					(mid 350.941005 -245.945912)
					(end 351.427542 -245.463314)
				)
				(arc
					(start 351.209102 -245.463314)
					(mid 350.942402 -245.727486)
					(end 350.675702 -245.463314)
				)
				(arc
					(start 350.675702 -245.460774)
					(mid 350.942402 -245.194074)
					(end 351.209102 -245.460774)
				)
				(xy 351.427542 -245.460774) (xy 351.427542 -244.320314)
				(arc
					(start 351.209102 -244.320314)
					(mid 350.942402 -244.584486)
					(end 350.675702 -244.320314)
				)
				(arc
					(start 350.675702 -244.317774)
					(mid 350.942402 -244.051074)
					(end 351.209102 -244.317774)
				)
			)
		)
	)
	(zone
		(layers "In2.Cu" "In5.Cu")
		(hatch none 0.5)
		(connect_pads
			(clearance 0)
		)
		(min_thickness 0.25)
		(keepout
			(tracks not_allowed)
			(vias allowed)
			(pads allowed)
			(copperpour not_allowed)
			(footprints allowed)
		)
		(placement
			(enabled no)
			(sheetname "")
		)
		(fill yes
			(thermal_gap 0.5)
			(thermal_bridge_width 0.5)
			(island_removal_mode 0)
		)
		(polygon
			(pts
				(arc
					(start 66.32067 -129.41935)
					(mid 65.83553 -128.93421)
					(end 65.35039 -129.41935)
				)
				(arc
					(start 65.35039 -130.56235)
					(mid 65.83426 -131.047488)
					(end 66.32067 -130.56489)
				)
				(arc
					(start 66.10223 -130.56489)
					(mid 65.83553 -130.829062)
					(end 65.56883 -130.56489)
				)
				(arc
					(start 65.56883 -130.56235)
					(mid 65.83553 -130.29565)
					(end 66.10223 -130.56235)
				)
				(xy 66.32067 -130.56235) (xy 66.32067 -129.42189)
				(arc
					(start 66.10223 -129.42189)
					(mid 65.83553 -129.686062)
					(end 65.56883 -129.42189)
				)
				(arc
					(start 65.56883 -129.41935)
					(mid 65.83553 -129.15265)
					(end 66.10223 -129.41935)
				)
			)
		)
	)
	(zone
		(layers "In2.Cu" "In5.Cu")
		(hatch none 0.5)
		(connect_pads
			(clearance 0)
		)
		(min_thickness 0.25)
		(keepout
			(tracks not_allowed)
			(vias allowed)
			(pads allowed)
			(copperpour not_allowed)
			(footprints allowed)
		)
		(placement
			(enabled no)
			(sheetname "")
		)
		(fill yes
			(thermal_gap 0.5)
			(thermal_bridge_width 0.5)
			(island_removal_mode 0)
		)
		(polygon
			(pts
				(arc
					(start 129.42062 -244.419374)
					(mid 128.93548 -243.934234)
					(end 128.45034 -244.419374)
				)
				(arc
					(start 128.45034 -245.56212)
					(mid 128.934083 -246.047512)
					(end 129.42062 -245.564914)
				)
				(arc
					(start 129.20218 -245.564914)
					(mid 128.93548 -245.829086)
					(end 128.66878 -245.564914)
				)
				(arc
					(start 128.66878 -245.562374)
					(mid 128.93548 -245.295674)
					(end 129.20218 -245.562374)
				)
				(xy 129.42062 -245.562374) (xy 129.42062 -244.421914)
				(arc
					(start 129.20218 -244.421914)
					(mid 128.93548 -244.686086)
					(end 128.66878 -244.421914)
				)
				(arc
					(start 128.66878 -244.419374)
					(mid 128.93548 -244.152674)
					(end 129.20218 -244.419374)
				)
			)
		)
	)
	(zone
		(layers "In2.Cu" "In5.Cu")
		(hatch none 0.5)
		(connect_pads
			(clearance 0)
		)
		(min_thickness 0.25)
		(keepout
			(tracks not_allowed)
			(vias allowed)
			(pads allowed)
			(copperpour not_allowed)
			(footprints allowed)
		)
		(placement
			(enabled no)
			(sheetname "")
		)
		(fill yes
			(thermal_gap 0.5)
			(thermal_bridge_width 0.5)
			(island_removal_mode 0)
		)
		(polygon
			(pts
				(arc
					(start 160.970722 -129.41935)
					(mid 160.485582 -128.93421)
					(end 160.000442 -129.41935)
				)
				(arc
					(start 160.000442 -130.56235)
					(mid 160.484312 -131.047488)
					(end 160.970722 -130.56489)
				)
				(arc
					(start 160.752282 -130.56489)
					(mid 160.485582 -130.829062)
					(end 160.218882 -130.56489)
				)
				(arc
					(start 160.218882 -130.56235)
					(mid 160.485582 -130.29565)
					(end 160.752282 -130.56235)
				)
				(xy 160.970722 -130.56235) (xy 160.970722 -129.42189)
				(arc
					(start 160.752282 -129.42189)
					(mid 160.485582 -129.686062)
					(end 160.218882 -129.42189)
				)
				(arc
					(start 160.218882 -129.41935)
					(mid 160.485582 -129.15265)
					(end 160.752282 -129.41935)
				)
			)
		)
	)
	(zone
		(layers "In2.Cu" "In5.Cu")
		(hatch none 0.5)
		(connect_pads
			(clearance 0)
		)
		(min_thickness 0.25)
		(keepout
			(tracks not_allowed)
			(vias allowed)
			(pads allowed)
			(copperpour not_allowed)
			(footprints allowed)
		)
		(placement
			(enabled no)
			(sheetname "")
		)
		(fill yes
			(thermal_gap 0.5)
			(thermal_bridge_width 0.5)
			(island_removal_mode 0)
		)
		(polygon
			(pts
				(arc
					(start 34.770822 -14.419326)
					(mid 34.285682 -13.934186)
					(end 33.800542 -14.419326)
				)
				(arc
					(start 33.800542 -15.562326)
					(mid 34.284412 -16.047464)
					(end 34.770822 -15.564866)
				)
				(arc
					(start 34.552382 -15.564866)
					(mid 34.285682 -15.829038)
					(end 34.018982 -15.564866)
				)
				(arc
					(start 34.018982 -15.562326)
					(mid 34.285682 -15.295626)
					(end 34.552382 -15.562326)
				)
				(xy 34.770822 -15.562326) (xy 34.770822 -14.421866)
				(arc
					(start 34.552382 -14.421866)
					(mid 34.285682 -14.686038)
					(end 34.018982 -14.421866)
				)
				(arc
					(start 34.018982 -14.419326)
					(mid 34.285682 -14.152626)
					(end 34.552382 -14.419326)
				)
			)
		)
	)
	(zone
		(layers "In2.Cu" "In5.Cu")
		(hatch none 0.5)
		(connect_pads
			(clearance 0)
		)
		(min_thickness 0.25)
		(keepout
			(tracks not_allowed)
			(vias allowed)
			(pads allowed)
			(copperpour not_allowed)
			(footprints allowed)
		)
		(placement
			(enabled no)
			(sheetname "")
		)
		(fill yes
			(thermal_gap 0.5)
			(thermal_bridge_width 0.5)
			(island_removal_mode 0)
		)
		(polygon
			(pts
				(arc
					(start 34.770822 -244.419374)
					(mid 34.285682 -243.934234)
					(end 33.800542 -244.419374)
				)
				(arc
					(start 33.800542 -245.56212)
					(mid 34.284285 -246.047512)
					(end 34.770822 -245.564914)
				)
				(arc
					(start 34.552382 -245.564914)
					(mid 34.285682 -245.829086)
					(end 34.018982 -245.564914)
				)
				(arc
					(start 34.018982 -245.562374)
					(mid 34.285682 -245.295674)
					(end 34.552382 -245.562374)
				)
				(xy 34.770822 -245.562374) (xy 34.770822 -244.421914)
				(arc
					(start 34.552382 -244.421914)
					(mid 34.285682 -244.686086)
					(end 34.018982 -244.421914)
				)
				(arc
					(start 34.018982 -244.419374)
					(mid 34.285682 -244.152674)
					(end 34.552382 -244.419374)
				)
			)
		)
	)
	(zone
		(layers "In2.Cu" "In5.Cu")
		(hatch none 0.5)
		(connect_pads
			(clearance 0)
		)
		(min_thickness 0.25)
		(keepout
			(tracks not_allowed)
			(vias allowed)
			(pads allowed)
			(copperpour not_allowed)
			(footprints allowed)
		)
		(placement
			(enabled no)
			(sheetname "")
		)
		(fill yes
			(thermal_gap 0.5)
			(thermal_bridge_width 0.5)
			(island_removal_mode 0)
		)
		(polygon
			(pts
				(arc
					(start 476.964756 -128.141984)
					(mid 476.479362 -128.626997)
					(end 476.964502 -129.112264)
				)
				(arc
					(start 478.107502 -129.112264)
					(mid 478.449649 -128.971067)
					(end 478.592642 -128.629664)
				)
				(arc
					(start 478.374202 -128.629664)
					(mid 478.107502 -128.893836)
					(end 477.840802 -128.629664)
				)
				(arc
					(start 477.231202 -128.629664)
					(mid 476.964502 -128.893836)
					(end 476.697802 -128.629664)
				)
				(arc
					(start 476.697802 -128.627124)
					(mid 476.964502 -128.360424)
					(end 477.231202 -128.627124)
				)
				(arc
					(start 477.840802 -128.627124)
					(mid 478.107502 -128.360424)
					(end 478.374202 -128.627124)
				)
				(arc
					(start 478.592642 -128.627124)
					(mid 478.450548 -128.284078)
					(end 478.107502 -128.141984)
				)
			)
		)
	)
	(zone
		(layers "In2.Cu" "In5.Cu")
		(hatch none 0.5)
		(connect_pads
			(clearance 0)
		)
		(min_thickness 0.25)
		(keepout
			(tracks not_allowed)
			(vias allowed)
			(pads allowed)
			(copperpour not_allowed)
			(footprints allowed)
		)
		(placement
			(enabled no)
			(sheetname "")
		)
		(fill yes
			(thermal_gap 0.5)
			(thermal_bridge_width 0.5)
			(island_removal_mode 0)
		)
		(polygon
			(pts
				(arc
					(start 413.864806 -128.141984)
					(mid 413.379412 -128.626997)
					(end 413.864552 -129.112264)
				)
				(arc
					(start 415.007552 -129.112264)
					(mid 415.349699 -128.971067)
					(end 415.492692 -128.629664)
				)
				(arc
					(start 415.274252 -128.629664)
					(mid 415.007552 -128.893836)
					(end 414.740852 -128.629664)
				)
				(arc
					(start 414.131252 -128.629664)
					(mid 413.864552 -128.893836)
					(end 413.597852 -128.629664)
				)
				(arc
					(start 413.597852 -128.627124)
					(mid 413.864552 -128.360424)
					(end 414.131252 -128.627124)
				)
				(arc
					(start 414.740852 -128.627124)
					(mid 415.007552 -128.360424)
					(end 415.274252 -128.627124)
				)
				(arc
					(start 415.492692 -128.627124)
					(mid 415.350598 -128.284078)
					(end 415.007552 -128.141984)
				)
			)
		)
	)
	(zone
		(layers "In2.Cu" "In5.Cu")
		(hatch none 0.5)
		(connect_pads
			(clearance 0)
		)
		(min_thickness 0.25)
		(keepout
			(tracks not_allowed)
			(vias allowed)
			(pads allowed)
			(copperpour not_allowed)
			(footprints allowed)
		)
		(placement
			(enabled no)
			(sheetname "")
		)
		(fill yes
			(thermal_gap 0.5)
			(thermal_bridge_width 0.5)
			(island_removal_mode 0)
		)
		(polygon
			(pts
				(arc
					(start 476.964756 -13.14196)
					(mid 476.479362 -13.626973)
					(end 476.964502 -14.11224)
				)
				(arc
					(start 478.107502 -14.11224)
					(mid 478.449649 -13.971043)
					(end 478.592642 -13.62964)
				)
				(arc
					(start 478.374202 -13.62964)
					(mid 478.107502 -13.893812)
					(end 477.840802 -13.62964)
				)
				(arc
					(start 477.231202 -13.62964)
					(mid 476.964502 -13.893812)
					(end 476.697802 -13.62964)
				)
				(arc
					(start 476.697802 -13.6271)
					(mid 476.964502 -13.3604)
					(end 477.231202 -13.6271)
				)
				(arc
					(start 477.840802 -13.6271)
					(mid 478.107502 -13.3604)
					(end 478.374202 -13.6271)
				)
				(arc
					(start 478.592642 -13.6271)
					(mid 478.450548 -13.284054)
					(end 478.107502 -13.14196)
				)
			)
		)
	)
	(zone
		(layers "In2.Cu" "In5.Cu")
		(hatch none 0.5)
		(connect_pads
			(clearance 0)
		)
		(min_thickness 0.25)
		(keepout
			(tracks not_allowed)
			(vias allowed)
			(pads allowed)
			(copperpour not_allowed)
			(footprints allowed)
		)
		(placement
			(enabled no)
			(sheetname "")
		)
		(fill yes
			(thermal_gap 0.5)
			(thermal_bridge_width 0.5)
			(island_removal_mode 0)
		)
		(polygon
			(pts
				(arc
					(start 192.520824 -129.41935)
					(mid 192.035684 -128.93421)
					(end 191.550544 -129.41935)
				)
				(arc
					(start 191.550544 -130.56235)
					(mid 192.034414 -131.047488)
					(end 192.520824 -130.56489)
				)
				(arc
					(start 192.302384 -130.56489)
					(mid 192.035684 -130.829062)
					(end 191.768984 -130.56489)
				)
				(arc
					(start 191.768984 -130.56235)
					(mid 192.035684 -130.29565)
					(end 192.302384 -130.56235)
				)
				(xy 192.520824 -130.56235) (xy 192.520824 -129.42189)
				(arc
					(start 192.302384 -129.42189)
					(mid 192.035684 -129.686062)
					(end 191.768984 -129.42189)
				)
				(arc
					(start 191.768984 -129.41935)
					(mid 192.035684 -129.15265)
					(end 192.302384 -129.41935)
				)
			)
		)
	)
	(zone
		(layers "In2.Cu" "In5.Cu")
		(hatch none 0.5)
		(connect_pads
			(clearance 0)
		)
		(min_thickness 0.25)
		(keepout
			(tracks not_allowed)
			(vias allowed)
			(pads allowed)
			(copperpour not_allowed)
			(footprints allowed)
		)
		(placement
			(enabled no)
			(sheetname "")
		)
		(fill yes
			(thermal_gap 0.5)
			(thermal_bridge_width 0.5)
			(island_removal_mode 0)
		)
		(polygon
			(pts
				(arc
					(start 66.32067 -244.419374)
					(mid 65.83553 -243.934234)
					(end 65.35039 -244.419374)
				)
				(arc
					(start 65.35039 -245.56212)
					(mid 65.834133 -246.047512)
					(end 66.32067 -245.564914)
				)
				(arc
					(start 66.10223 -245.564914)
					(mid 65.83553 -245.829086)
					(end 65.56883 -245.564914)
				)
				(arc
					(start 65.56883 -245.562374)
					(mid 65.83553 -245.295674)
					(end 66.10223 -245.562374)
				)
				(xy 66.32067 -245.562374) (xy 66.32067 -244.421914)
				(arc
					(start 66.10223 -244.421914)
					(mid 65.83553 -244.686086)
					(end 65.56883 -244.421914)
				)
				(arc
					(start 65.56883 -244.419374)
					(mid 65.83553 -244.152674)
					(end 66.10223 -244.419374)
				)
			)
		)
	)
	(zone
		(layers "In2.Cu" "In5.Cu")
		(hatch none 0.5)
		(connect_pads
			(clearance 0)
		)
		(min_thickness 0.25)
		(keepout
			(tracks not_allowed)
			(vias allowed)
			(pads allowed)
			(copperpour not_allowed)
			(footprints allowed)
		)
		(placement
			(enabled no)
			(sheetname "")
		)
		(fill yes
			(thermal_gap 0.5)
			(thermal_bridge_width 0.5)
			(island_removal_mode 0)
		)
		(polygon
			(pts
				(arc
					(start 319.214754 -128.141984)
					(mid 318.72936 -128.626997)
					(end 319.2145 -129.112264)
				)
				(arc
					(start 320.3575 -129.112264)
					(mid 320.699647 -128.971067)
					(end 320.84264 -128.629664)
				)
				(arc
					(start 320.6242 -128.629664)
					(mid 320.3575 -128.893836)
					(end 320.0908 -128.629664)
				)
				(arc
					(start 319.4812 -128.629664)
					(mid 319.2145 -128.893836)
					(end 318.9478 -128.629664)
				)
				(arc
					(start 318.9478 -128.627124)
					(mid 319.2145 -128.360424)
					(end 319.4812 -128.627124)
				)
				(arc
					(start 320.0908 -128.627124)
					(mid 320.3575 -128.360424)
					(end 320.6242 -128.627124)
				)
				(arc
					(start 320.84264 -128.627124)
					(mid 320.700546 -128.284078)
					(end 320.3575 -128.141984)
				)
			)
		)
	)
	(zone
		(layers "In2.Cu" "In5.Cu")
		(hatch none 0.5)
		(connect_pads
			(clearance 0)
		)
		(min_thickness 0.25)
		(keepout
			(tracks not_allowed)
			(vias allowed)
			(pads allowed)
			(copperpour not_allowed)
			(footprints allowed)
		)
		(placement
			(enabled no)
			(sheetname "")
		)
		(fill yes
			(thermal_gap 0.5)
			(thermal_bridge_width 0.5)
			(island_removal_mode 0)
		)
		(polygon
			(pts
				(arc
					(start 192.520824 -14.419326)
					(mid 192.035684 -13.934186)
					(end 191.550544 -14.419326)
				)
				(arc
					(start 191.550544 -15.562326)
					(mid 192.034414 -16.047464)
					(end 192.520824 -15.564866)
				)
				(arc
					(start 192.302384 -15.564866)
					(mid 192.035684 -15.829038)
					(end 191.768984 -15.564866)
				)
				(arc
					(start 191.768984 -15.562326)
					(mid 192.035684 -15.295626)
					(end 192.302384 -15.562326)
				)
				(xy 192.520824 -15.562326) (xy 192.520824 -14.421866)
				(arc
					(start 192.302384 -14.421866)
					(mid 192.035684 -14.686038)
					(end 191.768984 -14.421866)
				)
				(arc
					(start 191.768984 -14.419326)
					(mid 192.035684 -14.152626)
					(end 192.302384 -14.419326)
				)
			)
		)
	)
	(zone
		(layers "In2.Cu" "In5.Cu")
		(hatch none 0.5)
		(connect_pads
			(clearance 0)
		)
		(min_thickness 0.25)
		(keepout
			(tracks not_allowed)
			(vias allowed)
			(pads allowed)
			(copperpour not_allowed)
			(footprints allowed)
		)
		(placement
			(enabled no)
			(sheetname "")
		)
		(fill yes
			(thermal_gap 0.5)
			(thermal_bridge_width 0.5)
			(island_removal_mode 0)
		)
		(polygon
			(pts
				(arc
					(start 382.314704 -13.14196)
					(mid 381.82931 -13.626973)
					(end 382.31445 -14.11224)
				)
				(arc
					(start 383.45745 -14.11224)
					(mid 383.799597 -13.971043)
					(end 383.94259 -13.62964)
				)
				(arc
					(start 383.72415 -13.62964)
					(mid 383.45745 -13.893812)
					(end 383.19075 -13.62964)
				)
				(arc
					(start 382.58115 -13.62964)
					(mid 382.31445 -13.893812)
					(end 382.04775 -13.62964)
				)
				(arc
					(start 382.04775 -13.6271)
					(mid 382.31445 -13.3604)
					(end 382.58115 -13.6271)
				)
				(arc
					(start 383.19075 -13.6271)
					(mid 383.45745 -13.3604)
					(end 383.72415 -13.6271)
				)
				(arc
					(start 383.94259 -13.6271)
					(mid 383.800496 -13.284054)
					(end 383.45745 -13.14196)
				)
			)
		)
	)
	(zone
		(layers "In2.Cu" "In5.Cu")
		(hatch none 0.5)
		(connect_pads
			(clearance 0)
		)
		(min_thickness 0.25)
		(keepout
			(tracks not_allowed)
			(vias allowed)
			(pads allowed)
			(copperpour not_allowed)
			(footprints allowed)
		)
		(placement
			(enabled no)
			(sheetname "")
		)
		(fill yes
			(thermal_gap 0.5)
			(thermal_bridge_width 0.5)
			(island_removal_mode 0)
		)
		(polygon
			(pts
				(arc
					(start 414.527492 -244.444774)
					(mid 414.042352 -243.959634)
					(end 413.557212 -244.444774)
				)
				(arc
					(start 413.557212 -245.58752)
					(mid 414.040955 -246.072912)
					(end 414.527492 -245.590314)
				)
				(arc
					(start 414.309052 -245.590314)
					(mid 414.042352 -245.854486)
					(end 413.775652 -245.590314)
				)
				(arc
					(start 413.775652 -245.587774)
					(mid 414.042352 -245.321074)
					(end 414.309052 -245.587774)
				)
				(xy 414.527492 -245.587774) (xy 414.527492 -244.447314)
				(arc
					(start 414.309052 -244.447314)
					(mid 414.042352 -244.711486)
					(end 413.775652 -244.447314)
				)
				(arc
					(start 413.775652 -244.444774)
					(mid 414.042352 -244.178074)
					(end 414.309052 -244.444774)
				)
			)
		)
	)
	(zone
		(layers "In2.Cu" "In5.Cu")
		(hatch none 0.5)
		(connect_pads
			(clearance 0)
		)
		(min_thickness 0.25)
		(keepout
			(tracks not_allowed)
			(vias allowed)
			(pads allowed)
			(copperpour not_allowed)
			(footprints allowed)
		)
		(placement
			(enabled no)
			(sheetname "")
		)
		(fill yes
			(thermal_gap 0.5)
			(thermal_bridge_width 0.5)
			(island_removal_mode 0)
		)
		(polygon
			(pts
				(arc
					(start 192.520824 -244.419374)
					(mid 192.035684 -243.934234)
					(end 191.550544 -244.419374)
				)
				(arc
					(start 191.550544 -245.56212)
					(mid 192.034287 -246.047512)
					(end 192.520824 -245.564914)
				)
				(arc
					(start 192.302384 -245.564914)
					(mid 192.035684 -245.829086)
					(end 191.768984 -245.564914)
				)
				(arc
					(start 191.768984 -245.562374)
					(mid 192.035684 -245.295674)
					(end 192.302384 -245.562374)
				)
				(xy 192.520824 -245.562374) (xy 192.520824 -244.421914)
				(arc
					(start 192.302384 -244.421914)
					(mid 192.035684 -244.686086)
					(end 191.768984 -244.421914)
				)
				(arc
					(start 191.768984 -244.419374)
					(mid 192.035684 -244.152674)
					(end 192.302384 -244.419374)
				)
			)
		)
	)
	(zone
		(layers "In2.Cu" "In5.Cu")
		(hatch none 0.5)
		(connect_pads
			(clearance 0)
		)
		(min_thickness 0.25)
		(keepout
			(tracks not_allowed)
			(vias allowed)
			(pads allowed)
			(copperpour not_allowed)
			(footprints allowed)
		)
		(placement
			(enabled no)
			(sheetname "")
		)
		(fill yes
			(thermal_gap 0.5)
			(thermal_bridge_width 0.5)
			(island_removal_mode 0)
		)
		(polygon
			(pts
				(arc
					(start 129.42062 -14.419326)
					(mid 128.93548 -13.934186)
					(end 128.45034 -14.419326)
				)
				(arc
					(start 128.45034 -15.562326)
					(mid 128.93421 -16.047464)
					(end 129.42062 -15.564866)
				)
				(arc
					(start 129.20218 -15.564866)
					(mid 128.93548 -15.829038)
					(end 128.66878 -15.564866)
				)
				(arc
					(start 128.66878 -15.562326)
					(mid 128.93548 -15.295626)
					(end 129.20218 -15.562326)
				)
				(xy 129.42062 -15.562326) (xy 129.42062 -14.421866)
				(arc
					(start 129.20218 -14.421866)
					(mid 128.93548 -14.686038)
					(end 128.66878 -14.421866)
				)
				(arc
					(start 128.66878 -14.419326)
					(mid 128.93548 -14.152626)
					(end 129.20218 -14.419326)
				)
			)
		)
	)
	(zone
		(layers "In2.Cu" "In5.Cu")
		(hatch none 0.5)
		(connect_pads
			(clearance 0)
		)
		(min_thickness 0.25)
		(keepout
			(tracks not_allowed)
			(vias allowed)
			(pads allowed)
			(copperpour not_allowed)
			(footprints allowed)
		)
		(placement
			(enabled no)
			(sheetname "")
		)
		(fill yes
			(thermal_gap 0.5)
			(thermal_bridge_width 0.5)
			(island_removal_mode 0)
		)
		(polygon
			(pts
				(arc
					(start 129.42062 -129.41935)
					(mid 128.93548 -128.93421)
					(end 128.45034 -129.41935)
				)
				(arc
					(start 128.45034 -130.56235)
					(mid 128.93421 -131.047488)
					(end 129.42062 -130.56489)
				)
				(arc
					(start 129.20218 -130.56489)
					(mid 128.93548 -130.829062)
					(end 128.66878 -130.56489)
				)
				(arc
					(start 128.66878 -130.56235)
					(mid 128.93548 -130.29565)
					(end 129.20218 -130.56235)
				)
				(xy 129.42062 -130.56235) (xy 129.42062 -129.42189)
				(arc
					(start 129.20218 -129.42189)
					(mid 128.93548 -129.686062)
					(end 128.66878 -129.42189)
				)
				(arc
					(start 128.66878 -129.41935)
					(mid 128.93548 -129.15265)
					(end 129.20218 -129.41935)
				)
			)
		)
	)
	(zone
		(layers "In2.Cu" "In5.Cu")
		(hatch none 0.5)
		(connect_pads
			(clearance 0)
		)
		(min_thickness 0.25)
		(keepout
			(tracks not_allowed)
			(vias allowed)
			(pads allowed)
			(copperpour not_allowed)
			(footprints allowed)
		)
		(placement
			(enabled no)
			(sheetname "")
		)
		(fill yes
			(thermal_gap 0.5)
			(thermal_bridge_width 0.5)
			(island_removal_mode 0)
		)
		(polygon
			(pts
				(arc
					(start 477.637602 -244.312694)
					(mid 477.152462 -243.827554)
					(end 476.667322 -244.312694)
				)
				(arc
					(start 476.667322 -245.45544)
					(mid 477.151065 -245.940832)
					(end 477.637602 -245.458234)
				)
				(arc
					(start 477.419162 -245.458234)
					(mid 477.152462 -245.722406)
					(end 476.885762 -245.458234)
				)
				(arc
					(start 476.885762 -245.455694)
					(mid 477.152462 -245.188994)
					(end 477.419162 -245.455694)
				)
				(xy 477.637602 -245.455694) (xy 477.637602 -244.315234)
				(arc
					(start 477.419162 -244.315234)
					(mid 477.152462 -244.579406)
					(end 476.885762 -244.315234)
				)
				(arc
					(start 476.885762 -244.312694)
					(mid 477.152462 -244.045994)
					(end 477.419162 -244.312694)
				)
			)
		)
	)
	(zone
		(layers "In2.Cu" "In5.Cu")
		(hatch none 0.5)
		(connect_pads
			(clearance 0)
		)
		(min_thickness 0.25)
		(keepout
			(tracks not_allowed)
			(vias allowed)
			(pads allowed)
			(copperpour not_allowed)
			(footprints allowed)
		)
		(placement
			(enabled no)
			(sheetname "")
		)
		(fill yes
			(thermal_gap 0.5)
			(thermal_bridge_width 0.5)
			(island_removal_mode 0)
		)
		(polygon
			(pts
				(arc
					(start 382.314704 -128.141984)
					(mid 381.82931 -128.626997)
					(end 382.31445 -129.112264)
				)
				(arc
					(start 383.45745 -129.112264)
					(mid 383.799597 -128.971067)
					(end 383.94259 -128.629664)
				)
				(arc
					(start 383.72415 -128.629664)
					(mid 383.45745 -128.893836)
					(end 383.19075 -128.629664)
				)
				(arc
					(start 382.58115 -128.629664)
					(mid 382.31445 -128.893836)
					(end 382.04775 -128.629664)
				)
				(arc
					(start 382.04775 -128.627124)
					(mid 382.31445 -128.360424)
					(end 382.58115 -128.627124)
				)
				(arc
					(start 383.19075 -128.627124)
					(mid 383.45745 -128.360424)
					(end 383.72415 -128.627124)
				)
				(arc
					(start 383.94259 -128.627124)
					(mid 383.800496 -128.284078)
					(end 383.45745 -128.141984)
				)
			)
		)
	)
	(zone
		(layers "In2.Cu" "In5.Cu")
		(hatch none 0.5)
		(connect_pads
			(clearance 0)
		)
		(min_thickness 0.25)
		(keepout
			(tracks not_allowed)
			(vias allowed)
			(pads allowed)
			(copperpour not_allowed)
			(footprints allowed)
		)
		(placement
			(enabled no)
			(sheetname "")
		)
		(fill yes
			(thermal_gap 0.5)
			(thermal_bridge_width 0.5)
			(island_removal_mode 0)
		)
		(polygon
			(pts
				(arc
					(start 66.32067 -14.419326)
					(mid 65.83553 -13.934186)
					(end 65.35039 -14.419326)
				)
				(arc
					(start 65.35039 -15.562326)
					(mid 65.83426 -16.047464)
					(end 66.32067 -15.564866)
				)
				(arc
					(start 66.10223 -15.564866)
					(mid 65.83553 -15.829038)
					(end 65.56883 -15.564866)
				)
				(arc
					(start 65.56883 -15.562326)
					(mid 65.83553 -15.295626)
					(end 66.10223 -15.562326)
				)
				(xy 66.32067 -15.562326) (xy 66.32067 -14.421866)
				(arc
					(start 66.10223 -14.421866)
					(mid 65.83553 -14.686038)
					(end 65.56883 -14.421866)
				)
				(arc
					(start 65.56883 -14.419326)
					(mid 65.83553 -14.152626)
					(end 66.10223 -14.419326)
				)
			)
		)
	)
	(zone
		(layers "In2.Cu" "In5.Cu")
		(hatch none 0.5)
		(connect_pads
			(clearance 0)
		)
		(min_thickness 0.25)
		(keepout
			(tracks not_allowed)
			(vias allowed)
			(pads allowed)
			(copperpour not_allowed)
			(footprints allowed)
		)
		(placement
			(enabled no)
			(sheetname "")
		)
		(fill yes
			(thermal_gap 0.5)
			(thermal_bridge_width 0.5)
			(island_removal_mode 0)
		)
		(polygon
			(pts
				(arc
					(start 160.970722 -14.419326)
					(mid 160.485582 -13.934186)
					(end 160.000442 -14.419326)
				)
				(arc
					(start 160.000442 -15.562326)
					(mid 160.484312 -16.047464)
					(end 160.970722 -15.564866)
				)
				(arc
					(start 160.752282 -15.564866)
					(mid 160.485582 -15.829038)
					(end 160.218882 -15.564866)
				)
				(arc
					(start 160.218882 -15.562326)
					(mid 160.485582 -15.295626)
					(end 160.752282 -15.562326)
				)
				(xy 160.970722 -15.562326) (xy 160.970722 -14.421866)
				(arc
					(start 160.752282 -14.421866)
					(mid 160.485582 -14.686038)
					(end 160.218882 -14.421866)
				)
				(arc
					(start 160.218882 -14.419326)
					(mid 160.485582 -14.152626)
					(end 160.752282 -14.419326)
				)
			)
		)
	)
	(zone
		(layers "In2.Cu" "In5.Cu")
		(hatch none 0.5)
		(connect_pads
			(clearance 0)
		)
		(min_thickness 0.25)
		(keepout
			(tracks not_allowed)
			(vias allowed)
			(pads allowed)
			(copperpour not_allowed)
			(footprints allowed)
		)
		(placement
			(enabled no)
			(sheetname "")
		)
		(fill yes
			(thermal_gap 0.5)
			(thermal_bridge_width 0.5)
			(island_removal_mode 0)
		)
		(polygon
			(pts
				(arc
					(start 97.870772 -244.419374)
					(mid 97.385632 -243.934234)
					(end 96.900492 -244.419374)
				)
				(arc
					(start 96.900492 -245.56212)
					(mid 97.384235 -246.047512)
					(end 97.870772 -245.564914)
				)
				(arc
					(start 97.652332 -245.564914)
					(mid 97.385632 -245.829086)
					(end 97.118932 -245.564914)
				)
				(arc
					(start 97.118932 -245.562374)
					(mid 97.385632 -245.295674)
					(end 97.652332 -245.562374)
				)
				(xy 97.870772 -245.562374) (xy 97.870772 -244.421914)
				(arc
					(start 97.652332 -244.421914)
					(mid 97.385632 -244.686086)
					(end 97.118932 -244.421914)
				)
				(arc
					(start 97.118932 -244.419374)
					(mid 97.385632 -244.152674)
					(end 97.652332 -244.419374)
				)
			)
		)
	)
	(zone
		(layers "In2.Cu" "In5.Cu")
		(hatch none 0.5)
		(connect_pads
			(clearance 0)
		)
		(min_thickness 0.25)
		(keepout
			(tracks not_allowed)
			(vias allowed)
			(pads allowed)
			(copperpour not_allowed)
			(footprints allowed)
		)
		(placement
			(enabled no)
			(sheetname "")
		)
		(fill yes
			(thermal_gap 0.5)
			(thermal_bridge_width 0.5)
			(island_removal_mode 0)
		)
		(polygon
			(pts
				(arc
					(start 319.8876 -244.312694)
					(mid 319.40246 -243.827554)
					(end 318.91732 -244.312694)
				)
				(arc
					(start 318.91732 -245.45544)
					(mid 319.401063 -245.940832)
					(end 319.8876 -245.458234)
				)
				(arc
					(start 319.66916 -245.458234)
					(mid 319.40246 -245.722406)
					(end 319.13576 -245.458234)
				)
				(arc
					(start 319.13576 -245.455694)
					(mid 319.40246 -245.188994)
					(end 319.66916 -245.455694)
				)
				(xy 319.8876 -245.455694) (xy 319.8876 -244.315234)
				(arc
					(start 319.66916 -244.315234)
					(mid 319.40246 -244.579406)
					(end 319.13576 -244.315234)
				)
				(arc
					(start 319.13576 -244.312694)
					(mid 319.40246 -244.045994)
					(end 319.66916 -244.312694)
				)
			)
		)
	)
	(zone
		(layers "In2.Cu" "In5.Cu")
		(hatch none 0.5)
		(connect_pads
			(clearance 0)
		)
		(min_thickness 0.25)
		(keepout
			(tracks not_allowed)
			(vias allowed)
			(pads allowed)
			(copperpour not_allowed)
			(footprints allowed)
		)
		(placement
			(enabled no)
			(sheetname "")
		)
		(fill yes
			(thermal_gap 0.5)
			(thermal_bridge_width 0.5)
			(island_removal_mode 0)
		)
		(polygon
			(pts
				(arc
					(start 445.414654 -13.14196)
					(mid 444.92926 -13.626973)
					(end 445.4144 -14.11224)
				)
				(arc
					(start 446.5574 -14.11224)
					(mid 446.899547 -13.971043)
					(end 447.04254 -13.62964)
				)
				(arc
					(start 446.8241 -13.62964)
					(mid 446.5574 -13.893812)
					(end 446.2907 -13.62964)
				)
				(arc
					(start 445.6811 -13.62964)
					(mid 445.4144 -13.893812)
					(end 445.1477 -13.62964)
				)
				(arc
					(start 445.1477 -13.6271)
					(mid 445.4144 -13.3604)
					(end 445.6811 -13.6271)
				)
				(arc
					(start 446.2907 -13.6271)
					(mid 446.5574 -13.3604)
					(end 446.8241 -13.6271)
				)
				(arc
					(start 447.04254 -13.6271)
					(mid 446.900446 -13.284054)
					(end 446.5574 -13.14196)
				)
			)
		)
	)
	(zone
		(layers "In2.Cu" "In5.Cu")
		(hatch none 0.5)
		(connect_pads
			(clearance 0)
		)
		(min_thickness 0.25)
		(keepout
			(tracks not_allowed)
			(vias allowed)
			(pads allowed)
			(copperpour not_allowed)
			(footprints allowed)
		)
		(placement
			(enabled no)
			(sheetname "")
		)
		(fill yes
			(thermal_gap 0.5)
			(thermal_bridge_width 0.5)
			(island_removal_mode 0)
		)
		(polygon
			(pts
				(arc
					(start 382.97739 -244.302534)
					(mid 382.49225 -243.817394)
					(end 382.00711 -244.302534)
				)
				(arc
					(start 382.00711 -245.44528)
					(mid 382.490853 -245.930672)
					(end 382.97739 -245.448074)
				)
				(arc
					(start 382.75895 -245.448074)
					(mid 382.49225 -245.712246)
					(end 382.22555 -245.448074)
				)
				(arc
					(start 382.22555 -245.445534)
					(mid 382.49225 -245.178834)
					(end 382.75895 -245.445534)
				)
				(xy 382.97739 -245.445534) (xy 382.97739 -244.305074)
				(arc
					(start 382.75895 -244.305074)
					(mid 382.49225 -244.569246)
					(end 382.22555 -244.305074)
				)
				(arc
					(start 382.22555 -244.302534)
					(mid 382.49225 -244.035834)
					(end 382.75895 -244.302534)
				)
			)
		)
	)
	(zone
		(layers "In2.Cu" "In5.Cu")
		(hatch none 0.5)
		(connect_pads
			(clearance 0)
		)
		(min_thickness 0.25)
		(keepout
			(tracks not_allowed)
			(vias allowed)
			(pads allowed)
			(copperpour not_allowed)
			(footprints allowed)
		)
		(placement
			(enabled no)
			(sheetname "")
		)
		(fill yes
			(thermal_gap 0.5)
			(thermal_bridge_width 0.5)
			(island_removal_mode 0)
		)
		(polygon
			(pts
				(arc
					(start 34.770822 -129.41935)
					(mid 34.285682 -128.93421)
					(end 33.800542 -129.41935)
				)
				(arc
					(start 33.800542 -130.56235)
					(mid 34.284412 -131.047488)
					(end 34.770822 -130.56489)
				)
				(arc
					(start 34.552382 -130.56489)
					(mid 34.285682 -130.829062)
					(end 34.018982 -130.56489)
				)
				(arc
					(start 34.018982 -130.56235)
					(mid 34.285682 -130.29565)
					(end 34.552382 -130.56235)
				)
				(xy 34.770822 -130.56235) (xy 34.770822 -129.42189)
				(arc
					(start 34.552382 -129.42189)
					(mid 34.285682 -129.686062)
					(end 34.018982 -129.42189)
				)
				(arc
					(start 34.018982 -129.41935)
					(mid 34.285682 -129.15265)
					(end 34.552382 -129.41935)
				)
			)
		)
	)
	(zone
		(layers "In2.Cu" "In5.Cu")
		(hatch none 0.5)
		(connect_pads
			(clearance 0)
		)
		(min_thickness 0.25)
		(keepout
			(tracks not_allowed)
			(vias allowed)
			(pads allowed)
			(copperpour not_allowed)
			(footprints allowed)
		)
		(placement
			(enabled no)
			(sheetname "")
		)
		(fill yes
			(thermal_gap 0.5)
			(thermal_bridge_width 0.5)
			(island_removal_mode 0)
		)
		(polygon
			(pts
				(arc
					(start 160.970722 -244.419374)
					(mid 160.485582 -243.934234)
					(end 160.000442 -244.419374)
				)
				(arc
					(start 160.000442 -245.56212)
					(mid 160.484185 -246.047512)
					(end 160.970722 -245.564914)
				)
				(arc
					(start 160.752282 -245.564914)
					(mid 160.485582 -245.829086)
					(end 160.218882 -245.564914)
				)
				(arc
					(start 160.218882 -245.562374)
					(mid 160.485582 -245.295674)
					(end 160.752282 -245.562374)
				)
				(xy 160.970722 -245.562374) (xy 160.970722 -244.421914)
				(arc
					(start 160.752282 -244.421914)
					(mid 160.485582 -244.686086)
					(end 160.218882 -244.421914)
				)
				(arc
					(start 160.218882 -244.419374)
					(mid 160.485582 -244.152674)
					(end 160.752282 -244.419374)
				)
			)
		)
	)
	(zone
		(net "GND")
		(layer "In3.Cu")
		(hatch none 0.5)
		(connect_pads
			(clearance 0.5)
		)
		(min_thickness 0.25)
		(fill yes
			(thermal_gap 0.5)
			(thermal_bridge_width 0.5)
			(island_removal_mode 0)
		)
		(polygon
			(pts
				(xy 209.32902 -64.269874) (xy 209.0039 -64.595248) (xy 209.0039 -81.124806) (xy 209.552794 -81.6737)
				(xy 223.288606 -81.6737) (xy 223.8121 -81.150206) (xy 223.8121 -64.269874)
			)
		)
		(polygon
			(pts
				(arc
					(start 221.348808 -77.599794)
					(mid 220.800041 -77.051408)
					(end 220.251528 -77.600048)
				)
				(arc
					(start 220.251528 -78.999842)
					(mid 220.800168 -79.548482)
					(end 221.348808 -78.999842)
				)
			)
		)
		(polygon
			(pts
				(arc
					(start 217.748612 -77.599794)
					(mid 217.199845 -77.051408)
					(end 216.651332 -77.600048)
				)
				(arc
					(start 216.651332 -78.999842)
					(mid 217.199972 -79.548482)
					(end 217.748612 -78.999842)
				)
			)
		)
		(polygon
			(pts
				(arc
					(start 214.14867 -77.599794)
					(mid 213.599903 -77.051408)
					(end 213.05139 -77.600048)
				)
				(arc
					(start 213.05139 -78.999842)
					(mid 213.60003 -79.548482)
					(end 214.14867 -78.999842)
				)
			)
		)
		(polygon
			(pts
				(arc
					(start 210.548728 -77.599794)
					(mid 209.999961 -77.051408)
					(end 209.451448 -77.600048)
				)
				(arc
					(start 209.451448 -78.999842)
					(mid 210.000088 -79.548482)
					(end 210.548728 -78.999842)
				)
			)
		)
		(polygon
			(pts
				(arc
					(start 223.148652 -76.399898)
					(mid 222.600012 -75.851258)
					(end 222.051372 -76.399898)
				)
				(arc
					(start 222.051372 -77.8002)
					(mid 222.600139 -78.348586)
					(end 223.148652 -77.799946)
				)
			)
		)
		(polygon
			(pts
				(arc
					(start 219.54871 -76.399898)
					(mid 219.00007 -75.851258)
					(end 218.45143 -76.399898)
				)
				(arc
					(start 218.45143 -77.8002)
					(mid 219.000197 -78.348586)
					(end 219.54871 -77.799946)
				)
			)
		)
		(polygon
			(pts
				(arc
					(start 215.948768 -76.399898)
					(mid 215.400128 -75.851258)
					(end 214.851488 -76.399898)
				)
				(arc
					(start 214.851488 -77.8002)
					(mid 215.400255 -78.348586)
					(end 215.948768 -77.799946)
				)
			)
		)
		(polygon
			(pts
				(arc
					(start 212.348826 -76.399898)
					(mid 211.800186 -75.851258)
					(end 211.251546 -76.399898)
				)
				(arc
					(start 211.251546 -77.8002)
					(mid 211.800313 -78.348586)
					(end 212.348826 -77.799946)
				)
			)
		)
		(polygon
			(pts
				(arc
					(start 210.548728 -73.999852)
					(mid 210.000088 -73.451212)
					(end 209.451448 -73.999852)
				)
				(arc
					(start 209.451448 -75.400154)
					(mid 210.000215 -75.94854)
					(end 210.548728 -75.3999)
				)
			)
		)
		(polygon
			(pts
				(arc
					(start 221.348808 -70.39991)
					(mid 220.800168 -69.85127)
					(end 220.251528 -70.39991)
				)
				(arc
					(start 220.251528 -71.800212)
					(mid 220.800295 -72.348598)
					(end 221.348808 -71.799958)
				)
			)
		)
		(polygon
			(pts
				(arc
					(start 217.748612 -70.39991)
					(mid 217.199972 -69.85127)
					(end 216.651332 -70.39991)
				)
				(arc
					(start 216.651332 -71.800212)
					(mid 217.200099 -72.348598)
					(end 217.748612 -71.799958)
				)
			)
		)
		(polygon
			(pts
				(arc
					(start 214.14867 -70.39991)
					(mid 213.60003 -69.85127)
					(end 213.05139 -70.39991)
				)
				(arc
					(start 213.05139 -71.800212)
					(mid 213.600157 -72.348598)
					(end 214.14867 -71.799958)
				)
			)
		)
		(polygon
			(pts
				(arc
					(start 210.548728 -70.39991)
					(mid 210.000088 -69.85127)
					(end 209.451448 -70.39991)
				)
				(arc
					(start 209.451448 -71.800212)
					(mid 210.000215 -72.348598)
					(end 210.548728 -71.799958)
				)
			)
		)
		(polygon
			(pts
				(arc
					(start 219.54871 -65.600072)
					(mid 219.00007 -65.051432)
					(end 218.45143 -65.600072)
				)
				(arc
					(start 218.45143 -67.00012)
					(mid 219.000197 -67.548506)
					(end 219.54871 -66.999866)
				)
			)
		)
		(polygon
			(pts
				(arc
					(start 215.948768 -65.600072)
					(mid 215.400128 -65.051432)
					(end 214.851488 -65.600072)
				)
				(arc
					(start 214.851488 -67.00012)
					(mid 215.400255 -67.548506)
					(end 215.948768 -66.999866)
				)
			)
		)
		(polygon
			(pts
				(arc
					(start 212.348826 -65.600072)
					(mid 211.800186 -65.051432)
					(end 211.251546 -65.600072)
				)
				(arc
					(start 211.251546 -67.00012)
					(mid 211.800313 -67.548506)
					(end 212.348826 -66.999866)
				)
			)
		)
		(polygon
			(pts
				(arc
					(start 223.148652 -65.599818)
					(mid 222.599885 -65.051432)
					(end 222.051372 -65.600072)
				)
				(arc
					(start 222.051372 -66.999866)
					(mid 222.600012 -67.548506)
					(end 223.148652 -66.999866)
				)
			)
		)
	)
	(zone
		(net "P12V_B")
		(layer "In3.Cu")
		(hatch none 0.5)
		(connect_pads
			(clearance 0.5)
		)
		(min_thickness 0.25)
		(fill yes
			(thermal_gap 0.5)
			(thermal_bridge_width 0.5)
			(island_removal_mode 0)
		)
		(polygon
			(pts
				(xy 1.27 -1.27) (xy 1.27 -369.73002)
				(arc
					(start 1.999996 -369.73002)
					(mid 3.605127 -370.394887)
					(end 4.269994 -372.000018)
				)
				(xy 4.269994 -384.72999) (xy 14.979904 -384.72999)
				(arc
					(start 14.979904 -383.29997)
					(mid 15.644771 -381.694839)
					(end 17.249902 -381.029972)
				)
				(arc
					(start 23.750016 -381.029972)
					(mid 24.317409 -381.163766)
					(end 24.765254 -381.536956)
				)
				(arc
					(start 25.180036 -381.536956)
					(mid 25.799334 -382.323511)
					(end 26.020014 -383.29997)
				)
				(xy 26.020014 -384.72999) (xy 71.030084 -384.72999)
				(arc
					(start 71.030084 -381)
					(mid 71.694951 -379.394869)
					(end 73.300082 -378.730002)
				)
				(arc
					(start 125.299978 -378.730002)
					(mid 126.905109 -379.394869)
					(end 127.569976 -381)
				)
				(xy 127.569976 -384.72999) (xy 172.580046 -384.72999)
				(arc
					(start 172.580046 -383.29997)
					(mid 173.244913 -381.694839)
					(end 174.850044 -381.029972)
				)
				(arc
					(start 181.349904 -381.029972)
					(mid 182.955035 -381.694839)
					(end 183.619902 -383.29997)
				)
				(xy 183.619902 -384.72999) (xy 196.730112 -384.72999)
				(arc
					(start 196.730112 -381)
					(mid 197.394979 -379.394869)
					(end 199.00011 -378.730002)
				)
				(arc
					(start 251.000006 -378.730002)
					(mid 252.605137 -379.394869)
					(end 253.270004 -381)
				)
				(xy 253.270004 -384.72999) (xy 268.924024 -384.72999) (xy 271.180052 -382.473962)
				(arc
					(start 271.180052 -361.00004)
					(mid 271.844919 -359.394909)
					(end 273.45005 -358.730042)
				)
				(arc
					(start 275.75002 -358.730042)
					(mid 277.355151 -359.394909)
					(end 278.020018 -361.00004)
				)
				(xy 278.020018 -382.473962) (xy 280.276046 -384.72999) (xy 306.37988 -384.72999)
				(arc
					(start 306.37988 -383.29997)
					(mid 307.044747 -381.694839)
					(end 308.649878 -381.029972)
				)
				(arc
					(start 315.149992 -381.029972)
					(mid 316.755123 -381.694839)
					(end 317.41999 -383.29997)
				)
				(xy 317.41999 -384.72999) (xy 362.43006 -384.72999)
				(arc
					(start 362.43006 -381)
					(mid 363.094927 -379.394869)
					(end 364.700058 -378.730002)
				)
				(arc
					(start 416.699954 -378.730002)
					(mid 418.305085 -379.394869)
					(end 418.969952 -381)
				)
				(xy 418.969952 -384.72999) (xy 463.980022 -384.72999)
				(arc
					(start 463.980022 -383.29997)
					(mid 464.644889 -381.694839)
					(end 466.25002 -381.029972)
				)
				(arc
					(start 472.74988 -381.029972)
					(mid 474.355011 -381.694839)
					(end 475.019878 -383.29997)
				)
				(xy 475.019878 -384.72999) (xy 487.179874 -384.72999)
				(arc
					(start 487.179874 -372.000018)
					(mid 487.844831 -370.394797)
					(end 489.450126 -369.73002)
				)
				(xy 490.180122 -369.73002) (xy 490.180122 -1.27) (xy 312.269886 -1.27)
				(arc
					(start 312.269886 -47.200058)
					(mid 311.605019 -48.805189)
					(end 309.999888 -49.470056)
				)
				(xy 270.26997 -49.470056)
				(arc
					(start 270.26997 -61.999876)
					(mid 269.605103 -63.605007)
					(end 267.999972 -64.269874)
				)
				(xy 224.36582 -64.269874) (xy 224.1931 -64.442594) (xy 224.1931 -81.308194) (xy 223.446594 -82.0547)
				(xy 209.394806 -82.0547) (xy 208.6229 -81.282794) (xy 208.6229 -64.620394) (xy 208.27238 -64.269874)
				(arc
					(start 208.000092 -64.269874)
					(mid 206.394961 -63.605007)
					(end 205.730094 -61.999876)
				)
				(xy 205.730094 -49.470056)
				(arc
					(start 200.000108 -49.470056)
					(mid 198.394977 -48.805189)
					(end 197.73011 -47.200058)
				)
				(xy 197.73011 -1.27)
			)
		)
		(polygon
			(pts
				(xy 157.431994 -326.8345) (xy 152.194006 -326.8345) (xy 151.4475 -327.581006) (xy 151.4475 -330.756006)
				(xy 151.18461 -331.018896) (xy 104.06761 -331.018896) (xy 102.5525 -332.534006) (xy 102.5525 -346.280994)
				(xy 103.4415 -347.169994) (xy 103.4415 -364.348776) (xy 103.964994 -364.87227) (xy 109.369606 -364.87227)
				(xy 112.286796 -361.95508) (xy 123.153932 -361.95508) (xy 126.524512 -358.5845) (xy 160.9725 -358.5845)
				(xy 160.9725 -358.2162) (xy 166.0144 -358.2162) (xy 166.0144 -358.5845) (xy 166.664894 -358.5845)
				(xy 166.7764 -358.472994) (xy 166.7764 -358.315006) (xy 166.664894 -358.2035) (xy 166.3954 -358.2035)
				(xy 166.3954 -328.851006) (xy 166.283894 -328.7395) (xy 166.125906 -328.7395) (xy 166.0144 -328.851006)
				(xy 166.0144 -329.1078) (xy 160.9725 -329.1078) (xy 160.9725 -328.7395) (xy 158.066994 -328.7395)
				(xy 157.7975 -328.470006) (xy 157.7975 -327.200006)
			)
		)
		(polygon
			(pts
				(arc
					(start 159.193992 -248.115074)
					(mid 158.708852 -247.629934)
					(end 158.223712 -248.115074)
				)
				(arc
					(start 158.223712 -249.385328)
					(mid 158.708979 -249.870214)
					(end 159.193992 -249.385074)
				)
			)
		)
		(polygon
			(pts
				(arc
					(start 481.824792 -248.11482)
					(mid 481.339525 -247.629934)
					(end 480.854512 -248.115074)
				)
				(arc
					(start 480.854512 -249.385074)
					(mid 481.339652 -249.870214)
					(end 481.824792 -249.385074)
				)
			)
		)
		(polygon
			(pts
				(arc
					(start 450.27469 -248.11482)
					(mid 449.789423 -247.629934)
					(end 449.30441 -248.115074)
				)
				(arc
					(start 449.30441 -249.385074)
					(mid 449.78955 -249.870214)
					(end 450.27469 -249.385074)
				)
			)
		)
		(polygon
			(pts
				(arc
					(start 418.724842 -248.11482)
					(mid 418.239575 -247.629934)
					(end 417.754562 -248.115074)
				)
				(arc
					(start 417.754562 -249.385074)
					(mid 418.239702 -249.870214)
					(end 418.724842 -249.385074)
				)
			)
		)
		(polygon
			(pts
				(arc
					(start 387.17474 -248.11482)
					(mid 386.689473 -247.629934)
					(end 386.20446 -248.115074)
				)
				(arc
					(start 386.20446 -249.385074)
					(mid 386.6896 -249.870214)
					(end 387.17474 -249.385074)
				)
			)
		)
		(polygon
			(pts
				(arc
					(start 355.624892 -248.11482)
					(mid 355.139625 -247.629934)
					(end 354.654612 -248.115074)
				)
				(arc
					(start 354.654612 -249.385074)
					(mid 355.139752 -249.870214)
					(end 355.624892 -249.385074)
				)
			)
		)
		(polygon
			(pts
				(arc
					(start 324.07479 -248.11482)
					(mid 323.589523 -247.629934)
					(end 323.10451 -248.115074)
				)
				(arc
					(start 323.10451 -249.385074)
					(mid 323.58965 -249.870214)
					(end 324.07479 -249.385074)
				)
			)
		)
		(polygon
			(pts
				(arc
					(start 190.744094 -248.11482)
					(mid 190.258827 -247.629934)
					(end 189.773814 -248.115074)
				)
				(arc
					(start 189.773814 -249.385074)
					(mid 190.258954 -249.870214)
					(end 190.744094 -249.385074)
				)
			)
		)
		(polygon
			(pts
				(arc
					(start 127.64389 -248.11482)
					(mid 127.158623 -247.629934)
					(end 126.67361 -248.115074)
				)
				(arc
					(start 126.67361 -249.385074)
					(mid 127.15875 -249.870214)
					(end 127.64389 -249.385074)
				)
			)
		)
		(polygon
			(pts
				(arc
					(start 96.094042 -248.11482)
					(mid 95.608775 -247.629934)
					(end 95.123762 -248.115074)
				)
				(arc
					(start 95.123762 -249.385074)
					(mid 95.608902 -249.870214)
					(end 96.094042 -249.385074)
				)
			)
		)
		(polygon
			(pts
				(arc
					(start 64.54394 -248.11482)
					(mid 64.058673 -247.629934)
					(end 63.57366 -248.115074)
				)
				(arc
					(start 63.57366 -249.385074)
					(mid 64.0588 -249.870214)
					(end 64.54394 -249.385074)
				)
			)
		)
		(polygon
			(pts
				(arc
					(start 32.994092 -248.11482)
					(mid 32.508825 -247.629934)
					(end 32.023812 -248.115074)
				)
				(arc
					(start 32.023812 -249.385074)
					(mid 32.508952 -249.870214)
					(end 32.994092 -249.385074)
				)
			)
		)
		(polygon
			(pts
				(arc
					(start 414.527492 -244.444774)
					(mid 414.042352 -243.959634)
					(end 413.557212 -244.444774)
				)
				(arc
					(start 413.557212 -245.588028)
					(mid 414.042479 -246.072914)
					(end 414.527492 -245.587774)
				)
			)
		)
		(polygon
			(pts
				(arc
					(start 192.520824 -244.419374)
					(mid 192.035684 -243.934234)
					(end 191.550544 -244.419374)
				)
				(arc
					(start 191.550544 -245.562628)
					(mid 192.035811 -246.047514)
					(end 192.520824 -245.562374)
				)
			)
		)
		(polygon
			(pts
				(arc
					(start 160.970722 -244.419374)
					(mid 160.485582 -243.934234)
					(end 160.000442 -244.419374)
				)
				(arc
					(start 160.000442 -245.562628)
					(mid 160.485709 -246.047514)
					(end 160.970722 -245.562374)
				)
			)
		)
		(polygon
			(pts
				(arc
					(start 129.42062 -244.419374)
					(mid 128.93548 -243.934234)
					(end 128.45034 -244.419374)
				)
				(arc
					(start 128.45034 -245.562628)
					(mid 128.935607 -246.047514)
					(end 129.42062 -245.562374)
				)
			)
		)
		(polygon
			(pts
				(arc
					(start 97.870772 -244.419374)
					(mid 97.385632 -243.934234)
					(end 96.900492 -244.419374)
				)
				(arc
					(start 96.900492 -245.562628)
					(mid 97.385759 -246.047514)
					(end 97.870772 -245.562374)
				)
			)
		)
		(polygon
			(pts
				(arc
					(start 66.32067 -244.419374)
					(mid 65.83553 -243.934234)
					(end 65.35039 -244.419374)
				)
				(arc
					(start 65.35039 -245.562628)
					(mid 65.835657 -246.047514)
					(end 66.32067 -245.562374)
				)
			)
		)
		(polygon
			(pts
				(arc
					(start 34.770822 -244.419374)
					(mid 34.285682 -243.934234)
					(end 33.800542 -244.419374)
				)
				(arc
					(start 33.800542 -245.562628)
					(mid 34.285809 -246.047514)
					(end 34.770822 -245.562374)
				)
			)
		)
		(polygon
			(pts
				(arc
					(start 351.427542 -244.317774)
					(mid 350.942402 -243.832634)
					(end 350.457262 -244.317774)
				)
				(arc
					(start 350.457262 -245.461028)
					(mid 350.942529 -245.945914)
					(end 351.427542 -245.460774)
				)
			)
		)
		(polygon
			(pts
				(arc
					(start 477.637602 -244.312694)
					(mid 477.152462 -243.827554)
					(end 476.667322 -244.312694)
				)
				(arc
					(start 476.667322 -245.455948)
					(mid 477.152589 -245.940834)
					(end 477.637602 -245.455694)
				)
			)
		)
		(polygon
			(pts
				(arc
					(start 446.0875 -244.312694)
					(mid 445.60236 -243.827554)
					(end 445.11722 -244.312694)
				)
				(arc
					(start 445.11722 -245.455948)
					(mid 445.602487 -245.940834)
					(end 446.0875 -245.455694)
				)
			)
		)
		(polygon
			(pts
				(arc
					(start 319.8876 -244.312694)
					(mid 319.40246 -243.827554)
					(end 318.91732 -244.312694)
				)
				(arc
					(start 318.91732 -245.455948)
					(mid 319.402587 -245.940834)
					(end 319.8876 -245.455694)
				)
			)
		)
		(polygon
			(pts
				(arc
					(start 382.97739 -244.302534)
					(mid 382.49225 -243.817394)
					(end 382.00711 -244.302534)
				)
				(arc
					(start 382.00711 -245.445788)
					(mid 382.492377 -245.930674)
					(end 382.97739 -245.445534)
				)
			)
		)
		(polygon
			(pts
				(xy 289.537394 -173.9773) (xy 276.450806 -173.9773) (xy 275.0439 -175.384206) (xy 275.0439 -239.218724)
				(xy 276.350476 -240.5253) (xy 289.943794 -240.5253) (xy 291.1221 -239.346994) (xy 291.1221 -175.562006)
			)
		)
		(polygon
			(pts
				(arc
					(start 159.193992 -133.11505)
					(mid 158.708852 -132.62991)
					(end 158.223712 -133.11505)
				)
				(arc
					(start 158.223712 -134.385304)
					(mid 158.708979 -134.87019)
					(end 159.193992 -134.38505)
				)
			)
		)
		(polygon
			(pts
				(arc
					(start 127.64389 -133.11505)
					(mid 127.15875 -132.62991)
					(end 126.67361 -133.11505)
				)
				(arc
					(start 126.67361 -134.385304)
					(mid 127.158877 -134.87019)
					(end 127.64389 -134.38505)
				)
			)
		)
		(polygon
			(pts
				(arc
					(start 96.094042 -133.11505)
					(mid 95.608902 -132.62991)
					(end 95.123762 -133.11505)
				)
				(arc
					(start 95.123762 -134.385304)
					(mid 95.609029 -134.87019)
					(end 96.094042 -134.38505)
				)
			)
		)
		(polygon
			(pts
				(arc
					(start 64.54394 -133.11505)
					(mid 64.0588 -132.62991)
					(end 63.57366 -133.11505)
				)
				(arc
					(start 63.57366 -134.385304)
					(mid 64.058927 -134.87019)
					(end 64.54394 -134.38505)
				)
			)
		)
		(polygon
			(pts
				(arc
					(start 32.994092 -133.11505)
					(mid 32.508952 -132.62991)
					(end 32.023812 -133.11505)
				)
				(arc
					(start 32.023812 -134.385304)
					(mid 32.509079 -134.87019)
					(end 32.994092 -134.38505)
				)
			)
		)
		(polygon
			(pts
				(arc
					(start 190.744094 -133.114796)
					(mid 190.258827 -132.62991)
					(end 189.773814 -133.11505)
				)
				(arc
					(start 189.773814 -134.38505)
					(mid 190.258954 -134.87019)
					(end 190.744094 -134.38505)
				)
			)
		)
		(polygon
			(pts
				(arc
					(start 481.701602 -132.922264)
					(mid 482.186742 -132.437124)
					(end 481.701602 -131.951984)
				)
				(arc
					(start 480.431348 -131.951984)
					(mid 479.946462 -132.437251)
					(end 480.431602 -132.922264)
				)
			)
		)
		(polygon
			(pts
				(arc
					(start 450.151754 -132.922264)
					(mid 450.63664 -132.436997)
					(end 450.1515 -131.951984)
				)
				(arc
					(start 448.8815 -131.951984)
					(mid 448.39636 -132.437124)
					(end 448.8815 -132.922264)
				)
			)
		)
		(polygon
			(pts
				(arc
					(start 418.601652 -132.922264)
					(mid 419.086792 -132.437124)
					(end 418.601652 -131.951984)
				)
				(arc
					(start 417.331398 -131.951984)
					(mid 416.846512 -132.437251)
					(end 417.331652 -132.922264)
				)
			)
		)
		(polygon
			(pts
				(arc
					(start 387.051804 -132.922264)
					(mid 387.53669 -132.436997)
					(end 387.05155 -131.951984)
				)
				(arc
					(start 385.78155 -131.951984)
					(mid 385.29641 -132.437124)
					(end 385.78155 -132.922264)
				)
			)
		)
		(polygon
			(pts
				(arc
					(start 355.501702 -132.922264)
					(mid 355.986842 -132.437124)
					(end 355.501702 -131.951984)
				)
				(arc
					(start 354.231448 -131.951984)
					(mid 353.746562 -132.437251)
					(end 354.231702 -132.922264)
				)
			)
		)
		(polygon
			(pts
				(arc
					(start 323.951854 -132.922264)
					(mid 324.43674 -132.436997)
					(end 323.9516 -131.951984)
				)
				(arc
					(start 322.6816 -131.951984)
					(mid 322.19646 -132.437124)
					(end 322.6816 -132.922264)
				)
			)
		)
		(polygon
			(pts
				(xy 289.181794 -129.9083) (xy 275.307806 -129.9083) (xy 274.5359 -130.680206) (xy 274.5359 -145.722594)
				(xy 275.841206 -147.0279) (xy 289.562794 -147.0279) (xy 290.5633 -146.027394) (xy 290.5633 -131.289806)
			)
		)
		(polygon
			(pts
				(arc
					(start 192.520824 -129.419096)
					(mid 192.035557 -128.93421)
					(end 191.550544 -129.41935)
				)
				(arc
					(start 191.550544 -130.56235)
					(mid 192.035684 -131.04749)
					(end 192.520824 -130.56235)
				)
			)
		)
		(polygon
			(pts
				(arc
					(start 160.970722 -129.419096)
					(mid 160.485455 -128.93421)
					(end 160.000442 -129.41935)
				)
				(arc
					(start 160.000442 -130.56235)
					(mid 160.485582 -131.04749)
					(end 160.970722 -130.56235)
				)
			)
		)
		(polygon
			(pts
				(arc
					(start 129.42062 -129.419096)
					(mid 128.935353 -128.93421)
					(end 128.45034 -129.41935)
				)
				(arc
					(start 128.45034 -130.56235)
					(mid 128.93548 -131.04749)
					(end 129.42062 -130.56235)
				)
			)
		)
		(polygon
			(pts
				(arc
					(start 97.870772 -129.419096)
					(mid 97.385505 -128.93421)
					(end 96.900492 -129.41935)
				)
				(arc
					(start 96.900492 -130.56235)
					(mid 97.385632 -131.04749)
					(end 97.870772 -130.56235)
				)
			)
		)
		(polygon
			(pts
				(arc
					(start 66.32067 -129.419096)
					(mid 65.835403 -128.93421)
					(end 65.35039 -129.41935)
				)
				(arc
					(start 65.35039 -130.56235)
					(mid 65.83553 -131.04749)
					(end 66.32067 -130.56235)
				)
			)
		)
		(polygon
			(pts
				(arc
					(start 34.770822 -129.419096)
					(mid 34.285555 -128.93421)
					(end 33.800542 -129.41935)
				)
				(arc
					(start 33.800542 -130.56235)
					(mid 34.285682 -131.04749)
					(end 34.770822 -130.56235)
				)
			)
		)
		(polygon
			(pts
				(arc
					(start 478.107502 -129.112264)
					(mid 478.592642 -128.627124)
					(end 478.107502 -128.141984)
				)
				(arc
					(start 476.964248 -128.141984)
					(mid 476.479362 -128.627251)
					(end 476.964502 -129.112264)
				)
			)
		)
		(polygon
			(pts
				(arc
					(start 446.5574 -129.112264)
					(mid 447.04254 -128.627124)
					(end 446.5574 -128.141984)
				)
				(arc
					(start 445.414146 -128.141984)
					(mid 444.92926 -128.627251)
					(end 445.4144 -129.112264)
				)
			)
		)
		(polygon
			(pts
				(arc
					(start 415.007552 -129.112264)
					(mid 415.492692 -128.627124)
					(end 415.007552 -128.141984)
				)
				(arc
					(start 413.864298 -128.141984)
					(mid 413.379412 -128.627251)
					(end 413.864552 -129.112264)
				)
			)
		)
		(polygon
			(pts
				(arc
					(start 383.45745 -129.112264)
					(mid 383.94259 -128.627124)
					(end 383.45745 -128.141984)
				)
				(arc
					(start 382.314196 -128.141984)
					(mid 381.82931 -128.627251)
					(end 382.31445 -129.112264)
				)
			)
		)
		(polygon
			(pts
				(arc
					(start 351.907602 -129.112264)
					(mid 352.392742 -128.627124)
					(end 351.907602 -128.141984)
				)
				(arc
					(start 350.764348 -128.141984)
					(mid 350.279462 -128.627251)
					(end 350.764602 -129.112264)
				)
			)
		)
		(polygon
			(pts
				(arc
					(start 320.3575 -129.112264)
					(mid 320.84264 -128.627124)
					(end 320.3575 -128.141984)
				)
				(arc
					(start 319.214246 -128.141984)
					(mid 318.72936 -128.627251)
					(end 319.2145 -129.112264)
				)
			)
		)
		(polygon
			(pts
				(xy 234.241594 -75.6793) (xy 231.086406 -75.6793) (xy 230.3653 -76.400406) (xy 230.3653 -81.333594)
				(xy 231.9655 -82.933794) (xy 231.9655 -101.648006) (xy 229.156006 -104.4575) (xy 215.821006 -104.4575)
				(xy 213.9315 -106.347006) (xy 213.9315 -150.797006) (xy 213.027006 -151.7015) (xy 198.041006 -151.7015)
				(xy 196.292216 -153.45029) (xy 196.292216 -249.719084) (xy 198.477632 -251.9045) (xy 230.329994 -251.9045)
				(xy 233.027982 -249.206512) (xy 233.027982 -239.654588) (xy 239.14227 -233.5403) (xy 265.914124 -233.5403)
				(xy 267.8303 -231.624124) (xy 267.8303 -131.445) (xy 266.954 -130.5687) (xy 219.738194 -130.5687)
				(xy 219.1385 -129.969006) (xy 219.1385 -111.457994) (xy 219.788994 -110.8075) (xy 228.981 -110.8075)
				(xy 236.3851 -103.4034) (xy 236.3851 -77.822806)
			)
		)
		(polygon
			(pts
				(arc
					(start 190.744094 -18.114772)
					(mid 190.258827 -17.629886)
					(end 189.773814 -18.115026)
				)
				(arc
					(start 189.773814 -19.385026)
					(mid 190.258954 -19.870166)
					(end 190.744094 -19.385026)
				)
			)
		)
		(polygon
			(pts
				(arc
					(start 159.193992 -18.114772)
					(mid 158.708725 -17.629886)
					(end 158.223712 -18.115026)
				)
				(arc
					(start 158.223712 -19.385026)
					(mid 158.708852 -19.870166)
					(end 159.193992 -19.385026)
				)
			)
		)
		(polygon
			(pts
				(arc
					(start 127.64389 -18.114772)
					(mid 127.158623 -17.629886)
					(end 126.67361 -18.115026)
				)
				(arc
					(start 126.67361 -19.385026)
					(mid 127.15875 -19.870166)
					(end 127.64389 -19.385026)
				)
			)
		)
		(polygon
			(pts
				(arc
					(start 96.094042 -18.114772)
					(mid 95.608775 -17.629886)
					(end 95.123762 -18.115026)
				)
				(arc
					(start 95.123762 -19.385026)
					(mid 95.608902 -19.870166)
					(end 96.094042 -19.385026)
				)
			)
		)
		(polygon
			(pts
				(arc
					(start 64.54394 -18.114772)
					(mid 64.058673 -17.629886)
					(end 63.57366 -18.115026)
				)
				(arc
					(start 63.57366 -19.385026)
					(mid 64.0588 -19.870166)
					(end 64.54394 -19.385026)
				)
			)
		)
		(polygon
			(pts
				(arc
					(start 32.994092 -18.114772)
					(mid 32.508825 -17.629886)
					(end 32.023812 -18.115026)
				)
				(arc
					(start 32.023812 -19.385026)
					(mid 32.508952 -19.870166)
					(end 32.994092 -19.385026)
				)
			)
		)
		(polygon
			(pts
				(arc
					(start 481.701602 -17.92224)
					(mid 482.186742 -17.4371)
					(end 481.701602 -16.95196)
				)
				(arc
					(start 480.431348 -16.95196)
					(mid 479.946462 -17.437227)
					(end 480.431602 -17.92224)
				)
			)
		)
		(polygon
			(pts
				(arc
					(start 450.151754 -17.92224)
					(mid 450.63664 -17.436973)
					(end 450.1515 -16.95196)
				)
				(arc
					(start 448.8815 -16.95196)
					(mid 448.39636 -17.4371)
					(end 448.8815 -17.92224)
				)
			)
		)
		(polygon
			(pts
				(arc
					(start 418.601652 -17.92224)
					(mid 419.086792 -17.4371)
					(end 418.601652 -16.95196)
				)
				(arc
					(start 417.331398 -16.95196)
					(mid 416.846512 -17.437227)
					(end 417.331652 -17.92224)
				)
			)
		)
		(polygon
			(pts
				(arc
					(start 387.051804 -17.92224)
					(mid 387.53669 -17.436973)
					(end 387.05155 -16.95196)
				)
				(arc
					(start 385.78155 -16.95196)
					(mid 385.29641 -17.4371)
					(end 385.78155 -17.92224)
				)
			)
		)
		(polygon
			(pts
				(arc
					(start 355.501702 -17.92224)
					(mid 355.986842 -17.4371)
					(end 355.501702 -16.95196)
				)
				(arc
					(start 354.231448 -16.95196)
					(mid 353.746562 -17.437227)
					(end 354.231702 -17.92224)
				)
			)
		)
		(polygon
			(pts
				(arc
					(start 323.951854 -17.92224)
					(mid 324.43674 -17.436973)
					(end 323.9516 -16.95196)
				)
				(arc
					(start 322.6816 -16.95196)
					(mid 322.19646 -17.4371)
					(end 322.6816 -17.92224)
				)
			)
		)
		(polygon
			(pts
				(arc
					(start 192.520824 -14.419072)
					(mid 192.035557 -13.934186)
					(end 191.550544 -14.419326)
				)
				(arc
					(start 191.550544 -15.562326)
					(mid 192.035684 -16.047466)
					(end 192.520824 -15.562326)
				)
			)
		)
		(polygon
			(pts
				(arc
					(start 160.970722 -14.419072)
					(mid 160.485455 -13.934186)
					(end 160.000442 -14.419326)
				)
				(arc
					(start 160.000442 -15.562326)
					(mid 160.485582 -16.047466)
					(end 160.970722 -15.562326)
				)
			)
		)
		(polygon
			(pts
				(arc
					(start 129.42062 -14.419072)
					(mid 128.935353 -13.934186)
					(end 128.45034 -14.419326)
				)
				(arc
					(start 128.45034 -15.562326)
					(mid 128.93548 -16.047466)
					(end 129.42062 -15.562326)
				)
			)
		)
		(polygon
			(pts
				(arc
					(start 97.870772 -14.419072)
					(mid 97.385505 -13.934186)
					(end 96.900492 -14.419326)
				)
				(arc
					(start 96.900492 -15.562326)
					(mid 97.385632 -16.047466)
					(end 97.870772 -15.562326)
				)
			)
		)
		(polygon
			(pts
				(arc
					(start 66.32067 -14.419072)
					(mid 65.835403 -13.934186)
					(end 65.35039 -14.419326)
				)
				(arc
					(start 65.35039 -15.562326)
					(mid 65.83553 -16.047466)
					(end 66.32067 -15.562326)
				)
			)
		)
		(polygon
			(pts
				(arc
					(start 34.770822 -14.419072)
					(mid 34.285555 -13.934186)
					(end 33.800542 -14.419326)
				)
				(arc
					(start 33.800542 -15.562326)
					(mid 34.285682 -16.047466)
					(end 34.770822 -15.562326)
				)
			)
		)
		(polygon
			(pts
				(arc
					(start 478.107502 -14.11224)
					(mid 478.592642 -13.6271)
					(end 478.107502 -13.14196)
				)
				(arc
					(start 476.964248 -13.14196)
					(mid 476.479362 -13.627227)
					(end 476.964502 -14.11224)
				)
			)
		)
		(polygon
			(pts
				(arc
					(start 446.5574 -14.11224)
					(mid 447.04254 -13.6271)
					(end 446.5574 -13.14196)
				)
				(arc
					(start 445.414146 -13.14196)
					(mid 444.92926 -13.627227)
					(end 445.4144 -14.11224)
				)
			)
		)
		(polygon
			(pts
				(arc
					(start 415.007552 -14.11224)
					(mid 415.492692 -13.6271)
					(end 415.007552 -13.14196)
				)
				(arc
					(start 413.864298 -13.14196)
					(mid 413.379412 -13.627227)
					(end 413.864552 -14.11224)
				)
			)
		)
		(polygon
			(pts
				(arc
					(start 383.45745 -14.11224)
					(mid 383.94259 -13.6271)
					(end 383.45745 -13.14196)
				)
				(arc
					(start 382.314196 -13.14196)
					(mid 381.82931 -13.627227)
					(end 382.31445 -14.11224)
				)
			)
		)
		(polygon
			(pts
				(arc
					(start 351.907602 -14.11224)
					(mid 352.392742 -13.6271)
					(end 351.907602 -13.14196)
				)
				(arc
					(start 350.764348 -13.14196)
					(mid 350.279462 -13.627227)
					(end 350.764602 -14.11224)
				)
			)
		)
		(polygon
			(pts
				(arc
					(start 320.3575 -14.11224)
					(mid 320.84264 -13.6271)
					(end 320.3575 -13.14196)
				)
				(arc
					(start 319.214246 -13.14196)
					(mid 318.72936 -13.627227)
					(end 319.2145 -14.11224)
				)
			)
		)
	)
	(zone
		(net "P3V3_STBY_B")
		(layer "In3.Cu")
		(hatch none 0.5)
		(connect_pads
			(clearance 0.5)
		)
		(min_thickness 0.25)
		(fill yes
			(thermal_gap 0.5)
			(thermal_bridge_width 0.5)
			(island_removal_mode 0)
		)
		(polygon
			(pts
				(xy 231.244394 -76.0603) (xy 230.7463 -76.558394) (xy 230.7463 -81.175606) (xy 232.3465 -82.775806)
				(xy 232.3465 -101.805994) (xy 229.313994 -104.8385) (xy 215.978994 -104.8385) (xy 214.3125 -106.504994)
				(xy 214.3125 -150.954994) (xy 213.184994 -152.0825) (xy 198.198994 -152.0825) (xy 196.673216 -153.608278)
				(xy 196.673216 -249.561096) (xy 198.63562 -251.5235) (xy 230.172006 -251.5235) (xy 232.646982 -249.048524)
				(xy 232.646982 -239.4966) (xy 238.984282 -233.1593) (xy 265.756136 -233.1593) (xy 267.4493 -231.466136)
				(xy 267.4493 -131.602988) (xy 266.796012 -130.9497) (xy 219.580206 -130.9497) (xy 218.7575 -130.126994)
				(xy 218.7575 -111.300006) (xy 219.631006 -110.4265) (xy 228.823012 -110.4265) (xy 236.0041 -103.245412)
				(xy 236.0041 -77.980794) (xy 234.083606 -76.0603)
			)
		)
	)
	(zone
		(layer "In3.Cu")
		(hatch none 0.5)
		(connect_pads
			(clearance 0)
		)
		(min_thickness 0.25)
		(keepout
			(tracks not_allowed)
			(vias allowed)
			(pads allowed)
			(copperpour not_allowed)
			(footprints allowed)
		)
		(placement
			(enabled no)
			(sheetname "")
		)
		(fill
			(thermal_gap 0.5)
			(thermal_bridge_width 0.5)
			(island_removal_mode 0)
		)
		(polygon
			(pts
				(xy 160.6042 -358.2162) (xy 160.6042 -329.1078) (xy 166.386764 -329.1078) (xy 166.386764 -358.2162)
			)
		)
	)
	(zone
		(net "GND")
		(layers "In3.Cu" "In4.Cu")
		(hatch none 0.5)
		(connect_pads
			(clearance 0.5)
		)
		(min_thickness 0.25)
		(fill yes
			(thermal_gap 0.5)
			(thermal_bridge_width 0.5)
			(island_removal_mode 0)
		)
		(polygon
			(pts
				(xy 275.465794 -130.2893) (xy 274.9169 -130.838194) (xy 274.9169 -145.564606) (xy 275.999194 -146.6469)
				(xy 289.404806 -146.6469) (xy 290.1823 -145.869406) (xy 290.1823 -131.447794) (xy 289.023806 -130.2893)
			)
		)
		(polygon
			(pts
				(arc
					(start 287.83661 -145.243042)
					(mid 288.38525 -144.694402)
					(end 287.83661 -144.145762)
				)
				(arc
					(start 286.436562 -144.145762)
					(mid 285.887922 -144.694402)
					(end 286.436562 -145.243042)
				)
			)
		)
		(polygon
			(pts
				(arc
					(start 284.236668 -145.243042)
					(mid 284.785308 -144.694402)
					(end 284.236668 -144.145762)
				)
				(arc
					(start 282.83662 -144.145762)
					(mid 282.28798 -144.694402)
					(end 282.83662 -145.243042)
				)
			)
		)
		(polygon
			(pts
				(arc
					(start 280.636726 -145.243042)
					(mid 281.185366 -144.694402)
					(end 280.636726 -144.145762)
				)
				(arc
					(start 279.236678 -144.145762)
					(mid 278.688038 -144.694402)
					(end 279.236678 -145.243042)
				)
			)
		)
		(polygon
			(pts
				(arc
					(start 286.836612 -143.442944)
					(mid 287.385252 -142.894304)
					(end 286.836612 -142.345664)
				)
				(arc
					(start 285.436564 -142.345664)
					(mid 284.887924 -142.894304)
					(end 285.436564 -143.442944)
				)
			)
		)
		(polygon
			(pts
				(arc
					(start 279.636728 -143.442944)
					(mid 280.185368 -142.894304)
					(end 279.636728 -142.345664)
				)
				(arc
					(start 278.23668 -142.345664)
					(mid 277.68804 -142.894304)
					(end 278.23668 -143.442944)
				)
			)
		)
		(polygon
			(pts
				(arc
					(start 287.83661 -141.6431)
					(mid 288.38525 -141.09446)
					(end 287.83661 -140.54582)
				)
				(arc
					(start 286.436562 -140.54582)
					(mid 285.887922 -141.09446)
					(end 286.436562 -141.6431)
				)
			)
		)
		(polygon
			(pts
				(arc
					(start 280.636726 -141.6431)
					(mid 281.185366 -141.09446)
					(end 280.636726 -140.54582)
				)
				(arc
					(start 279.236678 -140.54582)
					(mid 278.688038 -141.09446)
					(end 279.236678 -141.6431)
				)
			)
		)
		(polygon
			(pts
				(arc
					(start 286.836612 -139.843002)
					(mid 287.385252 -139.294362)
					(end 286.836612 -138.745722)
				)
				(arc
					(start 285.436564 -138.745722)
					(mid 284.887924 -139.294362)
					(end 285.436564 -139.843002)
				)
			)
		)
		(polygon
			(pts
				(arc
					(start 279.636728 -139.843002)
					(mid 280.185368 -139.294362)
					(end 279.636728 -138.745722)
				)
				(arc
					(start 278.23668 -138.745722)
					(mid 277.68804 -139.294362)
					(end 278.23668 -139.843002)
				)
			)
		)
		(polygon
			(pts
				(arc
					(start 287.83661 -138.043158)
					(mid 288.38525 -137.494518)
					(end 287.83661 -136.945878)
				)
				(arc
					(start 286.436562 -136.945878)
					(mid 285.887922 -137.494518)
					(end 286.436562 -138.043158)
				)
			)
		)
		(polygon
			(pts
				(arc
					(start 280.636726 -138.045698)
					(mid 281.187906 -137.494518)
					(end 280.636726 -136.943338)
				)
				(arc
					(start 279.236678 -136.943338)
					(mid 278.685498 -137.494518)
					(end 279.236678 -138.045698)
				)
			)
		)
		(polygon
			(pts
				(arc
					(start 286.836612 -136.24306)
					(mid 287.385252 -135.69442)
					(end 286.836612 -135.14578)
				)
				(arc
					(start 285.436564 -135.14578)
					(mid 284.887924 -135.69442)
					(end 285.436564 -136.24306)
				)
			)
		)
		(polygon
			(pts
				(arc
					(start 279.636728 -136.24306)
					(mid 280.185368 -135.69442)
					(end 279.636728 -135.14578)
				)
				(arc
					(start 278.23668 -135.14578)
					(mid 277.68804 -135.69442)
					(end 278.23668 -136.24306)
				)
			)
		)
		(polygon
			(pts
				(arc
					(start 287.83661 -134.442962)
					(mid 288.38525 -133.894322)
					(end 287.83661 -133.345682)
				)
				(arc
					(start 286.436562 -133.345682)
					(mid 285.887922 -133.894322)
					(end 286.436562 -134.442962)
				)
			)
		)
		(polygon
			(pts
				(arc
					(start 280.636726 -134.442962)
					(mid 281.185366 -133.894322)
					(end 280.636726 -133.345682)
				)
				(arc
					(start 279.236678 -133.345682)
					(mid 278.688038 -133.894322)
					(end 279.236678 -134.442962)
				)
			)
		)
		(polygon
			(pts
				(arc
					(start 286.836612 -132.643118)
					(mid 287.385252 -132.094478)
					(end 286.836612 -131.545838)
				)
				(arc
					(start 285.436564 -131.545838)
					(mid 284.887924 -132.094478)
					(end 285.436564 -132.643118)
				)
			)
		)
		(polygon
			(pts
				(arc
					(start 279.636728 -132.643118)
					(mid 280.185368 -132.094478)
					(end 279.636728 -131.545838)
				)
				(arc
					(start 278.23668 -131.545838)
					(mid 277.68804 -132.094478)
					(end 278.23668 -132.643118)
				)
			)
		)
	)
	(zone
		(net "GND")
		(layers "In3.Cu" "In4.Cu")
		(hatch none 0.5)
		(connect_pads
			(clearance 0.5)
		)
		(min_thickness 0.25)
		(fill yes
			(thermal_gap 0.5)
			(thermal_bridge_width 0.5)
			(island_removal_mode 0)
		)
		(polygon
			(pts
				(xy 276.608794 -174.3583) (xy 275.4249 -175.542194) (xy 275.4249 -239.060736) (xy 276.508464 -240.1443)
				(xy 289.785806 -240.1443) (xy 290.7411 -239.189006) (xy 290.7411 -175.719994) (xy 289.379406 -174.3583)
			)
		)
		(polygon
			(pts
				(arc
					(start 287.83661 -239.243108)
					(mid 288.38525 -238.694468)
					(end 287.83661 -238.145828)
				)
				(arc
					(start 286.436562 -238.145828)
					(mid 285.887922 -238.694468)
					(end 286.436562 -239.243108)
				)
			)
		)
		(polygon
			(pts
				(arc
					(start 280.636726 -239.243108)
					(mid 281.185366 -238.694468)
					(end 280.636726 -238.145828)
				)
				(arc
					(start 279.236678 -238.145828)
					(mid 278.688038 -238.694468)
					(end 279.236678 -239.243108)
				)
			)
		)
		(polygon
			(pts
				(arc
					(start 286.836612 -237.44301)
					(mid 287.385252 -236.89437)
					(end 286.836612 -236.34573)
				)
				(arc
					(start 285.436564 -236.34573)
					(mid 284.887924 -236.89437)
					(end 285.436564 -237.44301)
				)
			)
		)
		(polygon
			(pts
				(arc
					(start 279.636728 -237.44301)
					(mid 280.185368 -236.89437)
					(end 279.636728 -236.34573)
				)
				(arc
					(start 278.23668 -236.34573)
					(mid 277.68804 -236.89437)
					(end 278.23668 -237.44301)
				)
			)
		)
		(polygon
			(pts
				(arc
					(start 287.83661 -235.643166)
					(mid 288.38525 -235.094526)
					(end 287.83661 -234.545886)
				)
				(arc
					(start 286.436562 -234.545886)
					(mid 285.887922 -235.094526)
					(end 286.436562 -235.643166)
				)
			)
		)
		(polygon
			(pts
				(arc
					(start 280.636726 -235.643166)
					(mid 281.185366 -235.094526)
					(end 280.636726 -234.545886)
				)
				(arc
					(start 279.236678 -234.545886)
					(mid 278.688038 -235.094526)
					(end 279.236678 -235.643166)
				)
			)
		)
		(polygon
			(pts
				(arc
					(start 286.836612 -233.843068)
					(mid 287.385252 -233.294428)
					(end 286.836612 -232.745788)
				)
				(arc
					(start 285.436564 -232.745788)
					(mid 284.887924 -233.294428)
					(end 285.436564 -233.843068)
				)
			)
		)
		(polygon
			(pts
				(arc
					(start 279.636728 -233.843068)
					(mid 280.185368 -233.294428)
					(end 279.636728 -232.745788)
				)
				(arc
					(start 278.23668 -232.745788)
					(mid 277.68804 -233.294428)
					(end 278.23668 -233.843068)
				)
			)
		)
		(polygon
			(pts
				(arc
					(start 287.83661 -232.043224)
					(mid 288.38525 -231.494584)
					(end 287.83661 -230.945944)
				)
				(arc
					(start 286.436562 -230.945944)
					(mid 285.887922 -231.494584)
					(end 286.436562 -232.043224)
				)
			)
		)
		(polygon
			(pts
				(arc
					(start 280.636726 -232.043224)
					(mid 281.185366 -231.494584)
					(end 280.636726 -230.945944)
				)
				(arc
					(start 279.236678 -230.945944)
					(mid 278.688038 -231.494584)
					(end 279.236678 -232.043224)
				)
			)
		)
		(polygon
			(pts
				(arc
					(start 286.836612 -230.243126)
					(mid 287.385252 -229.694486)
					(end 286.836612 -229.145846)
				)
				(arc
					(start 285.436564 -229.145846)
					(mid 284.887924 -229.694486)
					(end 285.436564 -230.243126)
				)
			)
		)
		(polygon
			(pts
				(arc
					(start 279.636728 -230.243126)
					(mid 280.185368 -229.694486)
					(end 279.636728 -229.145846)
				)
				(arc
					(start 278.23668 -229.145846)
					(mid 277.68804 -229.694486)
					(end 278.23668 -230.243126)
				)
			)
		)
		(polygon
			(pts
				(arc
					(start 287.83661 -228.443028)
					(mid 288.38525 -227.894388)
					(end 287.83661 -227.345748)
				)
				(arc
					(start 286.436562 -227.345748)
					(mid 285.887922 -227.894388)
					(end 286.436562 -228.443028)
				)
			)
		)
		(polygon
			(pts
				(arc
					(start 280.636726 -228.443028)
					(mid 281.185366 -227.894388)
					(end 280.636726 -227.345748)
				)
				(arc
					(start 279.236678 -227.345748)
					(mid 278.688038 -227.894388)
					(end 279.236678 -228.443028)
				)
			)
		)
		(polygon
			(pts
				(arc
					(start 286.836612 -226.643184)
					(mid 287.385252 -226.094544)
					(end 286.836612 -225.545904)
				)
				(arc
					(start 285.436564 -225.545904)
					(mid 284.887924 -226.094544)
					(end 285.436564 -226.643184)
				)
			)
		)
		(polygon
			(pts
				(arc
					(start 279.636728 -226.643184)
					(mid 280.185368 -226.094544)
					(end 279.636728 -225.545904)
				)
				(arc
					(start 278.23668 -225.545904)
					(mid 277.68804 -226.094544)
					(end 278.23668 -226.643184)
				)
			)
		)
		(polygon
			(pts
				(arc
					(start 280.636726 -224.843086)
					(mid 281.185366 -224.294446)
					(end 280.636726 -223.745806)
				)
				(arc
					(start 279.236678 -223.745806)
					(mid 278.688038 -224.294446)
					(end 279.236678 -224.843086)
				)
			)
		)
		(polygon
			(pts
				(arc
					(start 287.83661 -224.906586)
					(mid 288.44875 -224.294446)
					(end 287.83661 -223.682306)
				)
				(arc
					(start 286.436562 -223.682306)
					(mid 285.824422 -224.294446)
					(end 286.436562 -224.906586)
				)
			)
		)
		(polygon
			(pts
				(arc
					(start 286.836612 -223.042988)
					(mid 287.385252 -222.494348)
					(end 286.836612 -221.945708)
				)
				(arc
					(start 285.436564 -221.945708)
					(mid 284.887924 -222.494348)
					(end 285.436564 -223.042988)
				)
			)
		)
		(polygon
			(pts
				(arc
					(start 279.636728 -223.042988)
					(mid 280.185368 -222.494348)
					(end 279.636728 -221.945708)
				)
				(arc
					(start 278.23668 -221.945708)
					(mid 277.68804 -222.494348)
					(end 278.23668 -223.042988)
				)
			)
		)
		(polygon
			(pts
				(arc
					(start 287.83661 -221.243144)
					(mid 288.38525 -220.694504)
					(end 287.83661 -220.145864)
				)
				(arc
					(start 286.436562 -220.145864)
					(mid 285.887922 -220.694504)
					(end 286.436562 -221.243144)
				)
			)
		)
		(polygon
			(pts
				(arc
					(start 280.636726 -221.243144)
					(mid 281.185366 -220.694504)
					(end 280.636726 -220.145864)
				)
				(arc
					(start 279.236678 -220.145864)
					(mid 278.688038 -220.694504)
					(end 279.236678 -221.243144)
				)
			)
		)
		(polygon
			(pts
				(arc
					(start 286.836612 -219.443046)
					(mid 287.385252 -218.894406)
					(end 286.836612 -218.345766)
				)
				(arc
					(start 285.436564 -218.345766)
					(mid 284.887924 -218.894406)
					(end 285.436564 -219.443046)
				)
			)
		)
		(polygon
			(pts
				(arc
					(start 279.636728 -219.443046)
					(mid 280.185368 -218.894406)
					(end 279.636728 -218.345766)
				)
				(arc
					(start 278.23668 -218.345766)
					(mid 277.68804 -218.894406)
					(end 278.23668 -219.443046)
				)
			)
		)
		(polygon
			(pts
				(arc
					(start 287.83661 -217.643202)
					(mid 288.38525 -217.094562)
					(end 287.83661 -216.545922)
				)
				(arc
					(start 286.436562 -216.545922)
					(mid 285.887922 -217.094562)
					(end 286.436562 -217.643202)
				)
			)
		)
		(polygon
			(pts
				(arc
					(start 280.636726 -217.643202)
					(mid 281.185366 -217.094562)
					(end 280.636726 -216.545922)
				)
				(arc
					(start 279.236678 -216.545922)
					(mid 278.688038 -217.094562)
					(end 279.236678 -217.643202)
				)
			)
		)
		(polygon
			(pts
				(arc
					(start 286.836612 -215.843104)
					(mid 287.385252 -215.294464)
					(end 286.836612 -214.745824)
				)
				(arc
					(start 285.436564 -214.745824)
					(mid 284.887924 -215.294464)
					(end 285.436564 -215.843104)
				)
			)
		)
		(polygon
			(pts
				(arc
					(start 279.636728 -215.843104)
					(mid 280.185368 -215.294464)
					(end 279.636728 -214.745824)
				)
				(arc
					(start 278.23668 -214.745824)
					(mid 277.68804 -215.294464)
					(end 278.23668 -215.843104)
				)
			)
		)
		(polygon
			(pts
				(arc
					(start 287.83661 -214.043006)
					(mid 288.38525 -213.494366)
					(end 287.83661 -212.945726)
				)
				(arc
					(start 286.436562 -212.945726)
					(mid 285.887922 -213.494366)
					(end 286.436562 -214.043006)
				)
			)
		)
		(polygon
			(pts
				(arc
					(start 280.636726 -214.043006)
					(mid 281.185366 -213.494366)
					(end 280.636726 -212.945726)
				)
				(arc
					(start 279.236678 -212.945726)
					(mid 278.688038 -213.494366)
					(end 279.236678 -214.043006)
				)
			)
		)
		(polygon
			(pts
				(arc
					(start 286.836612 -212.243162)
					(mid 287.385252 -211.694522)
					(end 286.836612 -211.145882)
				)
				(arc
					(start 285.436564 -211.145882)
					(mid 284.887924 -211.694522)
					(end 285.436564 -212.243162)
				)
			)
		)
		(polygon
			(pts
				(arc
					(start 279.636728 -212.243162)
					(mid 280.185368 -211.694522)
					(end 279.636728 -211.145882)
				)
				(arc
					(start 278.23668 -211.145882)
					(mid 277.68804 -211.694522)
					(end 278.23668 -212.243162)
				)
			)
		)
		(polygon
			(pts
				(arc
					(start 287.83661 -210.443064)
					(mid 288.38525 -209.894424)
					(end 287.83661 -209.345784)
				)
				(arc
					(start 286.436562 -209.345784)
					(mid 285.887922 -209.894424)
					(end 286.436562 -210.443064)
				)
			)
		)
		(polygon
			(pts
				(arc
					(start 280.636726 -210.443064)
					(mid 281.185366 -209.894424)
					(end 280.636726 -209.345784)
				)
				(arc
					(start 279.236678 -209.345784)
					(mid 278.688038 -209.894424)
					(end 279.236678 -210.443064)
				)
			)
		)
		(polygon
			(pts
				(arc
					(start 286.836612 -208.64322)
					(mid 287.385252 -208.09458)
					(end 286.836612 -207.54594)
				)
				(arc
					(start 285.436564 -207.54594)
					(mid 284.887924 -208.09458)
					(end 285.436564 -208.64322)
				)
			)
		)
		(polygon
			(pts
				(arc
					(start 279.636728 -208.64322)
					(mid 280.185368 -208.09458)
					(end 279.636728 -207.54594)
				)
				(arc
					(start 278.23668 -207.54594)
					(mid 277.68804 -208.09458)
					(end 278.23668 -208.64322)
				)
			)
		)
		(polygon
			(pts
				(arc
					(start 287.83661 -206.843122)
					(mid 288.38525 -206.294482)
					(end 287.83661 -205.745842)
				)
				(arc
					(start 286.436562 -205.745842)
					(mid 285.887922 -206.294482)
					(end 286.436562 -206.843122)
				)
			)
		)
		(polygon
			(pts
				(arc
					(start 280.636726 -206.843122)
					(mid 281.185366 -206.294482)
					(end 280.636726 -205.745842)
				)
				(arc
					(start 279.236678 -205.745842)
					(mid 278.688038 -206.294482)
					(end 279.236678 -206.843122)
				)
			)
		)
		(polygon
			(pts
				(arc
					(start 286.836612 -205.043024)
					(mid 287.385252 -204.494384)
					(end 286.836612 -203.945744)
				)
				(arc
					(start 285.436564 -203.945744)
					(mid 284.887924 -204.494384)
					(end 285.436564 -205.043024)
				)
			)
		)
		(polygon
			(pts
				(arc
					(start 279.636728 -205.043024)
					(mid 280.185368 -204.494384)
					(end 279.636728 -203.945744)
				)
				(arc
					(start 278.23668 -203.945744)
					(mid 277.68804 -204.494384)
					(end 278.23668 -205.043024)
				)
			)
		)
		(polygon
			(pts
				(arc
					(start 287.83661 -203.24318)
					(mid 288.38525 -202.69454)
					(end 287.83661 -202.1459)
				)
				(arc
					(start 286.436562 -202.1459)
					(mid 285.887922 -202.69454)
					(end 286.436562 -203.24318)
				)
			)
		)
		(polygon
			(pts
				(arc
					(start 280.636726 -203.24318)
					(mid 281.185366 -202.69454)
					(end 280.636726 -202.1459)
				)
				(arc
					(start 279.236678 -202.1459)
					(mid 278.688038 -202.69454)
					(end 279.236678 -203.24318)
				)
			)
		)
		(polygon
			(pts
				(arc
					(start 286.836612 -201.443082)
					(mid 287.385252 -200.894442)
					(end 286.836612 -200.345802)
				)
				(arc
					(start 285.436564 -200.345802)
					(mid 284.887924 -200.894442)
					(end 285.436564 -201.443082)
				)
			)
		)
		(polygon
			(pts
				(arc
					(start 279.636728 -201.443082)
					(mid 280.185368 -200.894442)
					(end 279.636728 -200.345802)
				)
				(arc
					(start 278.23668 -200.345802)
					(mid 277.68804 -200.894442)
					(end 278.23668 -201.443082)
				)
			)
		)
		(polygon
			(pts
				(arc
					(start 287.83661 -199.642984)
					(mid 288.38525 -199.094344)
					(end 287.83661 -198.545704)
				)
				(arc
					(start 286.436562 -198.545704)
					(mid 285.887922 -199.094344)
					(end 286.436562 -199.642984)
				)
			)
		)
		(polygon
			(pts
				(arc
					(start 280.636726 -199.642984)
					(mid 281.185366 -199.094344)
					(end 280.636726 -198.545704)
				)
				(arc
					(start 279.236678 -198.545704)
					(mid 278.688038 -199.094344)
					(end 279.236678 -199.642984)
				)
			)
		)
		(polygon
			(pts
				(arc
					(start 286.836612 -197.84314)
					(mid 287.385252 -197.2945)
					(end 286.836612 -196.74586)
				)
				(arc
					(start 285.436564 -196.74586)
					(mid 284.887924 -197.2945)
					(end 285.436564 -197.84314)
				)
			)
		)
		(polygon
			(pts
				(arc
					(start 279.636728 -197.84314)
					(mid 280.185368 -197.2945)
					(end 279.636728 -196.74586)
				)
				(arc
					(start 278.23668 -196.74586)
					(mid 277.68804 -197.2945)
					(end 278.23668 -197.84314)
				)
			)
		)
		(polygon
			(pts
				(arc
					(start 287.83661 -196.043042)
					(mid 288.38525 -195.494402)
					(end 287.83661 -194.945762)
				)
				(arc
					(start 286.436562 -194.945762)
					(mid 285.887922 -195.494402)
					(end 286.436562 -196.043042)
				)
			)
		)
		(polygon
			(pts
				(arc
					(start 280.636726 -196.043042)
					(mid 281.185366 -195.494402)
					(end 280.636726 -194.945762)
				)
				(arc
					(start 279.236678 -194.945762)
					(mid 278.688038 -195.494402)
					(end 279.236678 -196.043042)
				)
			)
		)
		(polygon
			(pts
				(arc
					(start 286.836612 -194.243198)
					(mid 287.385252 -193.694558)
					(end 286.836612 -193.145918)
				)
				(arc
					(start 285.436564 -193.145918)
					(mid 284.887924 -193.694558)
					(end 285.436564 -194.243198)
				)
			)
		)
		(polygon
			(pts
				(arc
					(start 279.636728 -194.243198)
					(mid 280.185368 -193.694558)
					(end 279.636728 -193.145918)
				)
				(arc
					(start 278.23668 -193.145918)
					(mid 277.68804 -193.694558)
					(end 278.23668 -194.243198)
				)
			)
		)
		(polygon
			(pts
				(arc
					(start 287.83661 -192.4431)
					(mid 288.38525 -191.89446)
					(end 287.83661 -191.34582)
				)
				(arc
					(start 286.436562 -191.34582)
					(mid 285.887922 -191.89446)
					(end 286.436562 -192.4431)
				)
			)
		)
		(polygon
			(pts
				(arc
					(start 280.636726 -192.4431)
					(mid 281.185366 -191.89446)
					(end 280.636726 -191.34582)
				)
				(arc
					(start 279.236678 -191.34582)
					(mid 278.688038 -191.89446)
					(end 279.236678 -192.4431)
				)
			)
		)
		(polygon
			(pts
				(arc
					(start 286.836612 -190.643002)
					(mid 287.385252 -190.094362)
					(end 286.836612 -189.545722)
				)
				(arc
					(start 285.436564 -189.545722)
					(mid 284.887924 -190.094362)
					(end 285.436564 -190.643002)
				)
			)
		)
		(polygon
			(pts
				(arc
					(start 279.636728 -190.643002)
					(mid 280.185368 -190.094362)
					(end 279.636728 -189.545722)
				)
				(arc
					(start 278.23668 -189.545722)
					(mid 277.68804 -190.094362)
					(end 278.23668 -190.643002)
				)
			)
		)
		(polygon
			(pts
				(arc
					(start 287.83661 -188.843158)
					(mid 288.38525 -188.294518)
					(end 287.83661 -187.745878)
				)
				(arc
					(start 286.436562 -187.745878)
					(mid 285.887922 -188.294518)
					(end 286.436562 -188.843158)
				)
			)
		)
		(polygon
			(pts
				(arc
					(start 280.636726 -188.843158)
					(mid 281.185366 -188.294518)
					(end 280.636726 -187.745878)
				)
				(arc
					(start 279.236678 -187.745878)
					(mid 278.688038 -188.294518)
					(end 279.236678 -188.843158)
				)
			)
		)
		(polygon
			(pts
				(arc
					(start 286.836612 -187.04306)
					(mid 287.385252 -186.49442)
					(end 286.836612 -185.94578)
				)
				(arc
					(start 285.436564 -185.94578)
					(mid 284.887924 -186.49442)
					(end 285.436564 -187.04306)
				)
			)
		)
		(polygon
			(pts
				(arc
					(start 279.636728 -187.04306)
					(mid 280.185368 -186.49442)
					(end 279.636728 -185.94578)
				)
				(arc
					(start 278.23668 -185.94578)
					(mid 277.68804 -186.49442)
					(end 278.23668 -187.04306)
				)
			)
		)
		(polygon
			(pts
				(arc
					(start 287.83661 -185.243216)
					(mid 288.38525 -184.694576)
					(end 287.83661 -184.145936)
				)
				(arc
					(start 286.436562 -184.145936)
					(mid 285.887922 -184.694576)
					(end 286.436562 -185.243216)
				)
			)
		)
		(polygon
			(pts
				(arc
					(start 280.636726 -185.243216)
					(mid 281.185366 -184.694576)
					(end 280.636726 -184.145936)
				)
				(arc
					(start 279.236678 -184.145936)
					(mid 278.688038 -184.694576)
					(end 279.236678 -185.243216)
				)
			)
		)
		(polygon
			(pts
				(arc
					(start 286.836612 -183.443118)
					(mid 287.385252 -182.894478)
					(end 286.836612 -182.345838)
				)
				(arc
					(start 285.436564 -182.345838)
					(mid 284.887924 -182.894478)
					(end 285.436564 -183.443118)
				)
			)
		)
		(polygon
			(pts
				(arc
					(start 279.636728 -183.443118)
					(mid 280.185368 -182.894478)
					(end 279.636728 -182.345838)
				)
				(arc
					(start 278.23668 -182.345838)
					(mid 277.68804 -182.894478)
					(end 278.23668 -183.443118)
				)
			)
		)
		(polygon
			(pts
				(arc
					(start 287.83661 -181.64302)
					(mid 288.38525 -181.09438)
					(end 287.83661 -180.54574)
				)
				(arc
					(start 286.436562 -180.54574)
					(mid 285.887922 -181.09438)
					(end 286.436562 -181.64302)
				)
			)
		)
		(polygon
			(pts
				(arc
					(start 280.636726 -181.64302)
					(mid 281.185366 -181.09438)
					(end 280.636726 -180.54574)
				)
				(arc
					(start 279.236678 -180.54574)
					(mid 278.688038 -181.09438)
					(end 279.236678 -181.64302)
				)
			)
		)
		(polygon
			(pts
				(arc
					(start 286.836612 -179.843176)
					(mid 287.385252 -179.294536)
					(end 286.836612 -178.745896)
				)
				(arc
					(start 285.436564 -178.745896)
					(mid 284.887924 -179.294536)
					(end 285.436564 -179.843176)
				)
			)
		)
		(polygon
			(pts
				(arc
					(start 279.636728 -179.843176)
					(mid 280.185368 -179.294536)
					(end 279.636728 -178.745896)
				)
				(arc
					(start 278.23668 -178.745896)
					(mid 277.68804 -179.294536)
					(end 278.23668 -179.843176)
				)
			)
		)
		(polygon
			(pts
				(arc
					(start 287.83661 -178.043078)
					(mid 288.38525 -177.494438)
					(end 287.83661 -176.945798)
				)
				(arc
					(start 286.436562 -176.945798)
					(mid 285.887922 -177.494438)
					(end 286.436562 -178.043078)
				)
			)
		)
		(polygon
			(pts
				(arc
					(start 280.636726 -178.043078)
					(mid 281.185366 -177.494438)
					(end 280.636726 -176.945798)
				)
				(arc
					(start 279.236678 -176.945798)
					(mid 278.688038 -177.494438)
					(end 279.236678 -178.043078)
				)
			)
		)
		(polygon
			(pts
				(arc
					(start 286.836612 -176.243234)
					(mid 287.385252 -175.694594)
					(end 286.836612 -175.145954)
				)
				(arc
					(start 285.436564 -175.145954)
					(mid 284.887924 -175.694594)
					(end 285.436564 -176.243234)
				)
			)
		)
		(polygon
			(pts
				(arc
					(start 279.636728 -176.243234)
					(mid 280.185368 -175.694594)
					(end 279.636728 -175.145954)
				)
				(arc
					(start 278.23668 -175.145954)
					(mid 277.68804 -175.694594)
					(end 278.23668 -176.243234)
				)
			)
		)
	)
	(zone
		(net "P12V_IN")
		(layer "In4.Cu")
		(hatch none 0.5)
		(connect_pads
			(clearance 0.5)
		)
		(min_thickness 0.25)
		(fill yes
			(thermal_gap 0.5)
			(thermal_bridge_width 0.5)
			(island_removal_mode 0)
		)
		(polygon
			(pts
				(arc
					(start 269.461488 -63.736728)
					(mid 268.777826 -64.132393)
					(end 267.999972 -64.269874)
				)
				(xy 252.6411 -64.269874) (xy 252.6411 -81.206594) (xy 240.214404 -93.63329) (xy 211.015834 -93.63329)
				(xy 199.164702 -105.484422) (xy 199.164702 -119.634254) (xy 194.00139 -124.797566) (xy 194.00139 -310.799226)
				(xy 204.8256 -321.623436) (xy 204.8256 -363.68355) (xy 205.51775 -364.3757) (xy 227.809806 -364.3757)
				(xy 245.4275 -346.758006) (xy 245.4275 -326.565006) (xy 247.444006 -324.5485) (xy 322.496434 -324.5485)
				(xy 328.653394 -318.39154) (xy 328.653394 -240.230914) (xy 327.751948 -239.329468) (xy 327.751948 -125.126496)
				(xy 314.1599 -111.534448) (xy 314.1599 -73.576434) (xy 306.30368 -65.720214) (xy 271.44472 -65.720214)
			)
		)
		(polygon
			(pts
				(arc
					(start 324.07479 -248.11482)
					(mid 323.589523 -247.629934)
					(end 323.10451 -248.115074)
				)
				(arc
					(start 323.10451 -249.385074)
					(mid 323.58965 -249.870214)
					(end 324.07479 -249.385074)
				)
			)
		)
		(polygon
			(pts
				(arc
					(start 319.8876 -244.312694)
					(mid 319.40246 -243.827554)
					(end 318.91732 -244.312694)
				)
				(arc
					(start 318.91732 -245.455948)
					(mid 319.402587 -245.940834)
					(end 319.8876 -245.455694)
				)
			)
		)
		(polygon
			(pts
				(xy 289.537394 -173.9773) (xy 276.450806 -173.9773) (xy 275.0439 -175.384206) (xy 275.0439 -239.218724)
				(xy 276.350476 -240.5253) (xy 289.943794 -240.5253) (xy 291.1221 -239.346994) (xy 291.1221 -175.562006)
			)
		)
		(polygon
			(pts
				(arc
					(start 323.951854 -132.922264)
					(mid 324.43674 -132.436997)
					(end 323.9516 -131.951984)
				)
				(arc
					(start 322.6816 -131.951984)
					(mid 322.19646 -132.437124)
					(end 322.6816 -132.922264)
				)
			)
		)
		(polygon
			(pts
				(xy 289.181794 -129.9083) (xy 275.307806 -129.9083) (xy 274.5359 -130.680206) (xy 274.5359 -145.722594)
				(xy 275.841206 -147.0279) (xy 289.562794 -147.0279) (xy 290.5633 -146.027394) (xy 290.5633 -131.289806)
			)
		)
		(polygon
			(pts
				(arc
					(start 320.3575 -129.112264)
					(mid 320.84264 -128.627124)
					(end 320.3575 -128.141984)
				)
				(arc
					(start 319.214246 -128.141984)
					(mid 318.72936 -128.627251)
					(end 319.2145 -129.112264)
				)
			)
		)
	)
	(zone
		(net "P5V_B_1")
		(layer "In4.Cu")
		(hatch none 0.5)
		(connect_pads
			(clearance 0.5)
		)
		(min_thickness 0.25)
		(fill yes
			(thermal_gap 0.5)
			(thermal_bridge_width 0.5)
			(island_removal_mode 0)
		)
		(polygon
			(pts
				(xy 31.320994 -131.5085) (xy 28.018994 -134.8105) (xy 19.128994 -134.8105) (xy 17.8435 -136.095994)
				(xy 17.8435 -144.477994) (xy 15.9385 -146.382994) (xy 15.9385 -229.029006) (xy 17.7165 -230.807006)
				(xy 17.7165 -252.397006) (xy 19.509994 -254.1905) (xy 181.150006 -254.1905) (xy 182.6895 -252.651006)
				(xy 182.6895 -217.731594) (xy 178.559206 -213.6013) (xy 92.123006 -213.6013) (xy 88.5825 -210.060794)
				(xy 88.5825 -135.460994) (xy 87.551006 -134.4295) (xy 83.390994 -134.4295) (xy 80.063594 -137.7569)
				(xy 78.178406 -137.7569) (xy 73.200006 -132.7785) (xy 65.326006 -132.7785) (xy 64.7065 -132.158994)
				(xy 64.7065 -131.650994) (xy 64.564006 -131.5085) (xy 62.816994 -131.5085) (xy 60.403994 -133.9215)
				(xy 51.894994 -133.9215) (xy 49.456594 -136.3599) (xy 41.221406 -136.3599) (xy 37.767006 -132.9055)
				(xy 33.703006 -132.9055) (xy 33.2105 -132.412994) (xy 33.2105 -131.650994) (xy 33.068006 -131.5085)
			)
		)
		(polygon
			(pts
				(arc
					(start 159.193992 -248.115074)
					(mid 158.708852 -247.629934)
					(end 158.223712 -248.115074)
				)
				(arc
					(start 158.223712 -249.385328)
					(mid 158.708979 -249.870214)
					(end 159.193992 -249.385074)
				)
			)
		)
		(polygon
			(pts
				(arc
					(start 127.64389 -248.11482)
					(mid 127.158623 -247.629934)
					(end 126.67361 -248.115074)
				)
				(arc
					(start 126.67361 -249.385074)
					(mid 127.15875 -249.870214)
					(end 127.64389 -249.385074)
				)
			)
		)
		(polygon
			(pts
				(arc
					(start 96.094042 -248.11482)
					(mid 95.608775 -247.629934)
					(end 95.123762 -248.115074)
				)
				(arc
					(start 95.123762 -249.385074)
					(mid 95.608902 -249.870214)
					(end 96.094042 -249.385074)
				)
			)
		)
		(polygon
			(pts
				(arc
					(start 64.54394 -248.11482)
					(mid 64.058673 -247.629934)
					(end 63.57366 -248.115074)
				)
				(arc
					(start 63.57366 -249.385074)
					(mid 64.0588 -249.870214)
					(end 64.54394 -249.385074)
				)
			)
		)
		(polygon
			(pts
				(arc
					(start 32.994092 -248.11482)
					(mid 32.508825 -247.629934)
					(end 32.023812 -248.115074)
				)
				(arc
					(start 32.023812 -249.385074)
					(mid 32.508952 -249.870214)
					(end 32.994092 -249.385074)
				)
			)
		)
		(polygon
			(pts
				(arc
					(start 160.970722 -244.419374)
					(mid 160.485582 -243.934234)
					(end 160.000442 -244.419374)
				)
				(arc
					(start 160.000442 -245.562628)
					(mid 160.485709 -246.047514)
					(end 160.970722 -245.562374)
				)
			)
		)
		(polygon
			(pts
				(arc
					(start 129.42062 -244.419374)
					(mid 128.93548 -243.934234)
					(end 128.45034 -244.419374)
				)
				(arc
					(start 128.45034 -245.562628)
					(mid 128.935607 -246.047514)
					(end 129.42062 -245.562374)
				)
			)
		)
		(polygon
			(pts
				(arc
					(start 97.870772 -244.419374)
					(mid 97.385632 -243.934234)
					(end 96.900492 -244.419374)
				)
				(arc
					(start 96.900492 -245.562628)
					(mid 97.385759 -246.047514)
					(end 97.870772 -245.562374)
				)
			)
		)
		(polygon
			(pts
				(arc
					(start 66.32067 -244.419374)
					(mid 65.83553 -243.934234)
					(end 65.35039 -244.419374)
				)
				(arc
					(start 65.35039 -245.562628)
					(mid 65.835657 -246.047514)
					(end 66.32067 -245.562374)
				)
			)
		)
		(polygon
			(pts
				(arc
					(start 34.770822 -244.419374)
					(mid 34.285682 -243.934234)
					(end 33.800542 -244.419374)
				)
				(arc
					(start 33.800542 -245.562628)
					(mid 34.285809 -246.047514)
					(end 34.770822 -245.562374)
				)
			)
		)
		(polygon
			(pts
				(arc
					(start 64.54394 -133.11505)
					(mid 64.0588 -132.62991)
					(end 63.57366 -133.11505)
				)
				(arc
					(start 63.57366 -134.385304)
					(mid 64.058927 -134.87019)
					(end 64.54394 -134.38505)
				)
			)
		)
		(polygon
			(pts
				(arc
					(start 32.994092 -133.11505)
					(mid 32.508952 -132.62991)
					(end 32.023812 -133.11505)
				)
				(arc
					(start 32.023812 -134.385304)
					(mid 32.509079 -134.87019)
					(end 32.994092 -134.38505)
				)
			)
		)
	)
	(zone
		(net "P5V_B_3")
		(layer "In4.Cu")
		(hatch none 0.5)
		(connect_pads
			(clearance 0.5)
		)
		(min_thickness 0.25)
		(fill yes
			(thermal_gap 0.5)
			(thermal_bridge_width 0.5)
			(island_removal_mode 0)
		)
		(polygon
			(pts
				(xy 384.126994 -131.3815) (xy 380.443994 -135.0645) (xy 369.471194 -135.0645) (xy 367.134394 -137.4013)
				(xy 360.651806 -137.4013) (xy 358.3305 -135.079994) (xy 358.3305 -132.285994) (xy 357.553006 -131.5085)
				(xy 351.868994 -131.5085) (xy 348.312994 -135.0645) (xy 339.676994 -135.0645) (xy 338.2645 -136.476994)
				(xy 338.2645 -256.334006) (xy 339.168994 -257.2385) (xy 483.359206 -257.2385) (xy 486.3973 -254.200406)
				(xy 486.3973 -217.782394) (xy 459.483206 -190.8683) (xy 454.174606 -190.8683) (xy 450.1007 -186.794394)
				(xy 450.1007 -181.485794) (xy 414.0835 -145.468594) (xy 414.0835 -142.669006) (xy 418.2745 -138.478006)
				(xy 418.2745 -136.065006) (xy 420.6875 -133.652006) (xy 420.6875 -131.777994) (xy 420.291006 -131.3815)
				(xy 408.764994 -131.3815) (xy 405.081994 -135.0645) (xy 392.732006 -135.0645) (xy 389.049006 -131.3815)
			)
		)
		(polygon
			(pts
				(arc
					(start 481.824792 -248.11482)
					(mid 481.339525 -247.629934)
					(end 480.854512 -248.115074)
				)
				(arc
					(start 480.854512 -249.385074)
					(mid 481.339652 -249.870214)
					(end 481.824792 -249.385074)
				)
			)
		)
		(polygon
			(pts
				(arc
					(start 450.27469 -248.11482)
					(mid 449.789423 -247.629934)
					(end 449.30441 -248.115074)
				)
				(arc
					(start 449.30441 -249.385074)
					(mid 449.78955 -249.870214)
					(end 450.27469 -249.385074)
				)
			)
		)
		(polygon
			(pts
				(arc
					(start 418.724842 -248.11482)
					(mid 418.239575 -247.629934)
					(end 417.754562 -248.115074)
				)
				(arc
					(start 417.754562 -249.385074)
					(mid 418.239702 -249.870214)
					(end 418.724842 -249.385074)
				)
			)
		)
		(polygon
			(pts
				(arc
					(start 387.17474 -248.11482)
					(mid 386.689473 -247.629934)
					(end 386.20446 -248.115074)
				)
				(arc
					(start 386.20446 -249.385074)
					(mid 386.6896 -249.870214)
					(end 387.17474 -249.385074)
				)
			)
		)
		(polygon
			(pts
				(arc
					(start 355.624892 -248.11482)
					(mid 355.139625 -247.629934)
					(end 354.654612 -248.115074)
				)
				(arc
					(start 354.654612 -249.385074)
					(mid 355.139752 -249.870214)
					(end 355.624892 -249.385074)
				)
			)
		)
		(polygon
			(pts
				(arc
					(start 414.527492 -244.444774)
					(mid 414.042352 -243.959634)
					(end 413.557212 -244.444774)
				)
				(arc
					(start 413.557212 -245.588028)
					(mid 414.042479 -246.072914)
					(end 414.527492 -245.587774)
				)
			)
		)
		(polygon
			(pts
				(arc
					(start 351.427542 -244.317774)
					(mid 350.942402 -243.832634)
					(end 350.457262 -244.317774)
				)
				(arc
					(start 350.457262 -245.461028)
					(mid 350.942529 -245.945914)
					(end 351.427542 -245.460774)
				)
			)
		)
		(polygon
			(pts
				(arc
					(start 477.637602 -244.312694)
					(mid 477.152462 -243.827554)
					(end 476.667322 -244.312694)
				)
				(arc
					(start 476.667322 -245.455948)
					(mid 477.152589 -245.940834)
					(end 477.637602 -245.455694)
				)
			)
		)
		(polygon
			(pts
				(arc
					(start 446.0875 -244.312694)
					(mid 445.60236 -243.827554)
					(end 445.11722 -244.312694)
				)
				(arc
					(start 445.11722 -245.455948)
					(mid 445.602487 -245.940834)
					(end 446.0875 -245.455694)
				)
			)
		)
		(polygon
			(pts
				(arc
					(start 382.97739 -244.302534)
					(mid 382.49225 -243.817394)
					(end 382.00711 -244.302534)
				)
				(arc
					(start 382.00711 -245.445788)
					(mid 382.492377 -245.930674)
					(end 382.97739 -245.445534)
				)
			)
		)
		(polygon
			(pts
				(arc
					(start 418.601652 -132.922264)
					(mid 419.086792 -132.437124)
					(end 418.601652 -131.951984)
				)
				(arc
					(start 417.331398 -131.951984)
					(mid 416.846512 -132.437251)
					(end 417.331652 -132.922264)
				)
			)
		)
		(polygon
			(pts
				(arc
					(start 387.051804 -132.922264)
					(mid 387.53669 -132.436997)
					(end 387.05155 -131.951984)
				)
				(arc
					(start 385.78155 -131.951984)
					(mid 385.29641 -132.437124)
					(end 385.78155 -132.922264)
				)
			)
		)
		(polygon
			(pts
				(arc
					(start 355.501702 -132.922264)
					(mid 355.986842 -132.437124)
					(end 355.501702 -131.951984)
				)
				(arc
					(start 354.231448 -131.951984)
					(mid 353.746562 -132.437251)
					(end 354.231702 -132.922264)
				)
			)
		)
	)
	(zone
		(layer "In4.Cu")
		(hatch none 0.5)
		(connect_pads
			(clearance 0)
		)
		(min_thickness 0.25)
		(keepout
			(tracks not_allowed)
			(vias allowed)
			(pads allowed)
			(copperpour not_allowed)
			(footprints allowed)
		)
		(placement
			(enabled no)
			(sheetname "")
		)
		(fill
			(thermal_gap 0.5)
			(thermal_bridge_width 0.5)
			(island_removal_mode 0)
		)
		(polygon
			(pts
				(arc
					(start 352.212148 -367.09985)
					(mid 349.387668 -367.09985)
					(end 352.212148 -367.09985)
				)
			)
		)
	)
	(zone
		(layer "In4.Cu")
		(hatch none 0.5)
		(connect_pads
			(clearance 0)
		)
		(min_thickness 0.25)
		(keepout
			(tracks not_allowed)
			(vias allowed)
			(pads allowed)
			(copperpour not_allowed)
			(footprints allowed)
		)
		(placement
			(enabled no)
			(sheetname "")
		)
		(fill
			(thermal_gap 0.5)
			(thermal_bridge_width 0.5)
			(island_removal_mode 0)
		)
		(polygon
			(pts
				(arc
					(start 60.812172 -372.599966)
					(mid 57.987692 -372.599966)
					(end 60.812172 -372.599966)
				)
			)
		)
	)
	(zone
		(net "P5V_B_2")
		(layer "In4.Cu")
		(hatch none 0.5)
		(connect_pads
			(clearance 0.5)
		)
		(min_thickness 0.25)
		(fill yes
			(thermal_gap 0.5)
			(thermal_bridge_width 0.5)
			(island_removal_mode 0)
		)
		(polygon
			(pts
				(xy 63.578994 -16.3195) (xy 63.0555 -16.842994) (xy 63.0555 -20.398994) (xy 61.673994 -21.7805)
				(xy 41.069006 -21.7805) (xy 37.132006 -17.8435) (xy 33.703006 -17.8435) (xy 33.2105 -17.350994)
				(xy 33.2105 -16.715994) (xy 33.068006 -16.5735) (xy 31.320994 -16.5735) (xy 28.780994 -19.1135)
				(xy 20.652994 -19.1135) (xy 17.7165 -22.049994) (xy 17.7165 -100.860606) (xy 25.631394 -108.7755)
				(xy 52.326794 -108.7755) (xy 59.591194 -116.0399) (xy 62.58433 -116.0399) (xy 63.498984 -116.954554)
				(xy 68.16471 -116.954554) (xy 69.079364 -116.0399) (xy 108.562394 -116.0399) (xy 112.3315 -119.809006)
				(xy 112.3315 -137.589006) (xy 113.997994 -139.2555) (xy 124.000006 -139.2555) (xy 125.5395 -137.716006)
				(xy 125.5395 -131.620006) (xy 126.286006 -130.8735) (xy 127.586994 -130.8735) (xy 128.2065 -131.493006)
				(xy 128.2065 -132.128006) (xy 128.602994 -132.5245) (xy 134.571994 -132.5245) (xy 141.302994 -139.2555)
				(xy 155.750006 -139.2555) (xy 157.1625 -137.843006) (xy 157.1625 -131.620006) (xy 158.036006 -130.7465)
				(xy 159.209994 -130.7465) (xy 159.8295 -131.366006) (xy 159.8295 -132.382006) (xy 159.844994 -132.3975)
				(xy 168.480994 -132.3975) (xy 175.338994 -139.2555) (xy 180.896006 -139.2555) (xy 182.9435 -137.208006)
				(xy 182.9435 -91.665806) (xy 187.068206 -87.5411) (xy 192.458594 -87.5411) (xy 193.474594 -88.5571)
				(xy 229.689406 -88.5571) (xy 233.7943 -84.452206) (xy 233.7943 -78.437994) (xy 232.610406 -77.2541)
				(xy 225.224594 -77.2541) (xy 224.3201 -78.158594) (xy 224.3201 -80.317594) (xy 223.294194 -81.3435)
				(xy 185.925206 -81.3435) (xy 182.9435 -78.361794) (xy 182.9435 -23.065994) (xy 181.658006 -21.7805)
				(xy 165.402006 -21.7805) (xy 161.592006 -17.9705) (xy 160.195006 -17.9705) (xy 159.4485 -17.223994)
				(xy 159.4485 -16.588994) (xy 159.306006 -16.4465) (xy 158.066994 -16.4465) (xy 155.399994 -19.1135)
				(xy 146.636994 -19.1135) (xy 144.300194 -21.4503) (xy 134.718806 -21.4503) (xy 131.239006 -17.9705)
				(xy 128.318006 -17.9705) (xy 127.8255 -17.477994) (xy 127.8255 -16.588994) (xy 127.683006 -16.4465)
				(xy 126.062994 -16.4465) (xy 123.395994 -19.1135) (xy 113.997994 -19.1135) (xy 111.686594 -21.4249)
				(xy 101.419406 -21.4249) (xy 97.838006 -17.8435) (xy 96.949006 -17.8435) (xy 96.3295 -17.223994)
				(xy 96.3295 -16.588994) (xy 96.060006 -16.3195) (xy 94.439994 -16.3195) (xy 91.645994 -19.1135)
				(xy 83.644994 -19.1135) (xy 80.977994 -21.7805) (xy 74.343006 -21.7805) (xy 70.533006 -17.9705)
				(xy 65.199006 -17.9705) (xy 64.7065 -17.477994) (xy 64.7065 -16.588994) (xy 64.437006 -16.3195)
			)
		)
		(polygon
			(pts
				(arc
					(start 160.970722 -129.419096)
					(mid 160.485455 -128.93421)
					(end 160.000442 -129.41935)
				)
				(arc
					(start 160.000442 -130.56235)
					(mid 160.485582 -131.04749)
					(end 160.970722 -130.56235)
				)
			)
		)
		(polygon
			(pts
				(arc
					(start 129.42062 -129.419096)
					(mid 128.935353 -128.93421)
					(end 128.45034 -129.41935)
				)
				(arc
					(start 128.45034 -130.56235)
					(mid 128.93548 -131.04749)
					(end 129.42062 -130.56235)
				)
			)
		)
		(polygon
			(pts
				(arc
					(start 159.193992 -18.114772)
					(mid 158.708725 -17.629886)
					(end 158.223712 -18.115026)
				)
				(arc
					(start 158.223712 -19.385026)
					(mid 158.708852 -19.870166)
					(end 159.193992 -19.385026)
				)
			)
		)
		(polygon
			(pts
				(arc
					(start 127.64389 -18.114772)
					(mid 127.158623 -17.629886)
					(end 126.67361 -18.115026)
				)
				(arc
					(start 126.67361 -19.385026)
					(mid 127.15875 -19.870166)
					(end 127.64389 -19.385026)
				)
			)
		)
		(polygon
			(pts
				(arc
					(start 96.094042 -18.114772)
					(mid 95.608775 -17.629886)
					(end 95.123762 -18.115026)
				)
				(arc
					(start 95.123762 -19.385026)
					(mid 95.608902 -19.870166)
					(end 96.094042 -19.385026)
				)
			)
		)
		(polygon
			(pts
				(arc
					(start 64.54394 -18.114772)
					(mid 64.058673 -17.629886)
					(end 63.57366 -18.115026)
				)
				(arc
					(start 63.57366 -19.385026)
					(mid 64.0588 -19.870166)
					(end 64.54394 -19.385026)
				)
			)
		)
		(polygon
			(pts
				(arc
					(start 32.994092 -18.114772)
					(mid 32.508825 -17.629886)
					(end 32.023812 -18.115026)
				)
				(arc
					(start 32.023812 -19.385026)
					(mid 32.508952 -19.870166)
					(end 32.994092 -19.385026)
				)
			)
		)
	)
	(zone
		(layer "In4.Cu")
		(hatch none 0.5)
		(connect_pads
			(clearance 0)
		)
		(min_thickness 0.25)
		(keepout
			(tracks not_allowed)
			(vias allowed)
			(pads allowed)
			(copperpour not_allowed)
			(footprints allowed)
		)
		(placement
			(enabled no)
			(sheetname "")
		)
		(fill
			(thermal_gap 0.5)
			(thermal_bridge_width 0.5)
			(island_removal_mode 0)
		)
		(polygon
			(pts
				(arc
					(start 448.812158 -372.599966)
					(mid 445.987678 -372.599966)
					(end 448.812158 -372.599966)
				)
			)
		)
	)
	(zone
		(layer "In4.Cu")
		(hatch none 0.5)
		(connect_pads
			(clearance 0)
		)
		(min_thickness 0.25)
		(keepout
			(tracks not_allowed)
			(vias allowed)
			(pads allowed)
			(copperpour not_allowed)
			(footprints allowed)
		)
		(placement
			(enabled no)
			(sheetname "")
		)
		(fill
			(thermal_gap 0.5)
			(thermal_bridge_width 0.5)
			(island_removal_mode 0)
		)
		(polygon
			(pts
				(arc
					(start 352.212148 -372.599966)
					(mid 349.387668 -372.599966)
					(end 352.212148 -372.599966)
				)
			)
		)
	)
	(zone
		(net "P5V_B_4")
		(layer "In4.Cu")
		(hatch none 0.5)
		(connect_pads
			(clearance 0.5)
		)
		(min_thickness 0.25)
		(fill yes
			(thermal_gap 0.5)
			(thermal_bridge_width 0.5)
			(island_removal_mode 0)
		)
		(polygon
			(pts
				(xy 393.966446 -10.810748) (xy 393.292838 -11.484356) (xy 349.490538 -11.484356) (xy 343.486994 -17.4879)
				(xy 330.888594 -17.4879) (xy 329.1205 -19.255994) (xy 329.1205 -38.529006) (xy 344.5383 -53.946806)
				(xy 344.5383 -94.846394) (xy 341.734394 -97.6503) (xy 314.952126 -97.6503) (xy 314.5409 -98.061526)
				(xy 314.5409 -109.29747) (xy 314.90793 -109.6645) (xy 415.114994 -109.6645) (xy 424.4975 -119.047006)
				(xy 424.4975 -138.605006) (xy 428.246794 -142.3543) (xy 435.861206 -142.3543) (xy 447.215006 -131.0005)
				(xy 452.325994 -131.0005) (xy 454.8505 -133.525006) (xy 454.8505 -140.383006) (xy 456.821794 -142.3543)
				(xy 470.913206 -142.3543) (xy 474.647006 -138.6205) (xy 477.314006 -138.6205) (xy 478.8535 -137.081006)
				(xy 478.8535 -134.063994) (xy 478.3455 -133.555994) (xy 478.3455 -131.620006) (xy 479.219006 -130.7465)
				(xy 484.299006 -130.7465) (xy 485.5845 -129.461006) (xy 485.5845 -119.560594) (xy 478.2185 -112.194594)
				(xy 478.2185 -101.698806) (xy 479.2345 -100.682806) (xy 479.2345 -24.559006) (xy 481.5205 -22.273006)
				(xy 481.5205 -19.733006) (xy 483.8065 -17.447006) (xy 483.8065 -16.715994) (xy 483.537006 -16.4465)
				(xy 479.122994 -16.4465) (xy 478.3455 -17.223994) (xy 478.3455 -19.509994) (xy 476.328994 -21.5265)
				(xy 471.756994 -21.5265) (xy 470.994994 -22.2885) (xy 464.614006 -22.2885) (xy 461.185006 -18.8595)
				(xy 454.454006 -18.8595) (xy 451.914006 -16.3195) (xy 444.294006 -16.3195) (xy 439.468006 -11.4935)
				(xy 398.8435 -11.4935) (xy 398.160748 -10.810748)
			)
		)
		(polygon
			(pts
				(arc
					(start 478.107502 -129.112264)
					(mid 478.592642 -128.627124)
					(end 478.107502 -128.141984)
				)
				(arc
					(start 476.964248 -128.141984)
					(mid 476.479362 -128.627251)
					(end 476.964502 -129.112264)
				)
			)
		)
		(polygon
			(pts
				(arc
					(start 446.5574 -129.112264)
					(mid 447.04254 -128.627124)
					(end 446.5574 -128.141984)
				)
				(arc
					(start 445.414146 -128.141984)
					(mid 444.92926 -128.627251)
					(end 445.4144 -129.112264)
				)
			)
		)
		(polygon
			(pts
				(arc
					(start 481.701602 -17.92224)
					(mid 482.186742 -17.4371)
					(end 481.701602 -16.95196)
				)
				(arc
					(start 480.431348 -16.95196)
					(mid 479.946462 -17.437227)
					(end 480.431602 -17.92224)
				)
			)
		)
		(polygon
			(pts
				(arc
					(start 450.151754 -17.92224)
					(mid 450.63664 -17.436973)
					(end 450.1515 -16.95196)
				)
				(arc
					(start 448.8815 -16.95196)
					(mid 448.39636 -17.4371)
					(end 448.8815 -17.92224)
				)
			)
		)
		(polygon
			(pts
				(arc
					(start 418.601652 -17.92224)
					(mid 419.086792 -17.4371)
					(end 418.601652 -16.95196)
				)
				(arc
					(start 417.331398 -16.95196)
					(mid 416.846512 -17.437227)
					(end 417.331652 -17.92224)
				)
			)
		)
		(polygon
			(pts
				(arc
					(start 387.051804 -17.92224)
					(mid 387.53669 -17.436973)
					(end 387.05155 -16.95196)
				)
				(arc
					(start 385.78155 -16.95196)
					(mid 385.29641 -17.4371)
					(end 385.78155 -17.92224)
				)
			)
		)
		(polygon
			(pts
				(arc
					(start 355.501702 -17.92224)
					(mid 355.986842 -17.4371)
					(end 355.501702 -16.95196)
				)
				(arc
					(start 354.231448 -16.95196)
					(mid 353.746562 -17.437227)
					(end 354.231702 -17.92224)
				)
			)
		)
		(polygon
			(pts
				(arc
					(start 415.007552 -14.11224)
					(mid 415.492692 -13.6271)
					(end 415.007552 -13.14196)
				)
				(arc
					(start 413.864298 -13.14196)
					(mid 413.379412 -13.627227)
					(end 413.864552 -14.11224)
				)
			)
		)
		(polygon
			(pts
				(arc
					(start 383.45745 -14.11224)
					(mid 383.94259 -13.6271)
					(end 383.45745 -13.14196)
				)
				(arc
					(start 382.314196 -13.14196)
					(mid 381.82931 -13.627227)
					(end 382.31445 -14.11224)
				)
			)
		)
		(polygon
			(pts
				(arc
					(start 351.907602 -14.11224)
					(mid 352.392742 -13.6271)
					(end 351.907602 -13.14196)
				)
				(arc
					(start 350.764348 -13.14196)
					(mid 350.279462 -13.627227)
					(end 350.764602 -14.11224)
				)
			)
		)
	)
	(zone
		(layer "In4.Cu")
		(hatch none 0.5)
		(connect_pads
			(clearance 0)
		)
		(min_thickness 0.25)
		(keepout
			(tracks not_allowed)
			(vias allowed)
			(pads allowed)
			(copperpour not_allowed)
			(footprints allowed)
		)
		(placement
			(enabled no)
			(sheetname "")
		)
		(fill
			(thermal_gap 0.5)
			(thermal_bridge_width 0.5)
			(island_removal_mode 0)
		)
		(polygon
			(pts
				(arc
					(start 157.412182 -372.599966)
					(mid 154.587702 -372.599966)
					(end 157.412182 -372.599966)
				)
			)
		)
	)
	(zone
		(layer "In4.Cu")
		(hatch none 0.5)
		(connect_pads
			(clearance 0)
		)
		(min_thickness 0.25)
		(keepout
			(tracks not_allowed)
			(vias allowed)
			(pads allowed)
			(copperpour not_allowed)
			(footprints allowed)
		)
		(placement
			(enabled no)
			(sheetname "")
		)
		(fill
			(thermal_gap 0.5)
			(thermal_bridge_width 0.5)
			(island_removal_mode 0)
		)
		(polygon
			(pts
				(arc
					(start 448.812158 -367.09985)
					(mid 445.987678 -367.09985)
					(end 448.812158 -367.09985)
				)
			)
		)
	)
	(zone
		(net "GND")
		(layer "In4.Cu")
		(hatch none 0.5)
		(connect_pads
			(clearance 0.5)
		)
		(min_thickness 0.25)
		(fill yes
			(thermal_gap 0.5)
			(thermal_bridge_width 0.5)
			(island_removal_mode 0)
		)
		(polygon
			(pts
				(xy 1.27 -1.27) (xy 1.27 -369.73002)
				(arc
					(start 1.999996 -369.73002)
					(mid 3.605127 -370.394887)
					(end 4.269994 -372.000018)
				)
				(xy 4.269994 -384.72999) (xy 14.979904 -384.72999)
				(arc
					(start 14.979904 -383.29997)
					(mid 15.644771 -381.694839)
					(end 17.249902 -381.029972)
				)
				(arc
					(start 23.750016 -381.029972)
					(mid 24.317409 -381.163766)
					(end 24.765254 -381.536956)
				)
				(arc
					(start 25.180036 -381.536956)
					(mid 25.799334 -382.323511)
					(end 26.020014 -383.29997)
				)
				(xy 26.020014 -384.72999) (xy 71.030084 -384.72999)
				(arc
					(start 71.030084 -381)
					(mid 71.694951 -379.394869)
					(end 73.300082 -378.730002)
				)
				(arc
					(start 125.299978 -378.730002)
					(mid 126.905109 -379.394869)
					(end 127.569976 -381)
				)
				(xy 127.569976 -384.72999) (xy 172.580046 -384.72999)
				(arc
					(start 172.580046 -383.29997)
					(mid 173.244913 -381.694839)
					(end 174.850044 -381.029972)
				)
				(arc
					(start 181.349904 -381.029972)
					(mid 182.955035 -381.694839)
					(end 183.619902 -383.29997)
				)
				(xy 183.619902 -384.72999) (xy 196.730112 -384.72999)
				(arc
					(start 196.730112 -381)
					(mid 197.394979 -379.394869)
					(end 199.00011 -378.730002)
				)
				(arc
					(start 251.000006 -378.730002)
					(mid 252.605137 -379.394869)
					(end 253.270004 -381)
				)
				(xy 253.270004 -384.72999) (xy 268.924024 -384.72999) (xy 271.180052 -382.473962)
				(arc
					(start 271.180052 -361.00004)
					(mid 271.844919 -359.394909)
					(end 273.45005 -358.730042)
				)
				(arc
					(start 275.75002 -358.730042)
					(mid 277.355151 -359.394909)
					(end 278.020018 -361.00004)
				)
				(xy 278.020018 -382.473962) (xy 280.276046 -384.72999) (xy 306.37988 -384.72999)
				(arc
					(start 306.37988 -383.29997)
					(mid 307.044747 -381.694839)
					(end 308.649878 -381.029972)
				)
				(arc
					(start 315.149992 -381.029972)
					(mid 316.755123 -381.694839)
					(end 317.41999 -383.29997)
				)
				(xy 317.41999 -384.72999) (xy 362.43006 -384.72999)
				(arc
					(start 362.43006 -381)
					(mid 363.094927 -379.394869)
					(end 364.700058 -378.730002)
				)
				(arc
					(start 416.699954 -378.730002)
					(mid 418.305085 -379.394869)
					(end 418.969952 -381)
				)
				(xy 418.969952 -384.72999) (xy 463.980022 -384.72999)
				(arc
					(start 463.980022 -383.29997)
					(mid 464.644889 -381.694839)
					(end 466.25002 -381.029972)
				)
				(arc
					(start 472.74988 -381.029972)
					(mid 474.355011 -381.694839)
					(end 475.019878 -383.29997)
				)
				(xy 475.019878 -384.72999) (xy 487.179874 -384.72999)
				(arc
					(start 487.179874 -372.000018)
					(mid 487.844831 -370.394797)
					(end 489.450126 -369.73002)
				)
				(xy 490.180122 -369.73002) (xy 490.180122 -1.27) (xy 312.269886 -1.27)
				(arc
					(start 312.269886 -47.200058)
					(mid 311.605019 -48.805189)
					(end 309.999888 -49.470056)
				)
				(xy 270.26997 -49.470056)
				(arc
					(start 270.26997 -61.999876)
					(mid 270.131151 -62.781774)
					(end 269.73149 -63.467996)
				)
				(xy 271.602708 -65.339214) (xy 306.461668 -65.339214) (xy 314.5409 -73.418446) (xy 314.5409 -96.929194)
				(xy 314.881006 -97.2693) (xy 341.576406 -97.2693) (xy 344.1573 -94.688406) (xy 344.1573 -54.104794)
				(xy 328.7395 -38.686994) (xy 328.7395 -19.098006) (xy 330.730606 -17.1069) (xy 343.329006 -17.1069)
				(xy 349.33255 -11.103356) (xy 393.13485 -11.103356) (xy 393.808458 -10.429748) (xy 398.318736 -10.429748)
				(xy 399.001488 -11.1125) (xy 439.625994 -11.1125) (xy 444.451994 -15.9385) (xy 452.071994 -15.9385)
				(xy 454.611994 -18.4785) (xy 461.342994 -18.4785) (xy 464.771994 -21.9075) (xy 470.837006 -21.9075)
				(xy 471.599006 -21.1455) (xy 476.171006 -21.1455) (xy 477.9645 -19.352006) (xy 477.9645 -17.066006)
				(xy 478.965006 -16.0655) (xy 483.694994 -16.0655) (xy 484.1875 -16.558006) (xy 484.1875 -17.604994)
				(xy 481.9015 -19.890994) (xy 481.9015 -22.430994) (xy 479.6155 -24.716994) (xy 479.6155 -100.840794)
				(xy 478.5995 -101.856794) (xy 478.5995 -112.036606) (xy 485.9655 -119.402606) (xy 485.9655 -129.618994)
				(xy 484.456994 -131.1275) (xy 479.376994 -131.1275) (xy 478.7265 -131.777994) (xy 478.7265 -133.398006)
				(xy 479.2345 -133.906006) (xy 479.2345 -137.238994) (xy 477.471994 -139.0015) (xy 474.804994 -139.0015)
				(xy 471.071194 -142.7353) (xy 456.663806 -142.7353) (xy 454.4695 -140.540994) (xy 454.4695 -133.682994)
				(xy 452.168006 -131.3815) (xy 447.372994 -131.3815) (xy 436.019194 -142.7353) (xy 428.088806 -142.7353)
				(xy 424.1165 -138.762994) (xy 424.1165 -119.204994) (xy 414.957006 -110.0455) (xy 314.943998 -110.0455)
				(xy 314.925964 -110.063534) (xy 314.92571 -110.063534) (xy 314.5409 -110.448344) (xy 314.5409 -111.37646)
				(xy 328.132948 -124.968508) (xy 328.132948 -239.17148) (xy 329.034394 -240.072926) (xy 329.034394 -318.549528)
				(xy 322.654422 -324.9295) (xy 247.601994 -324.9295) (xy 245.8085 -326.722994) (xy 245.8085 -346.915994)
				(xy 227.967794 -364.7567) (xy 205.359762 -364.7567) (xy 204.4446 -363.841538) (xy 204.4446 -358.892094)
				(xy 204.137006 -358.5845) (xy 166.0144 -358.5845) (xy 166.0144 -328.7395) (xy 204.149706 -328.7395)
				(xy 204.4446 -328.444606) (xy 204.4446 -321.781424) (xy 193.62039 -310.957214) (xy 193.62039 -124.639578)
				(xy 198.783702 -119.476266) (xy 198.783702 -105.326434) (xy 210.857846 -93.25229) (xy 240.056416 -93.25229)
				(xy 252.2601 -81.048606) (xy 252.2601 -64.269874)
				(arc
					(start 208.000092 -64.269874)
					(mid 206.394961 -63.605007)
					(end 205.730094 -61.999876)
				)
				(xy 205.730094 -49.470056)
				(arc
					(start 200.000108 -49.470056)
					(mid 198.394977 -48.805189)
					(end 197.73011 -47.200058)
				)
				(xy 197.73011 -1.27)
			)
		)
		(polygon
			(pts
				(arc
					(start 447.399918 -371.187726)
					(mid 447.399918 -374.012206)
					(end 447.399918 -371.187726)
				)
			)
		)
		(polygon
			(pts
				(arc
					(start 350.799908 -371.187726)
					(mid 350.799908 -374.012206)
					(end 350.799908 -371.187726)
				)
			)
		)
		(polygon
			(pts
				(arc
					(start 155.999942 -371.187726)
					(mid 155.999942 -374.012206)
					(end 155.999942 -371.187726)
				)
			)
		)
		(polygon
			(pts
				(arc
					(start 59.399932 -371.187726)
					(mid 59.399932 -374.012206)
					(end 59.399932 -371.187726)
				)
			)
		)
		(polygon
			(pts
				(arc
					(start 447.399918 -365.68761)
					(mid 447.399918 -368.51209)
					(end 447.399918 -365.68761)
				)
			)
		)
		(polygon
			(pts
				(arc
					(start 350.799908 -365.68761)
					(mid 350.799908 -368.51209)
					(end 350.799908 -365.68761)
				)
			)
		)
		(polygon
			(pts
				(arc
					(start 155.999942 -365.68761)
					(mid 155.999942 -368.51209)
					(end 155.999942 -365.68761)
				)
			)
		)
		(polygon
			(pts
				(arc
					(start 59.399932 -365.68761)
					(mid 59.399932 -368.51209)
					(end 59.399932 -365.68761)
				)
			)
		)
		(polygon
			(pts
				(xy 157.431994 -326.8345) (xy 152.194006 -326.8345) (xy 151.4475 -327.581006) (xy 151.4475 -330.756006)
				(xy 151.18461 -331.018896) (xy 104.06761 -331.018896) (xy 102.5525 -332.534006) (xy 102.5525 -346.280994)
				(xy 103.4415 -347.169994) (xy 103.4415 -364.348776) (xy 103.964994 -364.87227) (xy 109.369606 -364.87227)
				(xy 112.286796 -361.95508) (xy 123.153932 -361.95508) (xy 126.524512 -358.5845) (xy 160.9725 -358.5845)
				(xy 160.9725 -328.7395) (xy 158.066994 -328.7395) (xy 157.7975 -328.470006) (xy 157.7975 -327.200006)
			)
		)
		(polygon
			(pts
				(arc
					(start 190.744094 -248.11482)
					(mid 190.258827 -247.629934)
					(end 189.773814 -248.115074)
				)
				(arc
					(start 189.773814 -249.385074)
					(mid 190.258954 -249.870214)
					(end 190.744094 -249.385074)
				)
			)
		)
		(polygon
			(pts
				(arc
					(start 192.520824 -244.419374)
					(mid 192.035684 -243.934234)
					(end 191.550544 -244.419374)
				)
				(arc
					(start 191.550544 -245.562628)
					(mid 192.035811 -246.047514)
					(end 192.520824 -245.562374)
				)
			)
		)
		(polygon
			(pts
				(arc
					(start 159.193992 -133.11505)
					(mid 158.708852 -132.62991)
					(end 158.223712 -133.11505)
				)
				(arc
					(start 158.223712 -134.385304)
					(mid 158.708979 -134.87019)
					(end 159.193992 -134.38505)
				)
			)
		)
		(polygon
			(pts
				(arc
					(start 127.64389 -133.11505)
					(mid 127.15875 -132.62991)
					(end 126.67361 -133.11505)
				)
				(arc
					(start 126.67361 -134.385304)
					(mid 127.158877 -134.87019)
					(end 127.64389 -134.38505)
				)
			)
		)
		(polygon
			(pts
				(arc
					(start 96.094042 -133.11505)
					(mid 95.608902 -132.62991)
					(end 95.123762 -133.11505)
				)
				(arc
					(start 95.123762 -134.385304)
					(mid 95.609029 -134.87019)
					(end 96.094042 -134.38505)
				)
			)
		)
		(polygon
			(pts
				(arc
					(start 190.744094 -133.114796)
					(mid 190.258827 -132.62991)
					(end 189.773814 -133.11505)
				)
				(arc
					(start 189.773814 -134.38505)
					(mid 190.258954 -134.87019)
					(end 190.744094 -134.38505)
				)
			)
		)
		(polygon
			(pts
				(arc
					(start 481.701602 -132.922264)
					(mid 482.186742 -132.437124)
					(end 481.701602 -131.951984)
				)
				(arc
					(start 480.431348 -131.951984)
					(mid 479.946462 -132.437251)
					(end 480.431602 -132.922264)
				)
			)
		)
		(polygon
			(pts
				(arc
					(start 450.151754 -132.922264)
					(mid 450.63664 -132.436997)
					(end 450.1515 -131.951984)
				)
				(arc
					(start 448.8815 -131.951984)
					(mid 448.39636 -132.437124)
					(end 448.8815 -132.922264)
				)
			)
		)
		(polygon
			(pts
				(xy 33.225994 -131.1275) (xy 31.163006 -131.1275) (xy 27.861006 -134.4295) (xy 18.971006 -134.4295)
				(xy 17.4625 -135.938006) (xy 17.4625 -144.320006) (xy 15.5575 -146.225006) (xy 15.5575 -229.186994)
				(xy 17.3355 -230.964994) (xy 17.3355 -252.554994) (xy 19.352006 -254.5715) (xy 181.307994 -254.5715)
				(xy 183.0705 -252.808994) (xy 183.0705 -217.573606) (xy 178.717194 -213.2203) (xy 92.280994 -213.2203)
				(xy 88.9635 -209.902806) (xy 88.9635 -135.303006) (xy 87.708994 -134.0485) (xy 83.233006 -134.0485)
				(xy 79.905606 -137.3759) (xy 78.336394 -137.3759) (xy 73.357994 -132.3975) (xy 65.483994 -132.3975)
				(xy 65.0875 -132.001006) (xy 65.0875 -131.493006) (xy 64.721994 -131.1275) (xy 62.659006 -131.1275)
				(xy 60.246006 -133.5405) (xy 51.737006 -133.5405) (xy 49.298606 -135.9789) (xy 41.379394 -135.9789)
				(xy 37.924994 -132.5245) (xy 33.860994 -132.5245) (xy 33.5915 -132.255006) (xy 33.5915 -131.493006)
			)
		)
		(polygon
			(pts
				(xy 389.206994 -131.0005) (xy 383.969006 -131.0005) (xy 380.286006 -134.6835) (xy 369.313206 -134.6835)
				(xy 366.976406 -137.0203) (xy 360.809794 -137.0203) (xy 358.7115 -134.922006) (xy 358.7115 -132.128006)
				(xy 357.710994 -131.1275) (xy 351.711006 -131.1275) (xy 348.155006 -134.6835) (xy 339.519006 -134.6835)
				(xy 337.8835 -136.319006) (xy 337.8835 -256.491994) (xy 339.011006 -257.6195) (xy 483.517194 -257.6195)
				(xy 486.7783 -254.358394) (xy 486.7783 -217.624406) (xy 459.641194 -190.4873) (xy 454.332594 -190.4873)
				(xy 450.4817 -186.636406) (xy 450.4817 -181.327806) (xy 414.4645 -145.310606) (xy 414.4645 -142.826994)
				(xy 418.6555 -138.635994) (xy 418.6555 -136.222994) (xy 421.0685 -133.809994) (xy 421.0685 -131.620006)
				(xy 420.448994 -131.0005) (xy 408.607006 -131.0005) (xy 404.924006 -134.6835) (xy 392.889994 -134.6835)
			)
		)
		(polygon
			(pts
				(arc
					(start 192.520824 -129.419096)
					(mid 192.035557 -128.93421)
					(end 191.550544 -129.41935)
				)
				(arc
					(start 191.550544 -130.56235)
					(mid 192.035684 -131.04749)
					(end 192.520824 -130.56235)
				)
			)
		)
		(polygon
			(pts
				(arc
					(start 97.870772 -129.419096)
					(mid 97.385505 -128.93421)
					(end 96.900492 -129.41935)
				)
				(arc
					(start 96.900492 -130.56235)
					(mid 97.385632 -131.04749)
					(end 97.870772 -130.56235)
				)
			)
		)
		(polygon
			(pts
				(arc
					(start 66.32067 -129.419096)
					(mid 65.835403 -128.93421)
					(end 65.35039 -129.41935)
				)
				(arc
					(start 65.35039 -130.56235)
					(mid 65.83553 -131.04749)
					(end 66.32067 -130.56235)
				)
			)
		)
		(polygon
			(pts
				(arc
					(start 34.770822 -129.419096)
					(mid 34.285555 -128.93421)
					(end 33.800542 -129.41935)
				)
				(arc
					(start 33.800542 -130.56235)
					(mid 34.285682 -131.04749)
					(end 34.770822 -130.56235)
				)
			)
		)
		(polygon
			(pts
				(arc
					(start 415.007552 -129.112264)
					(mid 415.492692 -128.627124)
					(end 415.007552 -128.141984)
				)
				(arc
					(start 413.864298 -128.141984)
					(mid 413.379412 -128.627251)
					(end 413.864552 -129.112264)
				)
			)
		)
		(polygon
			(pts
				(arc
					(start 383.45745 -129.112264)
					(mid 383.94259 -128.627124)
					(end 383.45745 -128.141984)
				)
				(arc
					(start 382.314196 -128.141984)
					(mid 381.82931 -128.627251)
					(end 382.31445 -129.112264)
				)
			)
		)
		(polygon
			(pts
				(arc
					(start 351.907602 -129.112264)
					(mid 352.392742 -128.627124)
					(end 351.907602 -128.141984)
				)
				(arc
					(start 350.764348 -128.141984)
					(mid 350.279462 -128.627251)
					(end 350.764602 -129.112264)
				)
			)
		)
		(polygon
			(pts
				(arc
					(start 221.348808 -77.599794)
					(mid 220.800041 -77.051408)
					(end 220.251528 -77.600048)
				)
				(arc
					(start 220.251528 -78.999842)
					(mid 220.800168 -79.548482)
					(end 221.348808 -78.999842)
				)
			)
		)
		(polygon
			(pts
				(arc
					(start 217.748612 -77.599794)
					(mid 217.199845 -77.051408)
					(end 216.651332 -77.600048)
				)
				(arc
					(start 216.651332 -78.999842)
					(mid 217.199972 -79.548482)
					(end 217.748612 -78.999842)
				)
			)
		)
		(polygon
			(pts
				(arc
					(start 214.14867 -77.599794)
					(mid 213.599903 -77.051408)
					(end 213.05139 -77.600048)
				)
				(arc
					(start 213.05139 -78.999842)
					(mid 213.60003 -79.548482)
					(end 214.14867 -78.999842)
				)
			)
		)
		(polygon
			(pts
				(arc
					(start 210.548728 -77.599794)
					(mid 209.999961 -77.051408)
					(end 209.451448 -77.600048)
				)
				(arc
					(start 209.451448 -78.999842)
					(mid 210.000088 -79.548482)
					(end 210.548728 -78.999842)
				)
			)
		)
		(polygon
			(pts
				(arc
					(start 223.148652 -76.399898)
					(mid 222.600012 -75.851258)
					(end 222.051372 -76.399898)
				)
				(arc
					(start 222.051372 -77.8002)
					(mid 222.600139 -78.348586)
					(end 223.148652 -77.799946)
				)
			)
		)
		(polygon
			(pts
				(arc
					(start 219.54871 -76.399898)
					(mid 219.00007 -75.851258)
					(end 218.45143 -76.399898)
				)
				(arc
					(start 218.45143 -77.8002)
					(mid 219.000197 -78.348586)
					(end 219.54871 -77.799946)
				)
			)
		)
		(polygon
			(pts
				(arc
					(start 215.948768 -76.399898)
					(mid 215.400128 -75.851258)
					(end 214.851488 -76.399898)
				)
				(arc
					(start 214.851488 -77.8002)
					(mid 215.400255 -78.348586)
					(end 215.948768 -77.799946)
				)
			)
		)
		(polygon
			(pts
				(arc
					(start 212.348826 -76.399898)
					(mid 211.800186 -75.851258)
					(end 211.251546 -76.399898)
				)
				(arc
					(start 211.251546 -77.8002)
					(mid 211.800313 -78.348586)
					(end 212.348826 -77.799946)
				)
			)
		)
		(polygon
			(pts
				(arc
					(start 210.548728 -73.999852)
					(mid 210.000088 -73.451212)
					(end 209.451448 -73.999852)
				)
				(arc
					(start 209.451448 -75.400154)
					(mid 210.000215 -75.94854)
					(end 210.548728 -75.3999)
				)
			)
		)
		(polygon
			(pts
				(arc
					(start 221.348808 -70.39991)
					(mid 220.800168 -69.85127)
					(end 220.251528 -70.39991)
				)
				(arc
					(start 220.251528 -71.800212)
					(mid 220.800295 -72.348598)
					(end 221.348808 -71.799958)
				)
			)
		)
		(polygon
			(pts
				(arc
					(start 217.748612 -70.39991)
					(mid 217.199972 -69.85127)
					(end 216.651332 -70.39991)
				)
				(arc
					(start 216.651332 -71.800212)
					(mid 217.200099 -72.348598)
					(end 217.748612 -71.799958)
				)
			)
		)
		(polygon
			(pts
				(arc
					(start 214.14867 -70.39991)
					(mid 213.60003 -69.85127)
					(end 213.05139 -70.39991)
				)
				(arc
					(start 213.05139 -71.800212)
					(mid 213.600157 -72.348598)
					(end 214.14867 -71.799958)
				)
			)
		)
		(polygon
			(pts
				(arc
					(start 210.548728 -70.39991)
					(mid 210.000088 -69.85127)
					(end 209.451448 -70.39991)
				)
				(arc
					(start 209.451448 -71.800212)
					(mid 210.000215 -72.348598)
					(end 210.548728 -71.799958)
				)
			)
		)
		(polygon
			(pts
				(arc
					(start 219.54871 -65.600072)
					(mid 219.00007 -65.051432)
					(end 218.45143 -65.600072)
				)
				(arc
					(start 218.45143 -67.00012)
					(mid 219.000197 -67.548506)
					(end 219.54871 -66.999866)
				)
			)
		)
		(polygon
			(pts
				(arc
					(start 215.948768 -65.600072)
					(mid 215.400128 -65.051432)
					(end 214.851488 -65.600072)
				)
				(arc
					(start 214.851488 -67.00012)
					(mid 215.400255 -67.548506)
					(end 215.948768 -66.999866)
				)
			)
		)
		(polygon
			(pts
				(arc
					(start 212.348826 -65.600072)
					(mid 211.800186 -65.051432)
					(end 211.251546 -65.600072)
				)
				(arc
					(start 211.251546 -67.00012)
					(mid 211.800313 -67.548506)
					(end 212.348826 -66.999866)
				)
			)
		)
		(polygon
			(pts
				(arc
					(start 223.148652 -65.599818)
					(mid 222.599885 -65.051432)
					(end 222.051372 -65.600072)
				)
				(arc
					(start 222.051372 -66.999866)
					(mid 222.600012 -67.548506)
					(end 223.148652 -66.999866)
				)
			)
		)
		(polygon
			(pts
				(arc
					(start 190.744094 -18.114772)
					(mid 190.258827 -17.629886)
					(end 189.773814 -18.115026)
				)
				(arc
					(start 189.773814 -19.385026)
					(mid 190.258954 -19.870166)
					(end 190.744094 -19.385026)
				)
			)
		)
		(polygon
			(pts
				(arc
					(start 323.951854 -17.92224)
					(mid 324.43674 -17.436973)
					(end 323.9516 -16.95196)
				)
				(arc
					(start 322.6816 -16.95196)
					(mid 322.19646 -17.4371)
					(end 322.6816 -17.92224)
				)
			)
		)
		(polygon
			(pts
				(xy 64.594994 -15.9385) (xy 63.421006 -15.9385) (xy 62.6745 -16.685006) (xy 62.6745 -20.241006)
				(xy 61.516006 -21.3995) (xy 41.226994 -21.3995) (xy 37.289994 -17.4625) (xy 33.860994 -17.4625)
				(xy 33.5915 -17.193006) (xy 33.5915 -16.558006) (xy 33.225994 -16.1925) (xy 31.163006 -16.1925)
				(xy 28.623006 -18.7325) (xy 20.495006 -18.7325) (xy 17.3355 -21.892006) (xy 17.3355 -101.018594)
				(xy 25.473406 -109.1565) (xy 52.168806 -109.1565) (xy 59.433206 -116.4209) (xy 62.426342 -116.4209)
				(xy 63.340996 -117.335554) (xy 68.322698 -117.335554) (xy 69.237352 -116.4209) (xy 108.404406 -116.4209)
				(xy 111.9505 -119.966994) (xy 111.9505 -137.746994) (xy 113.840006 -139.6365) (xy 124.157994 -139.6365)
				(xy 125.9205 -137.873994) (xy 125.9205 -131.777994) (xy 126.443994 -131.2545) (xy 127.429006 -131.2545)
				(xy 127.8255 -131.650994) (xy 127.8255 -132.285994) (xy 128.445006 -132.9055) (xy 134.414006 -132.9055)
				(xy 141.145006 -139.6365) (xy 155.907994 -139.6365) (xy 157.5435 -138.000994) (xy 157.5435 -131.777994)
				(xy 158.193994 -131.1275) (xy 159.052006 -131.1275) (xy 159.4485 -131.523994) (xy 159.4485 -132.539994)
				(xy 159.687006 -132.7785) (xy 168.323006 -132.7785) (xy 175.181006 -139.6365) (xy 181.053994 -139.6365)
				(xy 183.3245 -137.365994) (xy 183.3245 -91.823794) (xy 187.226194 -87.9221) (xy 192.300606 -87.9221)
				(xy 193.316606 -88.9381) (xy 229.847394 -88.9381) (xy 234.1753 -84.610194) (xy 234.1753 -78.280006)
				(xy 232.768394 -76.8731) (xy 225.066606 -76.8731) (xy 223.9391 -78.000606) (xy 223.9391 -80.159606)
				(xy 223.136206 -80.9625) (xy 186.083194 -80.9625) (xy 183.3245 -78.203806) (xy 183.3245 -22.908006)
				(xy 181.815994 -21.3995) (xy 165.559994 -21.3995) (xy 161.749994 -17.5895) (xy 160.352994 -17.5895)
				(xy 159.8295 -17.066006) (xy 159.8295 -16.431006) (xy 159.463994 -16.0655) (xy 157.909006 -16.0655)
				(xy 155.242006 -18.7325) (xy 146.479006 -18.7325) (xy 144.142206 -21.0693) (xy 134.876794 -21.0693)
				(xy 131.396994 -17.5895) (xy 128.475994 -17.5895) (xy 128.2065 -17.320006) (xy 128.2065 -16.431006)
				(xy 127.840994 -16.0655) (xy 125.905006 -16.0655) (xy 123.238006 -18.7325) (xy 113.840006 -18.7325)
				(xy 111.528606 -21.0439) (xy 101.577394 -21.0439) (xy 97.995994 -17.4625) (xy 97.106994 -17.4625)
				(xy 96.7105 -17.066006) (xy 96.7105 -16.431006) (xy 96.217994 -15.9385) (xy 94.282006 -15.9385)
				(xy 91.488006 -18.7325) (xy 83.487006 -18.7325) (xy 80.820006 -21.3995) (xy 74.500994 -21.3995)
				(xy 70.690994 -17.5895) (xy 65.356994 -17.5895) (xy 65.0875 -17.320006) (xy 65.0875 -16.431006)
			)
		)
		(polygon
			(pts
				(arc
					(start 192.520824 -14.419072)
					(mid 192.035557 -13.934186)
					(end 191.550544 -14.419326)
				)
				(arc
					(start 191.550544 -15.562326)
					(mid 192.035684 -16.047466)
					(end 192.520824 -15.562326)
				)
			)
		)
		(polygon
			(pts
				(arc
					(start 160.970722 -14.419072)
					(mid 160.485455 -13.934186)
					(end 160.000442 -14.419326)
				)
				(arc
					(start 160.000442 -15.562326)
					(mid 160.485582 -16.047466)
					(end 160.970722 -15.562326)
				)
			)
		)
		(polygon
			(pts
				(arc
					(start 129.42062 -14.419072)
					(mid 128.935353 -13.934186)
					(end 128.45034 -14.419326)
				)
				(arc
					(start 128.45034 -15.562326)
					(mid 128.93548 -16.047466)
					(end 129.42062 -15.562326)
				)
			)
		)
		(polygon
			(pts
				(arc
					(start 97.870772 -14.419072)
					(mid 97.385505 -13.934186)
					(end 96.900492 -14.419326)
				)
				(arc
					(start 96.900492 -15.562326)
					(mid 97.385632 -16.047466)
					(end 97.870772 -15.562326)
				)
			)
		)
		(polygon
			(pts
				(arc
					(start 66.32067 -14.419072)
					(mid 65.835403 -13.934186)
					(end 65.35039 -14.419326)
				)
				(arc
					(start 65.35039 -15.562326)
					(mid 65.83553 -16.047466)
					(end 66.32067 -15.562326)
				)
			)
		)
		(polygon
			(pts
				(arc
					(start 34.770822 -14.419072)
					(mid 34.285555 -13.934186)
					(end 33.800542 -14.419326)
				)
				(arc
					(start 33.800542 -15.562326)
					(mid 34.285682 -16.047466)
					(end 34.770822 -15.562326)
				)
			)
		)
		(polygon
			(pts
				(arc
					(start 478.107502 -14.11224)
					(mid 478.592642 -13.6271)
					(end 478.107502 -13.14196)
				)
				(arc
					(start 476.964248 -13.14196)
					(mid 476.479362 -13.627227)
					(end 476.964502 -14.11224)
				)
			)
		)
		(polygon
			(pts
				(arc
					(start 446.5574 -14.11224)
					(mid 447.04254 -13.6271)
					(end 446.5574 -13.14196)
				)
				(arc
					(start 445.414146 -13.14196)
					(mid 444.92926 -13.627227)
					(end 445.4144 -14.11224)
				)
			)
		)
		(polygon
			(pts
				(arc
					(start 320.3575 -14.11224)
					(mid 320.84264 -13.6271)
					(end 320.3575 -13.14196)
				)
				(arc
					(start 319.214246 -13.14196)
					(mid 318.72936 -13.627227)
					(end 319.2145 -14.11224)
				)
			)
		)
	)
	(zone
		(layer "In4.Cu")
		(hatch none 0.5)
		(connect_pads
			(clearance 0)
		)
		(min_thickness 0.25)
		(keepout
			(tracks not_allowed)
			(vias allowed)
			(pads allowed)
			(copperpour not_allowed)
			(footprints allowed)
		)
		(placement
			(enabled no)
			(sheetname "")
		)
		(fill
			(thermal_gap 0.5)
			(thermal_bridge_width 0.5)
			(island_removal_mode 0)
		)
		(polygon
			(pts
				(arc
					(start 157.412182 -367.09985)
					(mid 154.587702 -367.09985)
					(end 157.412182 -367.09985)
				)
			)
		)
	)
	(zone
		(layer "In4.Cu")
		(hatch none 0.5)
		(connect_pads
			(clearance 0)
		)
		(min_thickness 0.25)
		(keepout
			(tracks not_allowed)
			(vias allowed)
			(pads allowed)
			(copperpour not_allowed)
			(footprints allowed)
		)
		(placement
			(enabled no)
			(sheetname "")
		)
		(fill
			(thermal_gap 0.5)
			(thermal_bridge_width 0.5)
			(island_removal_mode 0)
		)
		(polygon
			(pts
				(arc
					(start 60.812172 -367.09985)
					(mid 57.987692 -367.09985)
					(end 60.812172 -367.09985)
				)
			)
		)
	)
	(zone
		(layers "In4.Cu" "In6.Cu")
		(hatch none 0.5)
		(connect_pads
			(clearance 0)
		)
		(min_thickness 0.25)
		(keepout
			(tracks not_allowed)
			(vias allowed)
			(pads allowed)
			(copperpour not_allowed)
			(footprints allowed)
		)
		(placement
			(enabled no)
			(sheetname "")
		)
		(fill yes
			(thermal_gap 0.5)
			(thermal_bridge_width 0.5)
			(island_removal_mode 0)
		)
		(polygon
			(pts
				(arc
					(start 470.333324 -377.219972)
					(mid 468.666576 -377.219972)
					(end 470.333324 -377.219972)
				)
			)
		)
	)
	(zone
		(layers "In4.Cu" "In6.Cu")
		(hatch none 0.5)
		(connect_pads
			(clearance 0)
		)
		(min_thickness 0.25)
		(keepout
			(tracks not_allowed)
			(vias allowed)
			(pads allowed)
			(copperpour not_allowed)
			(footprints allowed)
		)
		(placement
			(enabled no)
			(sheetname "")
		)
		(fill yes
			(thermal_gap 0.5)
			(thermal_bridge_width 0.5)
			(island_removal_mode 0)
		)
		(polygon
			(pts
				(arc
					(start 178.933348 -377.219972)
					(mid 177.2666 -377.219972)
					(end 178.933348 -377.219972)
				)
			)
		)
	)
	(zone
		(layers "In4.Cu" "In6.Cu")
		(hatch none 0.5)
		(connect_pads
			(clearance 0)
		)
		(min_thickness 0.25)
		(keepout
			(tracks not_allowed)
			(vias allowed)
			(pads allowed)
			(copperpour not_allowed)
			(footprints allowed)
		)
		(placement
			(enabled no)
			(sheetname "")
		)
		(fill yes
			(thermal_gap 0.5)
			(thermal_bridge_width 0.5)
			(island_removal_mode 0)
		)
		(polygon
			(pts
				(arc
					(start 21.33346 -377.219972)
					(mid 19.666712 -377.219972)
					(end 21.33346 -377.219972)
				)
			)
		)
	)
	(zone
		(layers "In4.Cu" "In6.Cu")
		(hatch none 0.5)
		(connect_pads
			(clearance 0)
		)
		(min_thickness 0.25)
		(keepout
			(tracks not_allowed)
			(vias allowed)
			(pads allowed)
			(copperpour not_allowed)
			(footprints allowed)
		)
		(placement
			(enabled no)
			(sheetname "")
		)
		(fill yes
			(thermal_gap 0.5)
			(thermal_bridge_width 0.5)
			(island_removal_mode 0)
		)
		(polygon
			(pts
				(arc
					(start 312.733436 -377.219972)
					(mid 311.066688 -377.219972)
					(end 312.733436 -377.219972)
				)
			)
		)
	)
	(zone
		(layer "In5.Cu")
		(hatch none 0.5)
		(connect_pads
			(clearance 0)
		)
		(min_thickness 0.25)
		(keepout
			(tracks not_allowed)
			(vias allowed)
			(pads allowed)
			(copperpour not_allowed)
			(footprints allowed)
		)
		(placement
			(enabled no)
			(sheetname "")
		)
		(fill
			(thermal_gap 0.5)
			(thermal_bridge_width 0.5)
			(island_removal_mode 0)
		)
		(polygon
			(pts
				(arc
					(start 190.744094 -133.115304)
					(mid 190.259081 -132.62991)
					(end 189.773814 -133.11505)
				)
				(arc
					(start 189.773814 -134.38505)
					(mid 190.258954 -134.87019)
					(end 190.744094 -134.38505)
				)
				(xy 190.744094 -133.991096) (xy 190.383922 -133.991096)
				(arc
					(start 190.379604 -133.99135)
					(mid 190.346018 -134.005262)
					(end 190.332106 -134.038848)
				)
				(xy 190.331852 -134.043166)
				(arc
					(start 190.331852 -134.12851)
					(mid 190.258954 -134.651746)
					(end 190.186056 -134.12851)
				)
				(xy 190.186056 -134.043166) (xy 190.185802 -134.038848) (xy 190.186056 -134.031736) (xy 190.186056 -134.008622)
				(arc
					(start 190.188596 -134.005828)
					(mid 190.242538 -133.901782)
					(end 190.346584 -133.84784)
				)
				(xy 190.349378 -133.8453) (xy 190.372492 -133.8453) (xy 190.379604 -133.845046) (xy 190.383922 -133.8453)
				(xy 190.744094 -133.8453) (xy 190.744094 -133.6548) (xy 190.383922 -133.6548) (xy 190.379604 -133.6548)
				(xy 190.372492 -133.6548) (xy 190.349378 -133.6548)
				(arc
					(start 190.346584 -133.652006)
					(mid 190.242538 -133.598064)
					(end 190.188596 -133.494018)
				)
				(xy 190.186056 -133.491224) (xy 190.186056 -133.46811) (xy 190.185802 -133.460998) (xy 190.186056 -133.45668)
				(arc
					(start 190.186056 -133.37159)
					(mid 190.258954 -132.848354)
					(end 190.331852 -133.37159)
				)
				(xy 190.331852 -133.45668)
				(arc
					(start 190.332106 -133.460998)
					(mid 190.346018 -133.494584)
					(end 190.379604 -133.508496)
				)
				(xy 190.383922 -133.508496) (xy 190.744094 -133.508496)
			)
		)
	)
	(zone
		(layer "In5.Cu")
		(hatch none 0.5)
		(connect_pads
			(clearance 0)
		)
		(min_thickness 0.25)
		(keepout
			(tracks not_allowed)
			(vias allowed)
			(pads allowed)
			(copperpour not_allowed)
			(footprints allowed)
		)
		(placement
			(enabled no)
			(sheetname "")
		)
		(fill
			(thermal_gap 0.5)
			(thermal_bridge_width 0.5)
			(island_removal_mode 0)
		)
		(polygon
			(pts
				(arc
					(start 322.6816 -131.951984)
					(mid 322.19646 -132.437124)
					(end 322.6816 -132.922264)
				)
				(xy 323.0753 -132.922264) (xy 323.0753 -132.601716)
				(arc
					(start 323.075046 -132.597398)
					(mid 323.049529 -132.535793)
					(end 322.987924 -132.510276)
				)
				(xy 322.983606 -132.510276)
				(arc
					(start 322.93814 -132.510276)
					(mid 322.414834 -132.437124)
					(end 322.93814 -132.363972)
				)
				(xy 322.983606 -132.363972) (xy 322.987924 -132.363972) (xy 322.995544 -132.363972) (xy 323.01815 -132.363972)
				(arc
					(start 323.020182 -132.366258)
					(mid 323.152949 -132.432373)
					(end 323.219064 -132.56514)
				)
				(xy 323.221096 -132.567172) (xy 323.221096 -132.589778) (xy 323.22135 -132.597398) (xy 323.221096 -132.601716)
				(xy 323.221096 -132.922264) (xy 323.411596 -132.922264) (xy 323.411596 -132.60197) (xy 323.411596 -132.597652)
				(xy 323.411596 -132.590032) (xy 323.411596 -132.567426)
				(arc
					(start 323.413882 -132.565394)
					(mid 323.480073 -132.432449)
					(end 323.613018 -132.366258)
				)
				(xy 323.61505 -132.363972) (xy 323.637656 -132.363972) (xy 323.645276 -132.363972) (xy 323.649594 -132.363972)
				(arc
					(start 323.69506 -132.363972)
					(mid 324.218366 -132.437124)
					(end 323.69506 -132.510276)
				)
				(xy 323.649594 -132.510276)
				(arc
					(start 323.645276 -132.510276)
					(mid 323.583492 -132.535868)
					(end 323.5579 -132.597652)
				)
				(xy 323.5579 -132.60197) (xy 323.5579 -132.922264)
				(arc
					(start 323.951346 -132.922264)
					(mid 324.43674 -132.437251)
					(end 323.9516 -131.951984)
				)
			)
		)
	)
	(zone
		(layer "In5.Cu")
		(hatch none 0.5)
		(connect_pads
			(clearance 0)
		)
		(min_thickness 0.25)
		(keepout
			(tracks not_allowed)
			(vias allowed)
			(pads allowed)
			(copperpour not_allowed)
			(footprints allowed)
		)
		(placement
			(enabled no)
			(sheetname "")
		)
		(fill
			(thermal_gap 0.5)
			(thermal_bridge_width 0.5)
			(island_removal_mode 0)
		)
		(polygon
			(pts
				(arc
					(start 285.436564 -207.54594)
					(mid 284.887924 -208.09458)
					(end 285.436564 -208.64322)
				)
				(arc
					(start 286.836612 -208.64322)
					(mid 287.385252 -208.09458)
					(end 286.836612 -207.54594)
				)
				(arc
					(start 286.361378 -207.54594)
					(mid 286.372052 -207.60872)
					(end 286.37738 -207.672178)
				)
				(xy 286.377888 -207.672686) (xy 286.377888 -207.689196) (xy 286.377888 -207.702912) (xy 286.377888 -207.70723)
				(xy 286.377888 -207.927194)
				(arc
					(start 286.377888 -207.931512)
					(mid 286.398221 -207.98846)
					(end 286.450024 -208.01965)
				)
				(arc
					(start 286.450024 -208.01965)
					(mid 287.230346 -208.094974)
					(end 286.44977 -208.167732)
				)
				(xy 286.437578 -208.167732)
				(arc
					(start 286.435546 -208.165446)
					(mid 286.300822 -208.098494)
					(end 286.23387 -207.96377)
				)
				(xy 286.231584 -207.961738) (xy 286.231584 -207.939132) (xy 286.231584 -207.931512) (xy 286.231584 -207.927194)
				(xy 286.231584 -207.70723)
				(arc
					(start 286.231584 -207.702912)
					(mid 286.226335 -207.623741)
					(end 286.210756 -207.54594)
				)
				(arc
					(start 286.01035 -207.54594)
					(mid 286.030152 -207.607637)
					(end 286.040068 -207.67167)
				)
				(xy 286.041084 -207.672686) (xy 286.041084 -207.692752) (xy 286.041338 -207.702912) (xy 286.041084 -207.70723)
				(xy 286.041084 -207.927194) (xy 286.041338 -207.931512) (xy 286.041084 -207.939132) (xy 286.041084 -207.961738)
				(arc
					(start 286.039052 -207.96377)
					(mid 285.9721 -208.098494)
					(end 285.837376 -208.165446)
				)
				(xy 285.835344 -208.167732)
				(arc
					(start 285.823406 -208.167732)
					(mid 285.042819 -208.094974)
					(end 285.823152 -208.01965)
				)
				(arc
					(start 285.823152 -208.01965)
					(mid 285.874817 -207.988394)
					(end 285.895034 -207.931512)
				)
				(xy 285.895288 -207.927194) (xy 285.895288 -207.70723)
				(arc
					(start 285.895034 -207.702912)
					(mid 285.881954 -207.620376)
					(end 285.84398 -207.54594)
				)
			)
		)
	)
	(zone
		(layer "In5.Cu")
		(hatch none 0.5)
		(connect_pads
			(clearance 0)
		)
		(min_thickness 0.25)
		(keepout
			(tracks not_allowed)
			(vias allowed)
			(pads allowed)
			(copperpour not_allowed)
			(footprints allowed)
		)
		(placement
			(enabled no)
			(sheetname "")
		)
		(fill
			(thermal_gap 0.5)
			(thermal_bridge_width 0.5)
			(island_removal_mode 0)
		)
		(polygon
			(pts
				(arc
					(start 217.748612 -70.39991)
					(mid 217.199972 -69.85127)
					(end 216.651332 -70.39991)
				)
				(arc
					(start 216.651332 -71.799704)
					(mid 217.199845 -72.348598)
					(end 217.748612 -71.799958)
				)
				(arc
					(start 217.748612 -71.385938)
					(mid 217.665041 -71.343191)
					(end 217.572336 -71.328534)
				)
				(arc
					(start 217.384884 -71.328534)
					(mid 217.318306 -71.353144)
					(end 217.283792 -71.415148)
				)
				(arc
					(start 217.283792 -71.415148)
					(mid 217.199324 -72.193791)
					(end 217.117422 -71.414894)
				)
				(xy 217.117422 -71.396606)
				(arc
					(start 217.119962 -71.394066)
					(mid 217.195754 -71.241766)
					(end 217.348054 -71.165974)
				)
				(xy 217.350594 -71.163434) (xy 217.606626 -71.163434)
				(arc
					(start 217.607896 -71.164704)
					(mid 217.679573 -71.175938)
					(end 217.748612 -71.198232)
				)
				(arc
					(start 217.748612 -71.063358)
					(mid 217.661494 -71.043222)
					(end 217.572336 -71.036434)
				)
				(xy 217.350594 -71.036434)
				(arc
					(start 217.348054 -71.033894)
					(mid 217.195754 -70.958102)
					(end 217.119962 -70.805802)
				)
				(xy 217.117422 -70.803262)
				(arc
					(start 217.117422 -70.784974)
					(mid 217.199325 -70.006097)
					(end 217.283792 -70.78472)
				)
				(arc
					(start 217.283792 -70.78472)
					(mid 217.318339 -70.846686)
					(end 217.384884 -70.871334)
				)
				(xy 217.606626 -70.871334)
				(arc
					(start 217.607388 -70.872096)
					(mid 217.678474 -70.878793)
					(end 217.748612 -70.892162)
				)
			)
		)
	)
	(zone
		(layer "In5.Cu")
		(hatch none 0.5)
		(connect_pads
			(clearance 0)
		)
		(min_thickness 0.25)
		(keepout
			(tracks not_allowed)
			(vias allowed)
			(pads allowed)
			(copperpour not_allowed)
			(footprints allowed)
		)
		(placement
			(enabled no)
			(sheetname "")
		)
		(fill
			(thermal_gap 0.5)
			(thermal_bridge_width 0.5)
			(island_removal_mode 0)
		)
		(polygon
			(pts
				(arc
					(start 190.744094 -248.115328)
					(mid 190.259081 -247.629934)
					(end 189.773814 -248.115074)
				)
				(arc
					(start 189.773814 -249.385074)
					(mid 190.258954 -249.870214)
					(end 190.744094 -249.385074)
				)
				(xy 190.744094 -248.99112) (xy 190.383922 -248.99112)
				(arc
					(start 190.379604 -248.991374)
					(mid 190.346018 -249.005286)
					(end 190.332106 -249.038872)
				)
				(xy 190.331852 -249.04319)
				(arc
					(start 190.331852 -249.128534)
					(mid 190.258954 -249.65177)
					(end 190.186056 -249.128534)
				)
				(xy 190.186056 -249.04319) (xy 190.185802 -249.038872) (xy 190.186056 -249.03176) (xy 190.186056 -249.008646)
				(arc
					(start 190.188596 -249.005852)
					(mid 190.242538 -248.901806)
					(end 190.346584 -248.847864)
				)
				(xy 190.349378 -248.845324) (xy 190.372492 -248.845324) (xy 190.379604 -248.84507) (xy 190.383922 -248.845324)
				(xy 190.744094 -248.845324) (xy 190.744094 -248.654824) (xy 190.383922 -248.654824) (xy 190.379604 -248.654824)
				(xy 190.372492 -248.654824) (xy 190.349378 -248.654824)
				(arc
					(start 190.346584 -248.65203)
					(mid 190.242538 -248.598088)
					(end 190.188596 -248.494042)
				)
				(xy 190.186056 -248.491248) (xy 190.186056 -248.468134) (xy 190.185802 -248.461022) (xy 190.186056 -248.456704)
				(arc
					(start 190.186056 -248.371614)
					(mid 190.258954 -247.848378)
					(end 190.331852 -248.371614)
				)
				(xy 190.331852 -248.456704)
				(arc
					(start 190.332106 -248.461022)
					(mid 190.346018 -248.494608)
					(end 190.379604 -248.50852)
				)
				(xy 190.383922 -248.50852) (xy 190.744094 -248.50852)
			)
		)
	)
	(zone
		(layer "In5.Cu")
		(hatch none 0.5)
		(connect_pads
			(clearance 0)
		)
		(min_thickness 0.25)
		(keepout
			(tracks not_allowed)
			(vias allowed)
			(pads allowed)
			(copperpour not_allowed)
			(footprints allowed)
		)
		(placement
			(enabled no)
			(sheetname "")
		)
		(fill
			(thermal_gap 0.5)
			(thermal_bridge_width 0.5)
			(island_removal_mode 0)
		)
		(polygon
			(pts
				(arc
					(start 223.148652 -65.600326)
					(mid 222.600139 -65.051432)
					(end 222.051372 -65.600072)
				)
				(arc
					(start 222.051372 -66.999866)
					(mid 222.600012 -67.548506)
					(end 223.148652 -66.999866)
				)
				(arc
					(start 223.148652 -66.585846)
					(mid 223.065081 -66.543099)
					(end 222.972376 -66.528442)
				)
				(arc
					(start 222.784924 -66.528442)
					(mid 222.718346 -66.553052)
					(end 222.683832 -66.615056)
				)
				(arc
					(start 222.683832 -66.615056)
					(mid 222.599364 -67.393699)
					(end 222.517462 -66.614802)
				)
				(xy 222.517462 -66.596514)
				(arc
					(start 222.520002 -66.593974)
					(mid 222.595794 -66.441674)
					(end 222.748094 -66.365882)
				)
				(xy 222.750634 -66.363342) (xy 223.006666 -66.363342)
				(arc
					(start 223.007936 -66.364612)
					(mid 223.079613 -66.375846)
					(end 223.148652 -66.39814)
				)
				(arc
					(start 223.148652 -66.263266)
					(mid 223.061534 -66.24313)
					(end 222.972376 -66.236342)
				)
				(xy 222.750634 -66.236342)
				(arc
					(start 222.748094 -66.233802)
					(mid 222.595794 -66.15801)
					(end 222.520002 -66.00571)
				)
				(xy 222.517462 -66.00317)
				(arc
					(start 222.517462 -65.985136)
					(mid 222.598333 -65.206367)
					(end 222.683832 -65.984628)
				)
				(arc
					(start 222.683832 -65.984628)
					(mid 222.718379 -66.046594)
					(end 222.784924 -66.071242)
				)
				(xy 223.006666 -66.071242)
				(arc
					(start 223.007428 -66.072004)
					(mid 223.078514 -66.078701)
					(end 223.148652 -66.09207)
				)
			)
		)
	)
	(zone
		(layer "In5.Cu")
		(hatch none 0.5)
		(connect_pads
			(clearance 0)
		)
		(min_thickness 0.25)
		(keepout
			(tracks not_allowed)
			(vias allowed)
			(pads allowed)
			(copperpour not_allowed)
			(footprints allowed)
		)
		(placement
			(enabled no)
			(sheetname "")
		)
		(fill
			(thermal_gap 0.5)
			(thermal_bridge_width 0.5)
			(island_removal_mode 0)
		)
		(polygon
			(pts
				(arc
					(start 286.436562 -198.545704)
					(mid 285.887922 -199.094344)
					(end 286.436562 -199.642984)
				)
				(arc
					(start 287.83661 -199.642984)
					(mid 288.38525 -199.094344)
					(end 287.83661 -198.545704)
				)
				(arc
					(start 287.39211 -198.545704)
					(mid 287.38148 -198.58017)
					(end 287.377886 -198.616062)
				)
				(xy 287.377632 -198.62038) (xy 287.377632 -198.865744)
				(arc
					(start 287.377886 -198.870062)
					(mid 287.398326 -198.945959)
					(end 287.454086 -199.00138)
				)
				(arc
					(start 287.454086 -199.00138)
					(mid 288.229995 -199.110788)
					(end 287.447736 -199.156066)
				)
				(arc
					(start 287.447736 -199.156066)
					(mid 287.301691 -199.061707)
					(end 287.23336 -198.901812)
				)
				(xy 287.231836 -198.900288) (xy 287.231836 -198.878698) (xy 287.231582 -198.870062) (xy 287.231836 -198.865744)
				(xy 287.231836 -198.62038) (xy 287.231582 -198.616062) (xy 287.231836 -198.606918) (xy 287.231836 -198.585836)
				(arc
					(start 287.233106 -198.584312)
					(mid 287.235573 -198.564916)
					(end 287.239202 -198.545704)
				)
				(arc
					(start 287.046162 -198.545704)
					(mid 287.042555 -198.580801)
					(end 287.041336 -198.616062)
				)
				(xy 287.041336 -198.62038) (xy 287.041336 -198.865744) (xy 287.041336 -198.870062) (xy 287.041336 -198.878698)
				(xy 287.041336 -198.900288)
				(arc
					(start 287.039558 -198.901812)
					(mid 286.971326 -199.061631)
					(end 286.825436 -199.156066)
				)
				(arc
					(start 286.825436 -199.156066)
					(mid 286.043148 -199.110409)
					(end 286.819086 -199.001126)
				)
				(arc
					(start 286.819086 -199.001126)
					(mid 286.874651 -198.945793)
					(end 286.895032 -198.870062)
				)
				(xy 286.895032 -198.865744) (xy 286.895032 -198.62038) (xy 286.895032 -198.616062) (xy 286.895032 -198.603108)
				(xy 286.895032 -198.585836) (xy 286.895794 -198.585328) (xy 286.898842 -198.545704)
			)
		)
	)
	(zone
		(layer "In5.Cu")
		(hatch none 0.5)
		(connect_pads
			(clearance 0)
		)
		(min_thickness 0.25)
		(keepout
			(tracks not_allowed)
			(vias allowed)
			(pads allowed)
			(copperpour not_allowed)
			(footprints allowed)
		)
		(placement
			(enabled no)
			(sheetname "")
		)
		(fill
			(thermal_gap 0.5)
			(thermal_bridge_width 0.5)
			(island_removal_mode 0)
		)
		(polygon
			(pts
				(arc
					(start 418.724842 -248.115328)
					(mid 418.239829 -247.629934)
					(end 417.754562 -248.115074)
				)
				(xy 417.754562 -248.50852) (xy 418.114734 -248.50852)
				(arc
					(start 418.119052 -248.50852)
					(mid 418.152638 -248.494608)
					(end 418.16655 -248.461022)
				)
				(xy 418.166804 -248.456704)
				(arc
					(start 418.166804 -248.371614)
					(mid 418.239702 -247.848378)
					(end 418.3126 -248.371614)
				)
				(xy 418.3126 -248.456704) (xy 418.312854 -248.461022) (xy 418.3126 -248.468134) (xy 418.3126 -248.491248)
				(arc
					(start 418.31006 -248.494042)
					(mid 418.256118 -248.598088)
					(end 418.152072 -248.65203)
				)
				(xy 418.149278 -248.654824) (xy 418.126164 -248.654824) (xy 418.119052 -248.654824) (xy 418.114734 -248.654824)
				(xy 417.754562 -248.654824) (xy 417.754562 -248.845324) (xy 418.114734 -248.845324) (xy 418.119052 -248.84507)
				(xy 418.126164 -248.845324) (xy 418.149278 -248.845324)
				(arc
					(start 418.152072 -248.847864)
					(mid 418.256118 -248.901806)
					(end 418.31006 -249.005852)
				)
				(xy 418.3126 -249.008646) (xy 418.3126 -249.03176) (xy 418.312854 -249.038872) (xy 418.3126 -249.04319)
				(arc
					(start 418.3126 -249.128534)
					(mid 418.239702 -249.65177)
					(end 418.166804 -249.128534)
				)
				(xy 418.166804 -249.04319)
				(arc
					(start 418.16655 -249.038872)
					(mid 418.152638 -249.005286)
					(end 418.119052 -248.991374)
				)
				(xy 418.114734 -248.99112) (xy 417.754562 -248.99112)
				(arc
					(start 417.754562 -249.385074)
					(mid 418.239702 -249.870214)
					(end 418.724842 -249.385074)
				)
			)
		)
	)
	(zone
		(layer "In5.Cu")
		(hatch none 0.5)
		(connect_pads
			(clearance 0)
		)
		(min_thickness 0.25)
		(keepout
			(tracks not_allowed)
			(vias allowed)
			(pads allowed)
			(copperpour not_allowed)
			(footprints allowed)
		)
		(placement
			(enabled no)
			(sheetname "")
		)
		(fill
			(thermal_gap 0.5)
			(thermal_bridge_width 0.5)
			(island_removal_mode 0)
		)
		(polygon
			(pts
				(arc
					(start 32.994092 -18.11528)
					(mid 32.509079 -17.629886)
					(end 32.023812 -18.115026)
				)
				(arc
					(start 32.023812 -19.385026)
					(mid 32.508952 -19.870166)
					(end 32.994092 -19.385026)
				)
				(xy 32.994092 -18.991072) (xy 32.63392 -18.991072)
				(arc
					(start 32.629602 -18.991326)
					(mid 32.596016 -19.005238)
					(end 32.582104 -19.038824)
				)
				(xy 32.58185 -19.043142)
				(arc
					(start 32.58185 -19.128486)
					(mid 32.509074 -19.651722)
					(end 32.4358 -19.128486)
				)
				(xy 32.4358 -19.043142) (xy 32.4358 -19.038824) (xy 32.4358 -19.031712) (xy 32.4358 -19.008598)
				(arc
					(start 32.438594 -19.005804)
					(mid 32.492536 -18.901758)
					(end 32.596582 -18.847816)
				)
				(xy 32.599376 -18.845276) (xy 32.62249 -18.845276) (xy 32.629602 -18.845022) (xy 32.63392 -18.845276)
				(xy 32.994092 -18.845276) (xy 32.994092 -18.654776) (xy 32.63392 -18.654776) (xy 32.629602 -18.654776)
				(xy 32.62249 -18.654776) (xy 32.599376 -18.654776)
				(arc
					(start 32.596582 -18.651982)
					(mid 32.492536 -18.59804)
					(end 32.438594 -18.493994)
				)
				(xy 32.4358 -18.4912) (xy 32.4358 -18.468086) (xy 32.4358 -18.460974) (xy 32.4358 -18.456656)
				(arc
					(start 32.4358 -18.371566)
					(mid 32.508952 -17.84826)
					(end 32.582104 -18.371566)
				)
				(xy 32.582104 -18.456656)
				(arc
					(start 32.582104 -18.460974)
					(mid 32.596016 -18.49456)
					(end 32.629602 -18.508472)
				)
				(xy 32.63392 -18.508472) (xy 32.994092 -18.508472)
			)
		)
	)
	(zone
		(layer "In5.Cu")
		(hatch none 0.5)
		(connect_pads
			(clearance 0)
		)
		(min_thickness 0.25)
		(keepout
			(tracks not_allowed)
			(vias allowed)
			(pads allowed)
			(copperpour not_allowed)
			(footprints allowed)
		)
		(placement
			(enabled no)
			(sheetname "")
		)
		(fill
			(thermal_gap 0.5)
			(thermal_bridge_width 0.5)
			(island_removal_mode 0)
		)
		(polygon
			(pts
				(arc
					(start 354.231956 -131.951984)
					(mid 353.746562 -132.436997)
					(end 354.231702 -132.922264)
				)
				(xy 354.625148 -132.922264) (xy 354.625148 -132.605018)
				(arc
					(start 354.625148 -132.6007)
					(mid 354.598663 -132.536761)
					(end 354.534724 -132.510276)
				)
				(xy 354.530406 -132.510276)
				(arc
					(start 354.488242 -132.510276)
					(mid 353.964936 -132.437124)
					(end 354.488242 -132.363972)
				)
				(xy 354.530406 -132.363972) (xy 354.534724 -132.363972) (xy 354.542598 -132.363972) (xy 354.56495 -132.363972)
				(arc
					(start 354.566982 -132.366258)
					(mid 354.702061 -132.433363)
					(end 354.769166 -132.568442)
				)
				(xy 354.771452 -132.570474) (xy 354.771452 -132.592826) (xy 354.771452 -132.6007) (xy 354.771452 -132.605018)
				(xy 354.771452 -132.922264) (xy 354.961952 -132.922264) (xy 354.961952 -132.605272) (xy 354.961698 -132.600954)
				(xy 354.961952 -132.59308) (xy 354.961952 -132.570728)
				(arc
					(start 354.963984 -132.568696)
					(mid 355.031165 -132.433439)
					(end 355.166422 -132.366258)
				)
				(xy 355.168454 -132.363972) (xy 355.190806 -132.363972) (xy 355.19868 -132.363972) (xy 355.202998 -132.363972)
				(arc
					(start 355.245162 -132.363972)
					(mid 355.768468 -132.437124)
					(end 355.245162 -132.510276)
				)
				(xy 355.202998 -132.510276)
				(arc
					(start 355.19868 -132.510276)
					(mid 355.134561 -132.536835)
					(end 355.108002 -132.600954)
				)
				(xy 355.107748 -132.605272) (xy 355.107748 -132.922264)
				(arc
					(start 355.501702 -132.922264)
					(mid 355.986842 -132.437124)
					(end 355.501702 -131.951984)
				)
			)
		)
	)
	(zone
		(layer "In5.Cu")
		(hatch none 0.5)
		(connect_pads
			(clearance 0)
		)
		(min_thickness 0.25)
		(keepout
			(tracks not_allowed)
			(vias allowed)
			(pads allowed)
			(copperpour not_allowed)
			(footprints allowed)
		)
		(placement
			(enabled no)
			(sheetname "")
		)
		(fill
			(thermal_gap 0.5)
			(thermal_bridge_width 0.5)
			(island_removal_mode 0)
		)
		(polygon
			(pts
				(arc
					(start 96.094042 -248.115328)
					(mid 95.609029 -247.629934)
					(end 95.123762 -248.115074)
				)
				(arc
					(start 95.123762 -249.385074)
					(mid 95.608902 -249.870214)
					(end 96.094042 -249.385074)
				)
				(xy 96.094042 -248.99112) (xy 95.73387 -248.99112)
				(arc
					(start 95.729552 -248.991374)
					(mid 95.695966 -249.005286)
					(end 95.682054 -249.038872)
				)
				(xy 95.6818 -249.04319)
				(arc
					(start 95.6818 -249.128534)
					(mid 95.608902 -249.65177)
					(end 95.536004 -249.128534)
				)
				(xy 95.536004 -249.04319) (xy 95.53575 -249.038872) (xy 95.536004 -249.03176) (xy 95.536004 -249.008646)
				(arc
					(start 95.538544 -249.005852)
					(mid 95.592486 -248.901806)
					(end 95.696532 -248.847864)
				)
				(xy 95.699326 -248.845324) (xy 95.72244 -248.845324) (xy 95.729552 -248.84507) (xy 95.73387 -248.845324)
				(xy 96.094042 -248.845324) (xy 96.094042 -248.654824) (xy 95.73387 -248.654824) (xy 95.729552 -248.654824)
				(xy 95.72244 -248.654824) (xy 95.699326 -248.654824)
				(arc
					(start 95.696532 -248.65203)
					(mid 95.592486 -248.598088)
					(end 95.538544 -248.494042)
				)
				(xy 95.536004 -248.491248) (xy 95.536004 -248.468134) (xy 95.53575 -248.461022) (xy 95.536004 -248.456704)
				(arc
					(start 95.536004 -248.371614)
					(mid 95.608902 -247.848378)
					(end 95.6818 -248.371614)
				)
				(xy 95.6818 -248.456704)
				(arc
					(start 95.682054 -248.461022)
					(mid 95.695966 -248.494608)
					(end 95.729552 -248.50852)
				)
				(xy 95.73387 -248.50852) (xy 96.094042 -248.50852)
			)
		)
	)
	(zone
		(layer "In5.Cu")
		(hatch none 0.5)
		(connect_pads
			(clearance 0)
		)
		(min_thickness 0.25)
		(keepout
			(tracks not_allowed)
			(vias allowed)
			(pads allowed)
			(copperpour not_allowed)
			(footprints allowed)
		)
		(placement
			(enabled no)
			(sheetname "")
		)
		(fill
			(thermal_gap 0.5)
			(thermal_bridge_width 0.5)
			(island_removal_mode 0)
		)
		(polygon
			(pts
				(arc
					(start 32.994092 -248.115328)
					(mid 32.509079 -247.629934)
					(end 32.023812 -248.115074)
				)
				(arc
					(start 32.023812 -249.385074)
					(mid 32.508952 -249.870214)
					(end 32.994092 -249.385074)
				)
				(xy 32.994092 -248.99112) (xy 32.63392 -248.99112)
				(arc
					(start 32.629602 -248.991374)
					(mid 32.596016 -249.005286)
					(end 32.582104 -249.038872)
				)
				(xy 32.58185 -249.04319)
				(arc
					(start 32.58185 -249.128534)
					(mid 32.509074 -249.65177)
					(end 32.4358 -249.128534)
				)
				(xy 32.4358 -249.04319) (xy 32.4358 -249.038872) (xy 32.4358 -249.03176) (xy 32.4358 -249.008646)
				(arc
					(start 32.438594 -249.005852)
					(mid 32.492536 -248.901806)
					(end 32.596582 -248.847864)
				)
				(xy 32.599376 -248.845324) (xy 32.62249 -248.845324) (xy 32.629602 -248.84507) (xy 32.63392 -248.845324)
				(xy 32.994092 -248.845324) (xy 32.994092 -248.654824) (xy 32.63392 -248.654824) (xy 32.629602 -248.654824)
				(xy 32.62249 -248.654824) (xy 32.599376 -248.654824)
				(arc
					(start 32.596582 -248.65203)
					(mid 32.492536 -248.598088)
					(end 32.438594 -248.494042)
				)
				(xy 32.4358 -248.491248) (xy 32.4358 -248.468134) (xy 32.4358 -248.461022) (xy 32.4358 -248.456704)
				(arc
					(start 32.4358 -248.371614)
					(mid 32.508952 -247.848308)
					(end 32.582104 -248.371614)
				)
				(xy 32.582104 -248.456704)
				(arc
					(start 32.582104 -248.461022)
					(mid 32.596016 -248.494608)
					(end 32.629602 -248.50852)
				)
				(xy 32.63392 -248.50852) (xy 32.994092 -248.50852)
			)
		)
	)
	(zone
		(layer "In5.Cu")
		(hatch none 0.5)
		(connect_pads
			(clearance 0)
		)
		(min_thickness 0.25)
		(keepout
			(tracks not_allowed)
			(vias allowed)
			(pads allowed)
			(copperpour not_allowed)
			(footprints allowed)
		)
		(placement
			(enabled no)
			(sheetname "")
		)
		(fill
			(thermal_gap 0.5)
			(thermal_bridge_width 0.5)
			(island_removal_mode 0)
		)
		(polygon
			(pts
				(arc
					(start 159.193992 -248.115074)
					(mid 158.708852 -247.629934)
					(end 158.223712 -248.115074)
				)
				(arc
					(start 158.223712 -249.38482)
					(mid 158.708725 -249.870214)
					(end 159.193992 -249.385074)
				)
				(xy 159.193992 -248.99112) (xy 158.83382 -248.99112)
				(arc
					(start 158.829502 -248.991374)
					(mid 158.795916 -249.005286)
					(end 158.782004 -249.038872)
				)
				(xy 158.782004 -249.04319)
				(arc
					(start 158.782004 -249.128534)
					(mid 158.708852 -249.65184)
					(end 158.6357 -249.128534)
				)
				(xy 158.6357 -249.04319) (xy 158.6357 -249.038872) (xy 158.6357 -249.03176) (xy 158.6357 -249.008646)
				(arc
					(start 158.638494 -249.005852)
					(mid 158.692436 -248.901806)
					(end 158.796482 -248.847864)
				)
				(xy 158.799276 -248.845324) (xy 158.82239 -248.845324) (xy 158.829502 -248.84507) (xy 158.83382 -248.845324)
				(xy 159.193992 -248.845324) (xy 159.193992 -248.654824) (xy 158.83382 -248.654824) (xy 158.829502 -248.654824)
				(xy 158.82239 -248.654824) (xy 158.799276 -248.654824)
				(arc
					(start 158.796482 -248.65203)
					(mid 158.692436 -248.598088)
					(end 158.638494 -248.494042)
				)
				(xy 158.6357 -248.491248) (xy 158.6357 -248.468134) (xy 158.6357 -248.461022) (xy 158.6357 -248.456704)
				(arc
					(start 158.6357 -248.371614)
					(mid 158.708852 -247.848308)
					(end 158.782004 -248.371614)
				)
				(xy 158.782004 -248.456704)
				(arc
					(start 158.782004 -248.461022)
					(mid 158.795916 -248.494608)
					(end 158.829502 -248.50852)
				)
				(xy 158.83382 -248.50852) (xy 159.193992 -248.50852)
			)
		)
	)
	(zone
		(net "P3V3_IN")
		(layer "In5.Cu")
		(hatch none 0.5)
		(connect_pads
			(clearance 0.5)
		)
		(min_thickness 0.25)
		(fill yes
			(thermal_gap 0.5)
			(thermal_bridge_width 0.5)
			(island_removal_mode 0)
		)
		(polygon
			(pts
				(xy 284.3784 -333.6036) (xy 285.2166 -333.6036) (xy 285.4198 -333.8068) (xy 285.4198 -335.5086)
				(xy 285.0642 -335.8642) (xy 283.3624 -335.8642) (xy 282.9306 -336.296) (xy 282.9306 -338.7344) (xy 283.3116 -339.1154)
				(xy 287.1216 -339.1154) (xy 287.6804 -338.5566) (xy 287.6804 -333.2734) (xy 288.092896 -332.860904)
				(xy 294.610536 -332.860904) (xy 294.625014 -332.846426) (xy 302.425354 -332.846426) (xy 302.636428 -333.0575)
				(xy 302.636428 -342.436196) (xy 302.790606 -342.590374) (xy 303.587658 -342.590374) (xy 303.74082 -342.437212)
				(xy 303.74082 -341.357204) (xy 303.919382 -341.178642) (xy 306.120292 -341.178642) (xy 306.298854 -341.357204)
				(xy 306.298854 -342.403684) (xy 306.485544 -342.590374) (xy 307.202078 -342.590374) (xy 307.492908 -342.299544)
				(xy 307.492908 -332.97622) (xy 307.88737 -332.581758) (xy 308.239922 -332.581758) (xy 310.68772 -332.581758)
				(xy 311.02554 -332.919578) (xy 311.02554 -343.151206) (xy 311.155334 -343.281) (xy 311.4294 -343.281)
				(xy 312.114692 -343.281) (xy 312.36539 -343.030302) (xy 312.36539 -341.68207) (xy 312.59526 -341.4522)
				(xy 313.6646 -341.4522) (xy 313.9186 -341.7062) (xy 313.9186 -343.0524) (xy 313.9186 -343.4334)
				(xy 310.769 -346.583) (xy 287.02 -370.332) (xy 281.813 -375.539) (xy 281.813 -377.444) (xy 282.067 -377.698)
				(xy 284.665166 -377.698) (xy 316.2808 -346.082366) (xy 316.2808 -329.4634) (xy 315.7728 -328.9554)
				(xy 314.549536 -328.9554) (xy 294.389302 -328.952098) (xy 293.18204 -327.744836) (xy 293.18204 -327.7362)
				(xy 287.8074 -327.7362) (xy 284.1752 -331.3684) (xy 284.1752 -333.4004)
			)
		)
	)
	(zone
		(layer "In5.Cu")
		(hatch none 0.5)
		(connect_pads
			(clearance 0)
		)
		(min_thickness 0.25)
		(keepout
			(tracks not_allowed)
			(vias allowed)
			(pads allowed)
			(copperpour not_allowed)
			(footprints allowed)
		)
		(placement
			(enabled no)
			(sheetname "")
		)
		(fill
			(thermal_gap 0.5)
			(thermal_bridge_width 0.5)
			(island_removal_mode 0)
		)
		(polygon
			(pts
				(arc
					(start 448.8815 -16.95196)
					(mid 448.39636 -17.4371)
					(end 448.8815 -17.92224)
				)
				(xy 449.2752 -17.92224) (xy 449.2752 -17.581118)
				(arc
					(start 449.274946 -17.5768)
					(mid 449.255455 -17.529743)
					(end 449.208398 -17.510252)
				)
				(xy 449.20408 -17.510252)
				(arc
					(start 449.13804 -17.510252)
					(mid 448.614734 -17.4371)
					(end 449.13804 -17.363948)
				)
				(xy 449.20408 -17.363948) (xy 449.208398 -17.363948) (xy 449.215764 -17.363948) (xy 449.238624 -17.363948)
				(arc
					(start 449.24091 -17.366488)
					(mid 449.358878 -17.42632)
					(end 449.41871 -17.544288)
				)
				(xy 449.420996 -17.546574) (xy 449.420996 -17.569434) (xy 449.42125 -17.5768) (xy 449.420996 -17.581118)
				(xy 449.420996 -17.92224) (xy 449.611496 -17.92224) (xy 449.611496 -17.581372) (xy 449.611496 -17.577054)
				(xy 449.611496 -17.569688) (xy 449.611496 -17.546828)
				(arc
					(start 449.614036 -17.544542)
					(mid 449.673945 -17.426397)
					(end 449.79209 -17.366488)
				)
				(xy 449.794376 -17.363948) (xy 449.817236 -17.363948) (xy 449.824602 -17.363948) (xy 449.82892 -17.363948)
				(arc
					(start 449.89496 -17.363948)
					(mid 450.418266 -17.4371)
					(end 449.89496 -17.510252)
				)
				(xy 449.82892 -17.510252)
				(arc
					(start 449.824602 -17.510252)
					(mid 449.777366 -17.529818)
					(end 449.7578 -17.577054)
				)
				(xy 449.7578 -17.581372) (xy 449.7578 -17.92224)
				(arc
					(start 450.151246 -17.92224)
					(mid 450.63664 -17.437227)
					(end 450.1515 -16.95196)
				)
			)
		)
	)
	(zone
		(layer "In5.Cu")
		(hatch none 0.5)
		(connect_pads
			(clearance 0)
		)
		(min_thickness 0.25)
		(keepout
			(tracks not_allowed)
			(vias allowed)
			(pads allowed)
			(copperpour not_allowed)
			(footprints allowed)
		)
		(placement
			(enabled no)
			(sheetname "")
		)
		(fill
			(thermal_gap 0.5)
			(thermal_bridge_width 0.5)
			(island_removal_mode 0)
		)
		(polygon
			(pts
				(arc
					(start 286.436562 -194.945762)
					(mid 285.887922 -195.494402)
					(end 286.436562 -196.043042)
				)
				(arc
					(start 287.83661 -196.043042)
					(mid 288.38525 -195.494402)
					(end 287.83661 -194.945762)
				)
				(arc
					(start 287.361376 -194.945762)
					(mid 287.37205 -195.008542)
					(end 287.377378 -195.072)
				)
				(xy 287.377632 -195.072508) (xy 287.377632 -195.089018) (xy 287.377886 -195.102734) (xy 287.377632 -195.107052)
				(xy 287.377632 -195.327016)
				(arc
					(start 287.377886 -195.331334)
					(mid 287.398219 -195.388282)
					(end 287.450022 -195.419472)
				)
				(arc
					(start 287.450022 -195.419472)
					(mid 288.230344 -195.49492)
					(end 287.449768 -195.5673)
				)
				(xy 287.437576 -195.5673)
				(arc
					(start 287.435544 -195.565268)
					(mid 287.30082 -195.498316)
					(end 287.233868 -195.363592)
				)
				(xy 287.231836 -195.36156) (xy 287.231836 -195.338954) (xy 287.231582 -195.331334) (xy 287.231836 -195.327016)
				(xy 287.231836 -195.107052)
				(arc
					(start 287.231582 -195.102734)
					(mid 287.226333 -195.023563)
					(end 287.210754 -194.945762)
				)
				(arc
					(start 287.010348 -194.945762)
					(mid 287.03015 -195.007459)
					(end 287.040066 -195.071492)
				)
				(xy 287.041336 -195.072508) (xy 287.041336 -195.092574) (xy 287.041336 -195.102734) (xy 287.041336 -195.107052)
				(xy 287.041336 -195.327016) (xy 287.041336 -195.331334) (xy 287.041336 -195.338954) (xy 287.041336 -195.36156)
				(arc
					(start 287.03905 -195.363592)
					(mid 286.972098 -195.498316)
					(end 286.837374 -195.565268)
				)
				(xy 286.835342 -195.5673)
				(arc
					(start 286.823404 -195.5673)
					(mid 286.042865 -195.49492)
					(end 286.82315 -195.419472)
				)
				(arc
					(start 286.82315 -195.419472)
					(mid 286.874815 -195.388216)
					(end 286.895032 -195.331334)
				)
				(xy 286.895032 -195.327016) (xy 286.895032 -195.107052)
				(arc
					(start 286.895032 -195.102734)
					(mid 286.881952 -195.020198)
					(end 286.843978 -194.945762)
				)
			)
		)
	)
	(zone
		(layer "In5.Cu")
		(hatch none 0.5)
		(connect_pads
			(clearance 0)
		)
		(min_thickness 0.25)
		(keepout
			(tracks not_allowed)
			(vias allowed)
			(pads allowed)
			(copperpour not_allowed)
			(footprints allowed)
		)
		(placement
			(enabled no)
			(sheetname "")
		)
		(fill
			(thermal_gap 0.5)
			(thermal_bridge_width 0.5)
			(island_removal_mode 0)
		)
		(polygon
			(pts
				(arc
					(start 286.436562 -220.145864)
					(mid 285.887922 -220.694504)
					(end 286.436562 -221.243144)
				)
				(arc
					(start 286.903922 -221.243144)
					(mid 286.898713 -221.203255)
					(end 286.895794 -221.163134)
				)
				(xy 286.895032 -221.162626) (xy 286.895032 -221.145862) (xy 286.895032 -221.1324) (xy 286.895032 -221.128082)
				(xy 286.895032 -220.882718)
				(arc
					(start 286.895032 -220.8784)
					(mid 286.874989 -220.814858)
					(end 286.822134 -220.77426)
				)
				(arc
					(start 286.822134 -220.77426)
					(mid 286.042907 -220.6901)
					(end 286.823912 -220.6244)
				)
				(arc
					(start 286.823912 -220.6244)
					(mid 286.968675 -220.699271)
					(end 287.039304 -220.846142)
				)
				(xy 287.041336 -220.848174) (xy 287.041336 -220.870272) (xy 287.041336 -220.8784) (xy 287.041336 -220.882718)
				(xy 287.041336 -221.128082)
				(arc
					(start 287.041336 -221.1324)
					(mid 287.044147 -221.188052)
					(end 287.052512 -221.243144)
				)
				(arc
					(start 287.2486 -221.243144)
					(mid 287.238539 -221.203955)
					(end 287.232852 -221.163896)
				)
				(xy 287.231836 -221.162626) (xy 287.231836 -221.142052) (xy 287.231582 -221.1324) (xy 287.231836 -221.128082)
				(xy 287.231836 -220.882718) (xy 287.231582 -220.8784) (xy 287.231836 -220.870272) (xy 287.231836 -220.848174)
				(arc
					(start 287.233614 -220.846142)
					(mid 287.304347 -220.699197)
					(end 287.44926 -220.6244)
				)
				(arc
					(start 287.44926 -220.6244)
					(mid 288.23027 -220.6901)
					(end 287.451038 -220.77426)
				)
				(arc
					(start 287.451038 -220.77426)
					(mid 287.39802 -220.814775)
					(end 287.377886 -220.8784)
				)
				(xy 287.377632 -220.882718) (xy 287.377632 -221.128082)
				(arc
					(start 287.377886 -221.1324)
					(mid 287.385459 -221.189723)
					(end 287.407604 -221.243144)
				)
				(arc
					(start 287.83661 -221.243144)
					(mid 288.38525 -220.694504)
					(end 287.83661 -220.145864)
				)
			)
		)
	)
	(zone
		(layer "In5.Cu")
		(hatch none 0.5)
		(connect_pads
			(clearance 0)
		)
		(min_thickness 0.25)
		(keepout
			(tracks not_allowed)
			(vias allowed)
			(pads allowed)
			(copperpour not_allowed)
			(footprints allowed)
		)
		(placement
			(enabled no)
			(sheetname "")
		)
		(fill
			(thermal_gap 0.5)
			(thermal_bridge_width 0.5)
			(island_removal_mode 0)
		)
		(polygon
			(pts
				(arc
					(start 417.331906 -131.951984)
					(mid 416.846512 -132.436997)
					(end 417.331652 -132.922264)
				)
				(xy 417.725352 -132.922264) (xy 417.725352 -132.643118)
				(arc
					(start 417.725098 -132.6388)
					(mid 417.687454 -132.54792)
					(end 417.596574 -132.510276)
				)
				(xy 417.592256 -132.510276)
				(arc
					(start 417.588192 -132.510276)
					(mid 417.064886 -132.437124)
					(end 417.588192 -132.363972)
				)
				(xy 417.592256 -132.363972) (xy 417.596574 -132.363972) (xy 417.604956 -132.363972) (xy 417.6268 -132.363972)
				(arc
					(start 417.628578 -132.36575)
					(mid 417.790971 -132.444403)
					(end 417.869624 -132.606796)
				)
				(xy 417.871148 -132.608574) (xy 417.871148 -132.630418) (xy 417.871402 -132.6388) (xy 417.871148 -132.643118)
				(xy 417.871148 -132.922264) (xy 418.061648 -132.922264) (xy 418.061648 -132.643118) (xy 418.061648 -132.6388)
				(xy 418.061648 -132.630418) (xy 418.061648 -132.608574)
				(arc
					(start 418.063426 -132.606796)
					(mid 418.142079 -132.444403)
					(end 418.304472 -132.36575)
				)
				(xy 418.30625 -132.363972) (xy 418.328094 -132.363972) (xy 418.336476 -132.363972) (xy 418.340794 -132.363972)
				(arc
					(start 418.345112 -132.363972)
					(mid 418.868418 -132.437124)
					(end 418.345112 -132.510276)
				)
				(xy 418.340794 -132.510276)
				(arc
					(start 418.336476 -132.510276)
					(mid 418.245596 -132.54792)
					(end 418.207952 -132.6388)
				)
				(xy 418.207952 -132.643118) (xy 418.207952 -132.922264)
				(arc
					(start 418.601652 -132.922264)
					(mid 419.086792 -132.437124)
					(end 418.601652 -131.951984)
				)
			)
		)
	)
	(zone
		(layer "In5.Cu")
		(hatch none 0.5)
		(connect_pads
			(clearance 0)
		)
		(min_thickness 0.25)
		(keepout
			(tracks not_allowed)
			(vias allowed)
			(pads allowed)
			(copperpour not_allowed)
			(footprints allowed)
		)
		(placement
			(enabled no)
			(sheetname "")
		)
		(fill
			(thermal_gap 0.5)
			(thermal_bridge_width 0.5)
			(island_removal_mode 0)
		)
		(polygon
			(pts
				(arc
					(start 285.436564 -221.945708)
					(mid 284.887924 -222.494348)
					(end 285.436564 -223.042988)
				)
				(arc
					(start 285.903416 -223.042988)
					(mid 285.898562 -223.004865)
					(end 285.895796 -222.966534)
				)
				(xy 285.895288 -222.966026) (xy 285.895288 -222.949008) (xy 285.895034 -222.9358) (xy 285.895288 -222.931482)
				(xy 285.895288 -222.686118)
				(arc
					(start 285.895034 -222.6818)
					(mid 285.874984 -222.617136)
					(end 285.821882 -222.57512)
				)
				(arc
					(start 285.821882 -222.57512)
					(mid 285.042864 -222.488141)
					(end 285.824168 -222.424752)
				)
				(arc
					(start 285.824168 -222.424752)
					(mid 285.969103 -222.501586)
					(end 286.039306 -222.649796)
				)
				(xy 286.041084 -222.651574) (xy 286.041084 -222.673672) (xy 286.041338 -222.6818) (xy 286.041084 -222.686118)
				(xy 286.041084 -222.931482)
				(arc
					(start 286.041338 -222.9358)
					(mid 286.043938 -222.989647)
					(end 286.051752 -223.042988)
				)
				(arc
					(start 286.24784 -223.042988)
					(mid 286.23834 -223.00554)
					(end 286.232854 -222.967296)
				)
				(xy 286.231584 -222.966026) (xy 286.231584 -222.945452) (xy 286.231584 -222.9358) (xy 286.231584 -222.931482)
				(xy 286.231584 -222.686118) (xy 286.231584 -222.6818) (xy 286.231584 -222.673672) (xy 286.231584 -222.651574)
				(arc
					(start 286.233616 -222.649796)
					(mid 286.304011 -222.501597)
					(end 286.449008 -222.424752)
				)
				(arc
					(start 286.449008 -222.424752)
					(mid 287.230325 -222.488141)
					(end 286.451294 -222.57512)
				)
				(arc
					(start 286.451294 -222.57512)
					(mid 286.398047 -222.617067)
					(end 286.377888 -222.6818)
				)
				(xy 286.377888 -222.686118) (xy 286.377888 -222.931482)
				(arc
					(start 286.377888 -222.9358)
					(mid 286.385014 -222.99123)
					(end 286.406082 -223.042988)
				)
				(arc
					(start 286.836612 -223.042988)
					(mid 287.385252 -222.494348)
					(end 286.836612 -221.945708)
				)
			)
		)
	)
	(zone
		(layer "In5.Cu")
		(hatch none 0.5)
		(connect_pads
			(clearance 0)
		)
		(min_thickness 0.25)
		(keepout
			(tracks not_allowed)
			(vias allowed)
			(pads allowed)
			(copperpour not_allowed)
			(footprints allowed)
		)
		(placement
			(enabled no)
			(sheetname "")
		)
		(fill
			(thermal_gap 0.5)
			(thermal_bridge_width 0.5)
			(island_removal_mode 0)
		)
		(polygon
			(pts
				(arc
					(start 285.436564 -232.745788)
					(mid 284.887924 -233.294428)
					(end 285.436564 -233.843068)
				)
				(arc
					(start 286.836612 -233.843068)
					(mid 287.385252 -233.294428)
					(end 286.836612 -232.745788)
				)
				(arc
					(start 286.361378 -232.745788)
					(mid 286.372052 -232.808568)
					(end 286.37738 -232.872026)
				)
				(xy 286.377888 -232.872534) (xy 286.377888 -232.889044) (xy 286.377888 -232.90276) (xy 286.377888 -232.907078)
				(xy 286.377888 -233.127042)
				(arc
					(start 286.377888 -233.13136)
					(mid 286.398221 -233.188308)
					(end 286.450024 -233.219498)
				)
				(arc
					(start 286.450024 -233.219498)
					(mid 287.230346 -233.294822)
					(end 286.44977 -233.36758)
				)
				(xy 286.437578 -233.36758)
				(arc
					(start 286.435546 -233.365294)
					(mid 286.300822 -233.298342)
					(end 286.23387 -233.163618)
				)
				(xy 286.231584 -233.161586) (xy 286.231584 -233.13898) (xy 286.231584 -233.13136) (xy 286.231584 -233.127042)
				(xy 286.231584 -232.907078)
				(arc
					(start 286.231584 -232.90276)
					(mid 286.226335 -232.823589)
					(end 286.210756 -232.745788)
				)
				(arc
					(start 286.01035 -232.745788)
					(mid 286.030152 -232.807485)
					(end 286.040068 -232.871518)
				)
				(xy 286.041084 -232.872534) (xy 286.041084 -232.8926) (xy 286.041338 -232.90276) (xy 286.041084 -232.907078)
				(xy 286.041084 -233.127042) (xy 286.041338 -233.13136) (xy 286.041084 -233.13898) (xy 286.041084 -233.161586)
				(arc
					(start 286.039052 -233.163618)
					(mid 285.9721 -233.298342)
					(end 285.837376 -233.365294)
				)
				(xy 285.835344 -233.36758)
				(arc
					(start 285.823406 -233.36758)
					(mid 285.042819 -233.294822)
					(end 285.823152 -233.219498)
				)
				(arc
					(start 285.823152 -233.219498)
					(mid 285.874817 -233.188242)
					(end 285.895034 -233.13136)
				)
				(xy 285.895288 -233.127042) (xy 285.895288 -232.907078)
				(arc
					(start 285.895034 -232.90276)
					(mid 285.881954 -232.820224)
					(end 285.84398 -232.745788)
				)
			)
		)
	)
	(zone
		(layer "In5.Cu")
		(hatch none 0.5)
		(connect_pads
			(clearance 0)
		)
		(min_thickness 0.25)
		(keepout
			(tracks not_allowed)
			(vias allowed)
			(pads allowed)
			(copperpour not_allowed)
			(footprints allowed)
		)
		(placement
			(enabled no)
			(sheetname "")
		)
		(fill
			(thermal_gap 0.5)
			(thermal_bridge_width 0.5)
			(island_removal_mode 0)
		)
		(polygon
			(pts
				(arc
					(start 285.436564 -236.34573)
					(mid 284.887924 -236.89437)
					(end 285.436564 -237.44301)
				)
				(arc
					(start 286.836612 -237.44301)
					(mid 287.385252 -236.89437)
					(end 286.836612 -236.34573)
				)
				(arc
					(start 286.361378 -236.34573)
					(mid 286.372052 -236.40851)
					(end 286.37738 -236.471968)
				)
				(xy 286.377888 -236.472476) (xy 286.377888 -236.488986) (xy 286.377888 -236.502702) (xy 286.377888 -236.50702)
				(xy 286.377888 -236.726984)
				(arc
					(start 286.377888 -236.731302)
					(mid 286.398221 -236.78825)
					(end 286.450024 -236.81944)
				)
				(arc
					(start 286.450024 -236.81944)
					(mid 287.230346 -236.894888)
					(end 286.44977 -236.967268)
				)
				(xy 286.437578 -236.967268)
				(arc
					(start 286.435546 -236.965236)
					(mid 286.300822 -236.898284)
					(end 286.23387 -236.76356)
				)
				(xy 286.231584 -236.761528) (xy 286.231584 -236.738922) (xy 286.231584 -236.731302) (xy 286.231584 -236.726984)
				(xy 286.231584 -236.50702)
				(arc
					(start 286.231584 -236.502702)
					(mid 286.226335 -236.423531)
					(end 286.210756 -236.34573)
				)
				(arc
					(start 286.01035 -236.34573)
					(mid 286.030152 -236.407427)
					(end 286.040068 -236.47146)
				)
				(xy 286.041084 -236.472476) (xy 286.041084 -236.492542) (xy 286.041338 -236.502702) (xy 286.041084 -236.50702)
				(xy 286.041084 -236.726984) (xy 286.041338 -236.731302) (xy 286.041084 -236.738922) (xy 286.041084 -236.761528)
				(arc
					(start 286.039052 -236.76356)
					(mid 285.9721 -236.898284)
					(end 285.837376 -236.965236)
				)
				(xy 285.835344 -236.967268)
				(arc
					(start 285.823406 -236.967268)
					(mid 285.042867 -236.894888)
					(end 285.823152 -236.81944)
				)
				(arc
					(start 285.823152 -236.81944)
					(mid 285.874817 -236.788184)
					(end 285.895034 -236.731302)
				)
				(xy 285.895288 -236.726984) (xy 285.895288 -236.50702)
				(arc
					(start 285.895034 -236.502702)
					(mid 285.881954 -236.420166)
					(end 285.84398 -236.34573)
				)
			)
		)
	)
	(zone
		(layer "In5.Cu")
		(hatch none 0.5)
		(connect_pads
			(clearance 0)
		)
		(min_thickness 0.25)
		(keepout
			(tracks not_allowed)
			(vias allowed)
			(pads allowed)
			(copperpour not_allowed)
			(footprints allowed)
		)
		(placement
			(enabled no)
			(sheetname "")
		)
		(fill
			(thermal_gap 0.5)
			(thermal_bridge_width 0.5)
			(island_removal_mode 0)
		)
		(polygon
			(pts
				(arc
					(start 32.994092 -133.11505)
					(mid 32.508952 -132.62991)
					(end 32.023812 -133.11505)
				)
				(arc
					(start 32.023812 -134.384796)
					(mid 32.508825 -134.87019)
					(end 32.994092 -134.38505)
				)
				(xy 32.994092 -133.991096) (xy 32.63392 -133.991096)
				(arc
					(start 32.629602 -133.99135)
					(mid 32.596016 -134.005262)
					(end 32.582104 -134.038848)
				)
				(xy 32.58185 -134.043166)
				(arc
					(start 32.58185 -134.12851)
					(mid 32.509074 -134.651746)
					(end 32.4358 -134.12851)
				)
				(xy 32.4358 -134.043166) (xy 32.4358 -134.038848) (xy 32.4358 -134.031736) (xy 32.4358 -134.008622)
				(arc
					(start 32.438594 -134.005828)
					(mid 32.492536 -133.901782)
					(end 32.596582 -133.84784)
				)
				(xy 32.599376 -133.8453) (xy 32.62249 -133.8453) (xy 32.629602 -133.845046) (xy 32.63392 -133.8453)
				(xy 32.994092 -133.8453) (xy 32.994092 -133.6548) (xy 32.63392 -133.6548) (xy 32.629602 -133.6548)
				(xy 32.62249 -133.6548) (xy 32.599376 -133.6548)
				(arc
					(start 32.596582 -133.652006)
					(mid 32.492536 -133.598064)
					(end 32.438594 -133.494018)
				)
				(xy 32.4358 -133.491224) (xy 32.4358 -133.46811) (xy 32.4358 -133.460998) (xy 32.4358 -133.45668)
				(arc
					(start 32.4358 -133.37159)
					(mid 32.508952 -132.848284)
					(end 32.582104 -133.37159)
				)
				(xy 32.582104 -133.45668)
				(arc
					(start 32.582104 -133.460998)
					(mid 32.596016 -133.494584)
					(end 32.629602 -133.508496)
				)
				(xy 32.63392 -133.508496) (xy 32.994092 -133.508496)
			)
		)
	)
	(zone
		(layer "In5.Cu")
		(hatch none 0.5)
		(connect_pads
			(clearance 0)
		)
		(min_thickness 0.25)
		(keepout
			(tracks not_allowed)
			(vias allowed)
			(pads allowed)
			(copperpour not_allowed)
			(footprints allowed)
		)
		(placement
			(enabled no)
			(sheetname "")
		)
		(fill
			(thermal_gap 0.5)
			(thermal_bridge_width 0.5)
			(island_removal_mode 0)
		)
		(polygon
			(pts
				(arc
					(start 190.744094 -18.11528)
					(mid 190.259081 -17.629886)
					(end 189.773814 -18.115026)
				)
				(arc
					(start 189.773814 -19.385026)
					(mid 190.258954 -19.870166)
					(end 190.744094 -19.385026)
				)
				(xy 190.744094 -18.991072) (xy 190.383922 -18.991072)
				(arc
					(start 190.379604 -18.991326)
					(mid 190.346018 -19.005238)
					(end 190.332106 -19.038824)
				)
				(xy 190.331852 -19.043142)
				(arc
					(start 190.331852 -19.128486)
					(mid 190.258954 -19.651722)
					(end 190.186056 -19.128486)
				)
				(xy 190.186056 -19.043142) (xy 190.185802 -19.038824) (xy 190.186056 -19.031712) (xy 190.186056 -19.008598)
				(arc
					(start 190.188596 -19.005804)
					(mid 190.242538 -18.901758)
					(end 190.346584 -18.847816)
				)
				(xy 190.349378 -18.845276) (xy 190.372492 -18.845276) (xy 190.379604 -18.845022) (xy 190.383922 -18.845276)
				(xy 190.744094 -18.845276) (xy 190.744094 -18.654776) (xy 190.383922 -18.654776) (xy 190.379604 -18.654776)
				(xy 190.372492 -18.654776) (xy 190.349378 -18.654776)
				(arc
					(start 190.346584 -18.651982)
					(mid 190.242538 -18.59804)
					(end 190.188596 -18.493994)
				)
				(xy 190.186056 -18.4912) (xy 190.186056 -18.468086) (xy 190.185802 -18.460974) (xy 190.186056 -18.456656)
				(arc
					(start 190.186056 -18.371566)
					(mid 190.258954 -17.84833)
					(end 190.331852 -18.371566)
				)
				(xy 190.331852 -18.456656)
				(arc
					(start 190.332106 -18.460974)
					(mid 190.346018 -18.49456)
					(end 190.379604 -18.508472)
				)
				(xy 190.383922 -18.508472) (xy 190.744094 -18.508472)
			)
		)
	)
	(zone
		(net "P12V_IN")
		(layer "In5.Cu")
		(hatch none 0.5)
		(connect_pads
			(clearance 0.5)
		)
		(min_thickness 0.25)
		(fill yes
			(thermal_gap 0.5)
			(thermal_bridge_width 0.5)
			(island_removal_mode 0)
		)
		(polygon
			(pts
				(xy 274.1168 -69.3928) (xy 274.1168 -99.06) (xy 273.6088 -99.568) (xy 253.746 -99.568) (xy 253.5682 -99.568)
				(xy 236.855 -82.8548) (xy 236.855 -69.9008) (xy 236.855 -63.9318) (xy 237.0074 -63.7794) (xy 273.8374 -63.7794)
				(xy 274.1168 -64.0588)
			)
		)
	)
	(zone
		(layer "In5.Cu")
		(hatch none 0.5)
		(connect_pads
			(clearance 0)
		)
		(min_thickness 0.25)
		(keepout
			(tracks not_allowed)
			(vias allowed)
			(pads allowed)
			(copperpour not_allowed)
			(footprints allowed)
		)
		(placement
			(enabled no)
			(sheetname "")
		)
		(fill
			(thermal_gap 0.5)
			(thermal_bridge_width 0.5)
			(island_removal_mode 0)
		)
		(polygon
			(pts
				(arc
					(start 285.436564 -203.945744)
					(mid 284.887924 -204.494384)
					(end 285.436564 -205.043024)
				)
				(arc
					(start 286.836612 -205.043024)
					(mid 287.385252 -204.494384)
					(end 286.836612 -203.945744)
				)
				(arc
					(start 286.392112 -203.945744)
					(mid 286.381482 -203.98021)
					(end 286.377888 -204.016102)
				)
				(xy 286.377888 -204.02042) (xy 286.377888 -204.265784)
				(arc
					(start 286.377888 -204.270102)
					(mid 286.398328 -204.345999)
					(end 286.454088 -204.40142)
				)
				(arc
					(start 286.454088 -204.40142)
					(mid 287.229997 -204.510828)
					(end 286.447738 -204.556106)
				)
				(arc
					(start 286.447738 -204.556106)
					(mid 286.301693 -204.461747)
					(end 286.233362 -204.301852)
				)
				(xy 286.231584 -204.300328) (xy 286.231584 -204.278738) (xy 286.231584 -204.270102) (xy 286.231584 -204.265784)
				(xy 286.231584 -204.02042) (xy 286.231584 -204.016102) (xy 286.231584 -204.006958) (xy 286.231584 -203.985876)
				(arc
					(start 286.233108 -203.984352)
					(mid 286.235575 -203.964956)
					(end 286.239204 -203.945744)
				)
				(arc
					(start 286.046164 -203.945744)
					(mid 286.042557 -203.980841)
					(end 286.041338 -204.016102)
				)
				(xy 286.041084 -204.02042) (xy 286.041084 -204.265784) (xy 286.041338 -204.270102) (xy 286.041084 -204.278738)
				(xy 286.041084 -204.300328)
				(arc
					(start 286.03956 -204.301852)
					(mid 285.971328 -204.461671)
					(end 285.825438 -204.556106)
				)
				(arc
					(start 285.825438 -204.556106)
					(mid 285.04315 -204.510449)
					(end 285.819088 -204.401166)
				)
				(arc
					(start 285.819088 -204.401166)
					(mid 285.874653 -204.345833)
					(end 285.895034 -204.270102)
				)
				(xy 285.895288 -204.265784) (xy 285.895288 -204.02042) (xy 285.895034 -204.016102) (xy 285.895288 -204.003148)
				(xy 285.895288 -203.985876) (xy 285.895796 -203.985368) (xy 285.898844 -203.945744)
			)
		)
	)
	(zone
		(layer "In5.Cu")
		(hatch none 0.5)
		(connect_pads
			(clearance 0)
		)
		(min_thickness 0.25)
		(keepout
			(tracks not_allowed)
			(vias allowed)
			(pads allowed)
			(copperpour not_allowed)
			(footprints allowed)
		)
		(placement
			(enabled no)
			(sheetname "")
		)
		(fill
			(thermal_gap 0.5)
			(thermal_bridge_width 0.5)
			(island_removal_mode 0)
		)
		(polygon
			(pts
				(arc
					(start 354.231956 -16.95196)
					(mid 353.746562 -17.436973)
					(end 354.231702 -17.92224)
				)
				(xy 354.625148 -17.92224) (xy 354.625148 -17.593818)
				(arc
					(start 354.625148 -17.5895)
					(mid 354.601937 -17.533463)
					(end 354.5459 -17.510252)
				)
				(xy 354.541582 -17.510252)
				(arc
					(start 354.488242 -17.510252)
					(mid 353.964936 -17.4371)
					(end 354.488242 -17.363948)
				)
				(xy 354.541582 -17.363948) (xy 354.5459 -17.363948) (xy 354.55352 -17.363948) (xy 354.576126 -17.363948)
				(arc
					(start 354.578412 -17.366234)
					(mid 354.705438 -17.429962)
					(end 354.769166 -17.556988)
				)
				(xy 354.771452 -17.559274) (xy 354.771452 -17.58188) (xy 354.771452 -17.5895) (xy 354.771452 -17.593818)
				(xy 354.771452 -17.92224) (xy 354.961952 -17.92224) (xy 354.961952 -17.594072) (xy 354.961698 -17.589754)
				(xy 354.961952 -17.582134) (xy 354.961952 -17.559528)
				(arc
					(start 354.963984 -17.557242)
					(mid 355.027788 -17.430038)
					(end 355.154992 -17.366234)
				)
				(xy 355.157278 -17.363948) (xy 355.179884 -17.363948) (xy 355.187504 -17.363948) (xy 355.191822 -17.363948)
				(arc
					(start 355.245162 -17.363948)
					(mid 355.768468 -17.4371)
					(end 355.245162 -17.510252)
				)
				(xy 355.191822 -17.510252)
				(arc
					(start 355.187504 -17.510252)
					(mid 355.131288 -17.533538)
					(end 355.108002 -17.589754)
				)
				(xy 355.107748 -17.594072) (xy 355.107748 -17.92224)
				(arc
					(start 355.501702 -17.92224)
					(mid 355.986842 -17.4371)
					(end 355.501702 -16.95196)
				)
			)
		)
	)
	(zone
		(net "MB0_CM_GATE")
		(layer "In5.Cu")
		(hatch none 0.5)
		(connect_pads
			(clearance 0.5)
		)
		(min_thickness 0.25)
		(fill yes
			(thermal_gap 0.5)
			(thermal_bridge_width 0.5)
			(island_removal_mode 0)
		)
		(polygon
			(pts
				(xy 214.884 -354.965) (xy 216.5858 -354.965) (xy 216.916 -355.2952) (xy 216.916 -358.775) (xy 216.154 -359.537)
				(xy 215.138 -359.537) (xy 214.63 -359.029) (xy 214.63 -355.219)
			)
		)
	)
	(zone
		(net "MB3_P12V_IN_R")
		(layer "In5.Cu")
		(hatch none 0.5)
		(connect_pads
			(clearance 0.5)
		)
		(min_thickness 0.25)
		(fill yes
			(thermal_gap 0.5)
			(thermal_bridge_width 0.5)
			(island_removal_mode 0)
		)
		(polygon
			(pts
				(xy 250.676918 -345.4908) (xy 250.676918 -353.903026) (xy 251.164344 -354.390452) (xy 258.233926 -354.390452)
				(xy 260.024372 -352.600006) (xy 260.024372 -338.985606) (xy 260.024372 -331.41158) (xy 260.024372 -330.585572)
				(xy 260.024372 -330.229972) (xy 259.6896 -329.8952) (xy 259.334 -329.8952) (xy 249.809 -329.8952)
				(xy 249.5804 -329.8952) (xy 249.2248 -330.2508) (xy 249.2248 -331.216) (xy 249.2248 -344.043) (xy 249.7582 -344.5764)
				(xy 249.762518 -344.5764)
			)
		)
	)
	(zone
		(layer "In5.Cu")
		(hatch none 0.5)
		(connect_pads
			(clearance 0)
		)
		(min_thickness 0.25)
		(keepout
			(tracks not_allowed)
			(vias allowed)
			(pads allowed)
			(copperpour not_allowed)
			(footprints allowed)
		)
		(placement
			(enabled no)
			(sheetname "")
		)
		(fill
			(thermal_gap 0.5)
			(thermal_bridge_width 0.5)
			(island_removal_mode 0)
		)
		(polygon
			(pts
				(arc
					(start 285.436564 -185.94578)
					(mid 284.887924 -186.49442)
					(end 285.436564 -187.04306)
				)
				(arc
					(start 286.836612 -187.04306)
					(mid 287.385252 -186.49442)
					(end 286.836612 -185.94578)
				)
				(arc
					(start 286.361378 -185.94578)
					(mid 286.372052 -186.00856)
					(end 286.37738 -186.072018)
				)
				(xy 286.377888 -186.072526) (xy 286.377888 -186.089036) (xy 286.377888 -186.102752) (xy 286.377888 -186.10707)
				(xy 286.377888 -186.327034)
				(arc
					(start 286.377888 -186.331352)
					(mid 286.398221 -186.3883)
					(end 286.450024 -186.41949)
				)
				(arc
					(start 286.450024 -186.41949)
					(mid 287.230346 -186.494814)
					(end 286.44977 -186.567572)
				)
				(xy 286.437578 -186.567572)
				(arc
					(start 286.435546 -186.565286)
					(mid 286.300822 -186.498334)
					(end 286.23387 -186.36361)
				)
				(xy 286.231584 -186.361578) (xy 286.231584 -186.338972) (xy 286.231584 -186.331352) (xy 286.231584 -186.327034)
				(xy 286.231584 -186.10707)
				(arc
					(start 286.231584 -186.102752)
					(mid 286.226335 -186.023581)
					(end 286.210756 -185.94578)
				)
				(arc
					(start 286.01035 -185.94578)
					(mid 286.030152 -186.007477)
					(end 286.040068 -186.07151)
				)
				(xy 286.041084 -186.072526) (xy 286.041084 -186.092592) (xy 286.041338 -186.102752) (xy 286.041084 -186.10707)
				(xy 286.041084 -186.327034) (xy 286.041338 -186.331352) (xy 286.041084 -186.338972) (xy 286.041084 -186.361578)
				(arc
					(start 286.039052 -186.36361)
					(mid 285.9721 -186.498334)
					(end 285.837376 -186.565286)
				)
				(xy 285.835344 -186.567572)
				(arc
					(start 285.823406 -186.567572)
					(mid 285.042819 -186.494814)
					(end 285.823152 -186.41949)
				)
				(arc
					(start 285.823152 -186.41949)
					(mid 285.874817 -186.388234)
					(end 285.895034 -186.331352)
				)
				(xy 285.895288 -186.327034) (xy 285.895288 -186.10707)
				(arc
					(start 285.895034 -186.102752)
					(mid 285.881954 -186.020216)
					(end 285.84398 -185.94578)
				)
			)
		)
	)
	(zone
		(layer "In5.Cu")
		(hatch none 0.5)
		(connect_pads
			(clearance 0)
		)
		(min_thickness 0.25)
		(keepout
			(tracks not_allowed)
			(vias allowed)
			(pads allowed)
			(copperpour not_allowed)
			(footprints allowed)
		)
		(placement
			(enabled no)
			(sheetname "")
		)
		(fill
			(thermal_gap 0.5)
			(thermal_bridge_width 0.5)
			(island_removal_mode 0)
		)
		(polygon
			(pts
				(arc
					(start 285.436564 -189.545722)
					(mid 284.887924 -190.094362)
					(end 285.436564 -190.643002)
				)
				(arc
					(start 286.836612 -190.643002)
					(mid 287.385252 -190.094362)
					(end 286.836612 -189.545722)
				)
				(arc
					(start 286.361378 -189.545722)
					(mid 286.372052 -189.608502)
					(end 286.37738 -189.67196)
				)
				(xy 286.377888 -189.672468) (xy 286.377888 -189.688978) (xy 286.377888 -189.702694) (xy 286.377888 -189.707012)
				(xy 286.377888 -189.926976)
				(arc
					(start 286.377888 -189.931294)
					(mid 286.398221 -189.988242)
					(end 286.450024 -190.019432)
				)
				(arc
					(start 286.450024 -190.019432)
					(mid 287.230346 -190.09488)
					(end 286.44977 -190.16726)
				)
				(xy 286.437578 -190.16726)
				(arc
					(start 286.435546 -190.165228)
					(mid 286.300822 -190.098276)
					(end 286.23387 -189.963552)
				)
				(xy 286.231584 -189.96152) (xy 286.231584 -189.938914) (xy 286.231584 -189.931294) (xy 286.231584 -189.926976)
				(xy 286.231584 -189.707012)
				(arc
					(start 286.231584 -189.702694)
					(mid 286.226335 -189.623523)
					(end 286.210756 -189.545722)
				)
				(arc
					(start 286.01035 -189.545722)
					(mid 286.030152 -189.607419)
					(end 286.040068 -189.671452)
				)
				(xy 286.041084 -189.672468) (xy 286.041084 -189.692534) (xy 286.041338 -189.702694) (xy 286.041084 -189.707012)
				(xy 286.041084 -189.926976) (xy 286.041338 -189.931294) (xy 286.041084 -189.938914) (xy 286.041084 -189.96152)
				(arc
					(start 286.039052 -189.963552)
					(mid 285.9721 -190.098276)
					(end 285.837376 -190.165228)
				)
				(xy 285.835344 -190.16726)
				(arc
					(start 285.823406 -190.16726)
					(mid 285.042867 -190.09488)
					(end 285.823152 -190.019432)
				)
				(arc
					(start 285.823152 -190.019432)
					(mid 285.874817 -189.988176)
					(end 285.895034 -189.931294)
				)
				(xy 285.895288 -189.926976) (xy 285.895288 -189.707012)
				(arc
					(start 285.895034 -189.702694)
					(mid 285.881954 -189.620158)
					(end 285.84398 -189.545722)
				)
			)
		)
	)
	(zone
		(layer "In5.Cu")
		(hatch none 0.5)
		(connect_pads
			(clearance 0)
		)
		(min_thickness 0.25)
		(keepout
			(tracks not_allowed)
			(vias allowed)
			(pads allowed)
			(copperpour not_allowed)
			(footprints allowed)
		)
		(placement
			(enabled no)
			(sheetname "")
		)
		(fill
			(thermal_gap 0.5)
			(thermal_bridge_width 0.5)
			(island_removal_mode 0)
		)
		(polygon
			(pts
				(arc
					(start 480.431856 -16.95196)
					(mid 479.946462 -17.436973)
					(end 480.431602 -17.92224)
				)
				(xy 480.825048 -17.92224) (xy 480.825048 -17.581118)
				(arc
					(start 480.825048 -17.5768)
					(mid 480.805557 -17.529743)
					(end 480.7585 -17.510252)
				)
				(xy 480.754182 -17.510252)
				(arc
					(start 480.688142 -17.510252)
					(mid 480.164836 -17.4371)
					(end 480.688142 -17.363948)
				)
				(xy 480.754182 -17.363948) (xy 480.7585 -17.363948) (xy 480.765866 -17.363948) (xy 480.788726 -17.363948)
				(arc
					(start 480.791012 -17.366488)
					(mid 480.90898 -17.42632)
					(end 480.968812 -17.544288)
				)
				(xy 480.971352 -17.546574) (xy 480.971352 -17.569434) (xy 480.971352 -17.5768) (xy 480.971352 -17.581118)
				(xy 480.971352 -17.92224) (xy 481.161852 -17.92224) (xy 481.161852 -17.600168) (xy 481.161598 -17.59585)
				(xy 481.161852 -17.58823) (xy 481.161852 -17.565624)
				(arc
					(start 481.163884 -17.563338)
					(mid 481.229517 -17.431867)
					(end 481.360988 -17.366234)
				)
				(xy 481.363274 -17.363948) (xy 481.38588 -17.363948) (xy 481.3935 -17.363948) (xy 481.397818 -17.363948)
				(arc
					(start 481.445062 -17.363948)
					(mid 481.968368 -17.4371)
					(end 481.445062 -17.510252)
				)
				(xy 481.397818 -17.510252)
				(arc
					(start 481.3935 -17.510252)
					(mid 481.332973 -17.535323)
					(end 481.307902 -17.59585)
				)
				(xy 481.307648 -17.600168) (xy 481.307648 -17.92224)
				(arc
					(start 481.701602 -17.92224)
					(mid 482.186742 -17.4371)
					(end 481.701602 -16.95196)
				)
			)
		)
	)
	(zone
		(layer "In5.Cu")
		(hatch none 0.5)
		(connect_pads
			(clearance 0)
		)
		(min_thickness 0.25)
		(keepout
			(tracks not_allowed)
			(vias allowed)
			(pads allowed)
			(copperpour not_allowed)
			(footprints allowed)
		)
		(placement
			(enabled no)
			(sheetname "")
		)
		(fill
			(thermal_gap 0.5)
			(thermal_bridge_width 0.5)
			(island_removal_mode 0)
		)
		(polygon
			(pts
				(arc
					(start 286.436562 -223.682306)
					(mid 285.824422 -224.294446)
					(end 286.436562 -224.906586)
				)
				(arc
					(start 286.924242 -224.906586)
					(mid 286.904758 -224.820195)
					(end 286.895794 -224.732088)
				)
				(xy 286.895032 -224.73158) (xy 286.895032 -224.71507) (xy 286.895032 -224.701354) (xy 286.895032 -224.697036)
				(xy 286.895032 -224.489264)
				(arc
					(start 286.895032 -224.484946)
					(mid 286.874953 -224.419378)
					(end 286.821626 -224.376234)
				)
				(arc
					(start 286.821626 -224.376234)
					(mid 286.042912 -224.287467)
					(end 286.824166 -224.225358)
				)
				(arc
					(start 286.824166 -224.225358)
					(mid 286.969258 -224.303712)
					(end 287.039304 -224.452942)
				)
				(xy 287.041336 -224.45472) (xy 287.041336 -224.476818) (xy 287.041336 -224.484946) (xy 287.041336 -224.489264)
				(xy 287.041336 -224.697036)
				(arc
					(start 287.041336 -224.701354)
					(mid 287.050698 -224.80563)
					(end 287.07842 -224.906586)
				)
				(arc
					(start 287.288478 -224.906586)
					(mid 287.25054 -224.822827)
					(end 287.232852 -224.732596)
				)
				(xy 287.231836 -224.73158) (xy 287.231836 -224.711514) (xy 287.231582 -224.701354) (xy 287.231836 -224.697036)
				(xy 287.231836 -224.489518) (xy 287.231582 -224.4852) (xy 287.231836 -224.477072) (xy 287.231836 -224.454974)
				(arc
					(start 287.233614 -224.453196)
					(mid 287.303842 -224.303888)
					(end 287.449006 -224.225358)
				)
				(arc
					(start 287.449006 -224.225358)
					(mid 288.230221 -224.287467)
					(end 287.451546 -224.376234)
				)
				(arc
					(start 287.451546 -224.376234)
					(mid 287.397994 -224.419423)
					(end 287.377886 -224.4852)
				)
				(xy 287.377632 -224.489518) (xy 287.377632 -224.697036)
				(arc
					(start 287.377886 -224.701354)
					(mid 287.405933 -224.816822)
					(end 287.483804 -224.906586)
				)
				(arc
					(start 287.83661 -224.906586)
					(mid 288.44875 -224.294446)
					(end 287.83661 -223.682306)
				)
				(xy 286.436816 -223.682306)
			)
		)
	)
	(zone
		(layer "In5.Cu")
		(hatch none 0.5)
		(connect_pads
			(clearance 0)
		)
		(min_thickness 0.25)
		(keepout
			(tracks not_allowed)
			(vias allowed)
			(pads allowed)
			(copperpour not_allowed)
			(footprints allowed)
		)
		(placement
			(enabled no)
			(sheetname "")
		)
		(fill
			(thermal_gap 0.5)
			(thermal_bridge_width 0.5)
			(island_removal_mode 0)
		)
		(polygon
			(pts
				(arc
					(start 286.436562 -140.54582)
					(mid 285.887922 -141.09446)
					(end 286.436562 -141.6431)
				)
				(arc
					(start 287.83661 -141.6431)
					(mid 288.38525 -141.09446)
					(end 287.83661 -140.54582)
				)
				(arc
					(start 287.349184 -140.54582)
					(mid 287.35916 -140.603805)
					(end 287.364424 -140.662406)
				)
				(xy 287.365186 -140.663168)
				(arc
					(start 287.365186 -140.875258)
					(mid 287.389427 -140.95296)
					(end 287.453578 -141.00302)
				)
				(arc
					(start 287.453578 -141.00302)
					(mid 288.230293 -141.100708)
					(end 287.450784 -141.172692)
				)
				(arc
					(start 287.450784 -141.172692)
					(mid 287.283251 -141.083328)
					(end 287.202372 -140.91158)
				)
				(xy 287.200086 -140.909548)
				(arc
					(start 287.200086 -140.697458)
					(mid 287.194929 -140.620944)
					(end 287.179512 -140.54582)
				)
				(arc
					(start 287.046162 -140.54582)
					(mid 287.062811 -140.602995)
					(end 287.071562 -140.661898)
				)
				(xy 287.073086 -140.663168) (xy 287.073086 -140.909548)
				(arc
					(start 287.0708 -140.91158)
					(mid 286.989832 -141.083243)
					(end 286.822388 -141.172692)
				)
				(arc
					(start 286.822388 -141.172692)
					(mid 286.042888 -141.100708)
					(end 286.819594 -141.00302)
				)
				(arc
					(start 286.819594 -141.00302)
					(mid 286.88368 -140.952915)
					(end 286.907986 -140.875258)
				)
				(arc
					(start 286.907986 -140.697458)
					(mid 286.896307 -140.618268)
					(end 286.862266 -140.54582)
				)
			)
		)
	)
	(zone
		(layer "In5.Cu")
		(hatch none 0.5)
		(connect_pads
			(clearance 0)
		)
		(min_thickness 0.25)
		(keepout
			(tracks not_allowed)
			(vias allowed)
			(pads allowed)
			(copperpour not_allowed)
			(footprints allowed)
		)
		(placement
			(enabled no)
			(sheetname "")
		)
		(fill
			(thermal_gap 0.5)
			(thermal_bridge_width 0.5)
			(island_removal_mode 0)
		)
		(polygon
			(pts
				(arc
					(start 210.548728 -70.39991)
					(mid 210.000088 -69.85127)
					(end 209.451448 -70.39991)
				)
				(arc
					(start 209.451448 -71.799704)
					(mid 209.999961 -72.348598)
					(end 210.548728 -71.799958)
				)
				(xy 210.548728 -71.328534)
				(arc
					(start 210.185 -71.328534)
					(mid 210.118422 -71.353144)
					(end 210.083908 -71.415148)
				)
				(arc
					(start 210.083908 -71.415148)
					(mid 209.99944 -72.193791)
					(end 209.917538 -71.414894)
				)
				(xy 209.917538 -71.396606)
				(arc
					(start 209.920078 -71.394066)
					(mid 209.99587 -71.241766)
					(end 210.14817 -71.165974)
				)
				(xy 210.15071 -71.163434) (xy 210.548728 -71.163434) (xy 210.548728 -71.036434) (xy 210.15071 -71.036434)
				(arc
					(start 210.14817 -71.033894)
					(mid 209.99587 -70.958102)
					(end 209.920078 -70.805802)
				)
				(xy 209.917538 -70.803262)
				(arc
					(start 209.917538 -70.784974)
					(mid 209.999441 -70.006097)
					(end 210.083908 -70.78472)
				)
				(arc
					(start 210.083908 -70.78472)
					(mid 210.118455 -70.846686)
					(end 210.185 -70.871334)
				)
				(xy 210.548728 -70.871334)
			)
		)
	)
	(zone
		(layer "In5.Cu")
		(hatch none 0.5)
		(connect_pads
			(clearance 0)
		)
		(min_thickness 0.25)
		(keepout
			(tracks not_allowed)
			(vias allowed)
			(pads allowed)
			(copperpour not_allowed)
			(footprints allowed)
		)
		(placement
			(enabled no)
			(sheetname "")
		)
		(fill
			(thermal_gap 0.5)
			(thermal_bridge_width 0.5)
			(island_removal_mode 0)
		)
		(polygon
			(pts
				(arc
					(start 355.624892 -248.115328)
					(mid 355.139879 -247.629934)
					(end 354.654612 -248.115074)
				)
				(xy 354.654612 -248.50852) (xy 355.014784 -248.50852)
				(arc
					(start 355.019102 -248.50852)
					(mid 355.052688 -248.494608)
					(end 355.0666 -248.461022)
				)
				(xy 355.0666 -248.456704)
				(arc
					(start 355.0666 -248.371614)
					(mid 355.139752 -247.848308)
					(end 355.212904 -248.371614)
				)
				(xy 355.212904 -248.456704) (xy 355.212904 -248.461022) (xy 355.212904 -248.468134) (xy 355.212904 -248.491248)
				(arc
					(start 355.21011 -248.494042)
					(mid 355.156168 -248.598088)
					(end 355.052122 -248.65203)
				)
				(xy 355.049328 -248.654824) (xy 355.026214 -248.654824) (xy 355.019102 -248.654824) (xy 355.014784 -248.654824)
				(xy 354.654612 -248.654824) (xy 354.654612 -248.845324) (xy 355.014784 -248.845324) (xy 355.019102 -248.84507)
				(xy 355.026214 -248.845324) (xy 355.049328 -248.845324)
				(arc
					(start 355.052122 -248.847864)
					(mid 355.156168 -248.901806)
					(end 355.21011 -249.005852)
				)
				(xy 355.212904 -249.008646) (xy 355.212904 -249.03176) (xy 355.212904 -249.038872) (xy 355.212904 -249.04319)
				(arc
					(start 355.212904 -249.128534)
					(mid 355.139752 -249.65184)
					(end 355.0666 -249.128534)
				)
				(xy 355.0666 -249.04319)
				(arc
					(start 355.0666 -249.038872)
					(mid 355.052688 -249.005286)
					(end 355.019102 -248.991374)
				)
				(xy 355.014784 -248.99112) (xy 354.654612 -248.99112)
				(arc
					(start 354.654612 -249.385074)
					(mid 355.139752 -249.870214)
					(end 355.624892 -249.385074)
				)
			)
		)
	)
	(zone
		(layer "In5.Cu")
		(hatch none 0.5)
		(connect_pads
			(clearance 0)
		)
		(min_thickness 0.25)
		(keepout
			(tracks not_allowed)
			(vias allowed)
			(pads allowed)
			(copperpour not_allowed)
			(footprints allowed)
		)
		(placement
			(enabled no)
			(sheetname "")
		)
		(fill
			(thermal_gap 0.5)
			(thermal_bridge_width 0.5)
			(island_removal_mode 0)
		)
		(polygon
			(pts
				(arc
					(start 385.78155 -16.95196)
					(mid 385.29641 -17.4371)
					(end 385.78155 -17.92224)
				)
				(xy 386.174996 -17.92224) (xy 386.174996 -17.581118)
				(arc
					(start 386.174996 -17.5768)
					(mid 386.155505 -17.529743)
					(end 386.108448 -17.510252)
				)
				(xy 386.10413 -17.510252)
				(arc
					(start 386.03809 -17.510252)
					(mid 385.514784 -17.4371)
					(end 386.03809 -17.363948)
				)
				(xy 386.10413 -17.363948) (xy 386.108448 -17.363948) (xy 386.115814 -17.363948) (xy 386.138674 -17.363948)
				(arc
					(start 386.14096 -17.366488)
					(mid 386.258928 -17.42632)
					(end 386.31876 -17.544288)
				)
				(xy 386.3213 -17.546574) (xy 386.3213 -17.569434) (xy 386.3213 -17.5768) (xy 386.3213 -17.581118)
				(xy 386.3213 -17.92224) (xy 386.5118 -17.92224) (xy 386.5118 -17.581372) (xy 386.511546 -17.577054)
				(xy 386.5118 -17.569688) (xy 386.5118 -17.546828)
				(arc
					(start 386.514086 -17.544542)
					(mid 386.573995 -17.426397)
					(end 386.69214 -17.366488)
				)
				(xy 386.694426 -17.363948) (xy 386.717286 -17.363948) (xy 386.724652 -17.363948) (xy 386.72897 -17.363948)
				(arc
					(start 386.79501 -17.363948)
					(mid 387.318316 -17.4371)
					(end 386.79501 -17.510252)
				)
				(xy 386.72897 -17.510252)
				(arc
					(start 386.724652 -17.510252)
					(mid 386.677416 -17.529818)
					(end 386.65785 -17.577054)
				)
				(xy 386.657596 -17.581372) (xy 386.657596 -17.92224)
				(arc
					(start 387.051296 -17.92224)
					(mid 387.53669 -17.437227)
					(end 387.05155 -16.95196)
				)
			)
		)
	)
	(zone
		(layer "In5.Cu")
		(hatch none 0.5)
		(connect_pads
			(clearance 0)
		)
		(min_thickness 0.25)
		(keepout
			(tracks not_allowed)
			(vias allowed)
			(pads allowed)
			(copperpour not_allowed)
			(footprints allowed)
		)
		(placement
			(enabled no)
			(sheetname "")
		)
		(fill
			(thermal_gap 0.5)
			(thermal_bridge_width 0.5)
			(island_removal_mode 0)
		)
		(polygon
			(pts
				(arc
					(start 385.78155 -131.951984)
					(mid 385.29641 -132.437124)
					(end 385.78155 -132.922264)
				)
				(xy 386.174996 -132.922264) (xy 386.174996 -132.582666)
				(arc
					(start 386.174996 -132.578348)
					(mid 386.155058 -132.530214)
					(end 386.106924 -132.510276)
				)
				(xy 386.102606 -132.510276)
				(arc
					(start 386.03809 -132.510276)
					(mid 385.514784 -132.437124)
					(end 386.03809 -132.363972)
				)
				(xy 386.102606 -132.363972) (xy 386.106924 -132.363972) (xy 386.11429 -132.363972) (xy 386.13715 -132.363972)
				(arc
					(start 386.139436 -132.366512)
					(mid 386.258469 -132.426803)
					(end 386.31876 -132.545836)
				)
				(xy 386.3213 -132.548122) (xy 386.3213 -132.570982) (xy 386.3213 -132.578348) (xy 386.3213 -132.582666)
				(xy 386.3213 -132.922264) (xy 386.5118 -132.922264) (xy 386.5118 -132.58292) (xy 386.511546 -132.578602)
				(xy 386.5118 -132.571236) (xy 386.5118 -132.548376)
				(arc
					(start 386.514086 -132.54609)
					(mid 386.574454 -132.42688)
					(end 386.693664 -132.366512)
				)
				(xy 386.69595 -132.363972) (xy 386.71881 -132.363972) (xy 386.726176 -132.363972) (xy 386.730494 -132.363972)
				(arc
					(start 386.79501 -132.363972)
					(mid 387.318316 -132.437124)
					(end 386.79501 -132.510276)
				)
				(xy 386.730494 -132.510276)
				(arc
					(start 386.726176 -132.510276)
					(mid 386.677862 -132.530288)
					(end 386.65785 -132.578602)
				)
				(xy 386.657596 -132.58292) (xy 386.657596 -132.922264)
				(arc
					(start 387.051296 -132.922264)
					(mid 387.53669 -132.437251)
					(end 387.05155 -131.951984)
				)
			)
		)
	)
	(zone
		(layer "In5.Cu")
		(hatch none 0.5)
		(connect_pads
			(clearance 0)
		)
		(min_thickness 0.25)
		(keepout
			(tracks not_allowed)
			(vias allowed)
			(pads allowed)
			(copperpour not_allowed)
			(footprints allowed)
		)
		(placement
			(enabled no)
			(sheetname "")
		)
		(fill
			(thermal_gap 0.5)
			(thermal_bridge_width 0.5)
			(island_removal_mode 0)
		)
		(polygon
			(pts
				(arc
					(start 286.436562 -216.545922)
					(mid 285.887922 -217.094562)
					(end 286.436562 -217.643202)
				)
				(arc
					(start 287.83661 -217.643202)
					(mid 288.38525 -217.094562)
					(end 287.83661 -216.545922)
				)
				(arc
					(start 287.361376 -216.545922)
					(mid 287.37205 -216.608702)
					(end 287.377378 -216.67216)
				)
				(xy 287.377632 -216.672668) (xy 287.377632 -216.689178) (xy 287.377886 -216.702894) (xy 287.377632 -216.707212)
				(xy 287.377632 -216.927176)
				(arc
					(start 287.377886 -216.931494)
					(mid 287.398219 -216.988442)
					(end 287.450022 -217.019632)
				)
				(arc
					(start 287.450022 -217.019632)
					(mid 288.230344 -217.09508)
					(end 287.449768 -217.16746)
				)
				(xy 287.437576 -217.16746)
				(arc
					(start 287.435544 -217.165428)
					(mid 287.30082 -217.098476)
					(end 287.233868 -216.963752)
				)
				(xy 287.231836 -216.96172) (xy 287.231836 -216.939114) (xy 287.231582 -216.931494) (xy 287.231836 -216.927176)
				(xy 287.231836 -216.707212)
				(arc
					(start 287.231582 -216.702894)
					(mid 287.226333 -216.623723)
					(end 287.210754 -216.545922)
				)
				(arc
					(start 287.010348 -216.545922)
					(mid 287.03015 -216.607619)
					(end 287.040066 -216.671652)
				)
				(xy 287.041336 -216.672668) (xy 287.041336 -216.692734) (xy 287.041336 -216.702894) (xy 287.041336 -216.707212)
				(xy 287.041336 -216.927176) (xy 287.041336 -216.931494) (xy 287.041336 -216.939114) (xy 287.041336 -216.96172)
				(arc
					(start 287.03905 -216.963752)
					(mid 286.972098 -217.098476)
					(end 286.837374 -217.165428)
				)
				(xy 286.835342 -217.16746)
				(arc
					(start 286.823404 -217.16746)
					(mid 286.042865 -217.09508)
					(end 286.82315 -217.019632)
				)
				(arc
					(start 286.82315 -217.019632)
					(mid 286.874815 -216.988376)
					(end 286.895032 -216.931494)
				)
				(xy 286.895032 -216.927176) (xy 286.895032 -216.707212)
				(arc
					(start 286.895032 -216.702894)
					(mid 286.881952 -216.620358)
					(end 286.843978 -216.545922)
				)
			)
		)
	)
	(zone
		(net "GND")
		(layer "In5.Cu")
		(hatch none 0.5)
		(connect_pads
			(clearance 0.5)
		)
		(min_thickness 0.25)
		(fill yes
			(thermal_gap 0.5)
			(thermal_bridge_width 0.5)
			(island_removal_mode 0)
		)
		(polygon
			(pts
				(xy 73.279 -346.964) (xy 101.219 -346.964) (xy 101.915468 -346.267532) (xy 101.915468 -332.420468)
				(xy 100.965 -331.47) (xy 73.279 -331.47) (xy 72.771 -331.978) (xy 72.771 -346.456)
			)
		)
	)
	(zone
		(layer "In5.Cu")
		(hatch none 0.5)
		(connect_pads
			(clearance 0)
		)
		(min_thickness 0.25)
		(keepout
			(tracks not_allowed)
			(vias allowed)
			(pads allowed)
			(copperpour not_allowed)
			(footprints allowed)
		)
		(placement
			(enabled no)
			(sheetname "")
		)
		(fill
			(thermal_gap 0.5)
			(thermal_bridge_width 0.5)
			(island_removal_mode 0)
		)
		(polygon
			(pts
				(arc
					(start 285.436564 -200.345802)
					(mid 284.887924 -200.894442)
					(end 285.436564 -201.443082)
				)
				(arc
					(start 286.836612 -201.443082)
					(mid 287.385252 -200.894442)
					(end 286.836612 -200.345802)
				)
				(arc
					(start 286.392112 -200.345802)
					(mid 286.381482 -200.380268)
					(end 286.377888 -200.41616)
				)
				(xy 286.377888 -200.420478) (xy 286.377888 -200.665842)
				(arc
					(start 286.377888 -200.67016)
					(mid 286.398328 -200.746057)
					(end 286.454088 -200.801478)
				)
				(arc
					(start 286.454088 -200.801478)
					(mid 287.229997 -200.910886)
					(end 286.447738 -200.956164)
				)
				(arc
					(start 286.447738 -200.956164)
					(mid 286.301693 -200.861805)
					(end 286.233362 -200.70191)
				)
				(xy 286.231584 -200.700386) (xy 286.231584 -200.678796) (xy 286.231584 -200.67016) (xy 286.231584 -200.665842)
				(xy 286.231584 -200.420478) (xy 286.231584 -200.41616) (xy 286.231584 -200.407016) (xy 286.231584 -200.385934)
				(arc
					(start 286.233108 -200.38441)
					(mid 286.235575 -200.365014)
					(end 286.239204 -200.345802)
				)
				(arc
					(start 286.046164 -200.345802)
					(mid 286.042557 -200.380899)
					(end 286.041338 -200.41616)
				)
				(xy 286.041084 -200.420478) (xy 286.041084 -200.665842) (xy 286.041338 -200.67016) (xy 286.041084 -200.678796)
				(xy 286.041084 -200.700386)
				(arc
					(start 286.03956 -200.70191)
					(mid 285.971328 -200.861729)
					(end 285.825438 -200.956164)
				)
				(arc
					(start 285.825438 -200.956164)
					(mid 285.04315 -200.910507)
					(end 285.819088 -200.801224)
				)
				(arc
					(start 285.819088 -200.801224)
					(mid 285.874653 -200.745891)
					(end 285.895034 -200.67016)
				)
				(xy 285.895288 -200.665842) (xy 285.895288 -200.420478) (xy 285.895034 -200.41616) (xy 285.895288 -200.403206)
				(xy 285.895288 -200.385934) (xy 285.895796 -200.385426) (xy 285.898844 -200.345802)
			)
		)
	)
	(zone
		(net "P12V_IN")
		(layer "In5.Cu")
		(hatch none 0.5)
		(connect_pads
			(clearance 0.5)
		)
		(min_thickness 0.25)
		(fill yes
			(thermal_gap 0.5)
			(thermal_bridge_width 0.5)
			(island_removal_mode 0)
		)
		(polygon
			(pts
				(xy 37.465 -348.488) (xy 37.211 -348.742) (xy 37.211 -354.711) (xy 43.307 -360.807) (xy 43.307 -364.871)
				(xy 43.815 -365.379) (xy 61.722 -365.379) (xy 72.39 -376.047) (xy 123.317 -376.047) (xy 130.683 -368.681)
				(xy 132.390388 -368.681) (xy 133.420612 -367.650776) (xy 133.420612 -361.064556) (xy 131.605528 -359.249472)
				(xy 126.779528 -359.249472) (xy 119.888 -366.141) (xy 82.044032 -366.141) (xy 67.061334 -351.158302)
				(xy 64.581786 -348.678754) (xy 64.589914 -348.678754) (xy 64.39916 -348.488)
			)
		)
	)
	(zone
		(layer "In5.Cu")
		(hatch none 0.5)
		(connect_pads
			(clearance 0)
		)
		(min_thickness 0.25)
		(keepout
			(tracks not_allowed)
			(vias allowed)
			(pads allowed)
			(copperpour not_allowed)
			(footprints allowed)
		)
		(placement
			(enabled no)
			(sheetname "")
		)
		(fill
			(thermal_gap 0.5)
			(thermal_bridge_width 0.5)
			(island_removal_mode 0)
		)
		(polygon
			(pts
				(arc
					(start 286.436562 -180.54574)
					(mid 285.887922 -181.09438)
					(end 286.436562 -181.64302)
				)
				(arc
					(start 287.83661 -181.64302)
					(mid 288.38525 -181.09438)
					(end 287.83661 -180.54574)
				)
				(arc
					(start 287.387284 -180.54574)
					(mid 287.380253 -180.572772)
					(end 287.377886 -180.600604)
				)
				(xy 287.377632 -180.604922) (xy 287.377632 -180.901086)
				(arc
					(start 287.377886 -180.905404)
					(mid 287.397972 -180.970592)
					(end 287.451292 -181.0131)
				)
				(arc
					(start 287.451292 -181.0131)
					(mid 288.230361 -181.100458)
					(end 287.449006 -181.163722)
				)
				(arc
					(start 287.449006 -181.163722)
					(mid 287.303857 -181.086187)
					(end 287.233614 -180.937408)
				)
				(xy 287.231836 -180.93563) (xy 287.231836 -180.913532) (xy 287.231582 -180.905404) (xy 287.231836 -180.901086)
				(xy 287.231836 -180.604922) (xy 287.231582 -180.600604) (xy 287.231836 -180.591714) (xy 287.231836 -180.570378)
				(xy 287.233106 -180.568854) (xy 287.236408 -180.54574)
				(arc
					(start 287.044384 -180.54574)
					(mid 287.042112 -180.57313)
					(end 287.041336 -180.600604)
				)
				(xy 287.041336 -180.604922) (xy 287.041336 -180.901086) (xy 287.041336 -180.905404) (xy 287.041336 -180.913532)
				(xy 287.041336 -180.93563)
				(arc
					(start 287.039304 -180.937408)
					(mid 286.969074 -181.086028)
					(end 286.824166 -181.163722)
				)
				(arc
					(start 286.824166 -181.163722)
					(mid 286.042851 -181.100457)
					(end 286.82188 -181.0131)
				)
				(arc
					(start 286.82188 -181.0131)
					(mid 286.875027 -180.970504)
					(end 286.895032 -180.905404)
				)
				(xy 286.895032 -180.901086) (xy 286.895032 -180.604922) (xy 286.895032 -180.600604) (xy 286.895032 -180.587904)
				(xy 286.895032 -180.570378) (xy 286.895794 -180.56987) (xy 286.897318 -180.54574)
			)
		)
	)
	(zone
		(layer "In5.Cu")
		(hatch none 0.5)
		(connect_pads
			(clearance 0)
		)
		(min_thickness 0.25)
		(keepout
			(tracks not_allowed)
			(vias allowed)
			(pads allowed)
			(copperpour not_allowed)
			(footprints allowed)
		)
		(placement
			(enabled no)
			(sheetname "")
		)
		(fill
			(thermal_gap 0.5)
			(thermal_bridge_width 0.5)
			(island_removal_mode 0)
		)
		(polygon
			(pts
				(arc
					(start 450.27469 -248.115328)
					(mid 449.789677 -247.629934)
					(end 449.30441 -248.115074)
				)
				(xy 449.30441 -248.50852) (xy 449.664582 -248.50852)
				(arc
					(start 449.6689 -248.50852)
					(mid 449.702486 -248.494608)
					(end 449.716398 -248.461022)
				)
				(xy 449.716652 -248.456704)
				(arc
					(start 449.716652 -248.371614)
					(mid 449.78955 -247.848378)
					(end 449.862448 -248.371614)
				)
				(xy 449.862448 -248.456704) (xy 449.862702 -248.461022) (xy 449.862448 -248.468134) (xy 449.862448 -248.491248)
				(arc
					(start 449.859908 -248.494042)
					(mid 449.805966 -248.598088)
					(end 449.70192 -248.65203)
				)
				(xy 449.699126 -248.654824) (xy 449.676012 -248.654824) (xy 449.6689 -248.654824) (xy 449.664582 -248.654824)
				(xy 449.30441 -248.654824) (xy 449.30441 -248.845324) (xy 449.664582 -248.845324) (xy 449.6689 -248.84507)
				(xy 449.676012 -248.845324) (xy 449.699126 -248.845324)
				(arc
					(start 449.70192 -248.847864)
					(mid 449.805966 -248.901806)
					(end 449.859908 -249.005852)
				)
				(xy 449.862448 -249.008646) (xy 449.862448 -249.03176) (xy 449.862702 -249.038872) (xy 449.862448 -249.04319)
				(arc
					(start 449.862448 -249.128534)
					(mid 449.78955 -249.65177)
					(end 449.716652 -249.128534)
				)
				(xy 449.716652 -249.04319)
				(arc
					(start 449.716398 -249.038872)
					(mid 449.702486 -249.005286)
					(end 449.6689 -248.991374)
				)
				(xy 449.664582 -248.99112) (xy 449.30441 -248.99112)
				(arc
					(start 449.30441 -249.385074)
					(mid 449.78955 -249.870214)
					(end 450.27469 -249.385074)
				)
			)
		)
	)
	(zone
		(layer "In5.Cu")
		(hatch none 0.5)
		(connect_pads
			(clearance 0)
		)
		(min_thickness 0.25)
		(keepout
			(tracks not_allowed)
			(vias allowed)
			(pads allowed)
			(copperpour not_allowed)
			(footprints allowed)
		)
		(placement
			(enabled no)
			(sheetname "")
		)
		(fill
			(thermal_gap 0.5)
			(thermal_bridge_width 0.5)
			(island_removal_mode 0)
		)
		(polygon
			(pts
				(arc
					(start 159.193992 -18.11528)
					(mid 158.708979 -17.629886)
					(end 158.223712 -18.115026)
				)
				(arc
					(start 158.223712 -19.385026)
					(mid 158.708852 -19.870166)
					(end 159.193992 -19.385026)
				)
				(xy 159.193992 -18.991072) (xy 158.83382 -18.991072)
				(arc
					(start 158.829502 -18.991326)
					(mid 158.795916 -19.005238)
					(end 158.782004 -19.038824)
				)
				(xy 158.782004 -19.043142)
				(arc
					(start 158.782004 -19.128486)
					(mid 158.708852 -19.651792)
					(end 158.6357 -19.128486)
				)
				(xy 158.6357 -19.043142) (xy 158.6357 -19.038824) (xy 158.6357 -19.031712) (xy 158.6357 -19.008598)
				(arc
					(start 158.638494 -19.005804)
					(mid 158.692436 -18.901758)
					(end 158.796482 -18.847816)
				)
				(xy 158.799276 -18.845276) (xy 158.82239 -18.845276) (xy 158.829502 -18.845022) (xy 158.83382 -18.845276)
				(xy 159.193992 -18.845276) (xy 159.193992 -18.654776) (xy 158.83382 -18.654776) (xy 158.829502 -18.654776)
				(xy 158.82239 -18.654776) (xy 158.799276 -18.654776)
				(arc
					(start 158.796482 -18.651982)
					(mid 158.692436 -18.59804)
					(end 158.638494 -18.493994)
				)
				(xy 158.6357 -18.4912) (xy 158.6357 -18.468086) (xy 158.6357 -18.460974) (xy 158.6357 -18.456656)
				(arc
					(start 158.6357 -18.371566)
					(mid 158.708852 -17.84826)
					(end 158.782004 -18.371566)
				)
				(xy 158.782004 -18.456656)
				(arc
					(start 158.782004 -18.460974)
					(mid 158.795916 -18.49456)
					(end 158.829502 -18.508472)
				)
				(xy 158.83382 -18.508472) (xy 159.193992 -18.508472)
			)
		)
	)
	(zone
		(layer "In5.Cu")
		(hatch none 0.5)
		(connect_pads
			(clearance 0)
		)
		(min_thickness 0.25)
		(keepout
			(tracks not_allowed)
			(vias allowed)
			(pads allowed)
			(copperpour not_allowed)
			(footprints allowed)
		)
		(placement
			(enabled no)
			(sheetname "")
		)
		(fill
			(thermal_gap 0.5)
			(thermal_bridge_width 0.5)
			(island_removal_mode 0)
		)
		(polygon
			(pts
				(arc
					(start 285.436564 -214.745824)
					(mid 284.887924 -215.294464)
					(end 285.436564 -215.843104)
				)
				(arc
					(start 286.836612 -215.843104)
					(mid 287.385252 -215.294464)
					(end 286.836612 -214.745824)
				)
				(arc
					(start 286.361378 -214.745824)
					(mid 286.372052 -214.808604)
					(end 286.37738 -214.872062)
				)
				(xy 286.377888 -214.87257) (xy 286.377888 -214.88908) (xy 286.377888 -214.902796) (xy 286.377888 -214.907114)
				(xy 286.377888 -215.127078)
				(arc
					(start 286.377888 -215.131396)
					(mid 286.398221 -215.188344)
					(end 286.450024 -215.219534)
				)
				(arc
					(start 286.450024 -215.219534)
					(mid 287.230346 -215.294858)
					(end 286.44977 -215.367616)
				)
				(xy 286.437578 -215.367616)
				(arc
					(start 286.435546 -215.36533)
					(mid 286.300822 -215.298378)
					(end 286.23387 -215.163654)
				)
				(xy 286.231584 -215.161622) (xy 286.231584 -215.139016) (xy 286.231584 -215.131396) (xy 286.231584 -215.127078)
				(xy 286.231584 -214.907114)
				(arc
					(start 286.231584 -214.902796)
					(mid 286.226335 -214.823625)
					(end 286.210756 -214.745824)
				)
				(arc
					(start 286.01035 -214.745824)
					(mid 286.030152 -214.807521)
					(end 286.040068 -214.871554)
				)
				(xy 286.041084 -214.87257) (xy 286.041084 -214.892636) (xy 286.041338 -214.902796) (xy 286.041084 -214.907114)
				(xy 286.041084 -215.127078) (xy 286.041338 -215.131396) (xy 286.041084 -215.139016) (xy 286.041084 -215.161622)
				(arc
					(start 286.039052 -215.163654)
					(mid 285.9721 -215.298378)
					(end 285.837376 -215.36533)
				)
				(xy 285.835344 -215.367616)
				(arc
					(start 285.823406 -215.367616)
					(mid 285.042819 -215.294858)
					(end 285.823152 -215.219534)
				)
				(arc
					(start 285.823152 -215.219534)
					(mid 285.874817 -215.188278)
					(end 285.895034 -215.131396)
				)
				(xy 285.895288 -215.127078) (xy 285.895288 -214.907114)
				(arc
					(start 285.895034 -214.902796)
					(mid 285.881954 -214.82026)
					(end 285.84398 -214.745824)
				)
			)
		)
	)
	(zone
		(layer "In5.Cu")
		(hatch none 0.5)
		(connect_pads
			(clearance 0)
		)
		(min_thickness 0.25)
		(keepout
			(tracks not_allowed)
			(vias allowed)
			(pads allowed)
			(copperpour not_allowed)
			(footprints allowed)
		)
		(placement
			(enabled no)
			(sheetname "")
		)
		(fill
			(thermal_gap 0.5)
			(thermal_bridge_width 0.5)
			(island_removal_mode 0)
		)
		(polygon
			(pts
				(arc
					(start 285.436564 -225.545904)
					(mid 284.887924 -226.094544)
					(end 285.436564 -226.643184)
				)
				(arc
					(start 285.9024 -226.643184)
					(mid 285.898215 -226.608343)
					(end 285.895796 -226.573334)
				)
				(xy 285.895288 -226.572826) (xy 285.895288 -226.555808) (xy 285.895034 -226.5426) (xy 285.895288 -226.538282)
				(xy 285.895288 -226.343718)
				(arc
					(start 285.895034 -226.3394)
					(mid 285.874279 -226.257632)
					(end 285.817056 -226.195636)
				)
				(arc
					(start 285.817056 -226.195636)
					(mid 285.04354 -226.071604)
					(end 285.8262 -226.03841)
				)
				(arc
					(start 285.8262 -226.03841)
					(mid 285.972507 -226.141693)
					(end 286.039814 -226.30765)
				)
				(xy 286.041084 -226.309174) (xy 286.041084 -226.33051) (xy 286.041338 -226.3394) (xy 286.041084 -226.343718)
				(xy 286.041084 -226.538282)
				(arc
					(start 286.041338 -226.5426)
					(mid 286.043721 -226.593108)
					(end 286.050736 -226.643184)
				)
				(arc
					(start 286.246062 -226.643184)
					(mid 286.237745 -226.608967)
					(end 286.232854 -226.574096)
				)
				(xy 286.231584 -226.572826) (xy 286.231584 -226.551998) (xy 286.231584 -226.5426) (xy 286.231584 -226.538282)
				(xy 286.231584 -226.343718) (xy 286.231584 -226.3394) (xy 286.231584 -226.33051) (xy 286.231584 -226.309174)
				(arc
					(start 286.233108 -226.30765)
					(mid 286.300498 -226.141606)
					(end 286.446976 -226.03841)
				)
				(arc
					(start 286.446976 -226.03841)
					(mid 287.229609 -226.071728)
					(end 286.45612 -226.195382)
				)
				(arc
					(start 286.45612 -226.195382)
					(mid 286.398717 -226.257456)
					(end 286.377888 -226.3394)
				)
				(xy 286.377888 -226.343718) (xy 286.377888 -226.538282)
				(arc
					(start 286.377888 -226.5426)
					(mid 286.384446 -226.594487)
					(end 286.403542 -226.643184)
				)
				(arc
					(start 286.836612 -226.643184)
					(mid 287.385252 -226.094544)
					(end 286.836612 -225.545904)
				)
			)
		)
	)
	(zone
		(layer "In5.Cu")
		(hatch none 0.5)
		(connect_pads
			(clearance 0)
		)
		(min_thickness 0.25)
		(keepout
			(tracks not_allowed)
			(vias allowed)
			(pads allowed)
			(copperpour not_allowed)
			(footprints allowed)
		)
		(placement
			(enabled no)
			(sheetname "")
		)
		(fill
			(thermal_gap 0.5)
			(thermal_bridge_width 0.5)
			(island_removal_mode 0)
		)
		(polygon
			(pts
				(arc
					(start 127.64389 -248.115328)
					(mid 127.158877 -247.629934)
					(end 126.67361 -248.115074)
				)
				(arc
					(start 126.67361 -249.385074)
					(mid 127.15875 -249.870214)
					(end 127.64389 -249.385074)
				)
				(xy 127.64389 -248.99112) (xy 127.283718 -248.99112)
				(arc
					(start 127.2794 -248.991374)
					(mid 127.245814 -249.005286)
					(end 127.231902 -249.038872)
				)
				(xy 127.231648 -249.04319)
				(arc
					(start 127.231648 -249.128534)
					(mid 127.15875 -249.65177)
					(end 127.085852 -249.128534)
				)
				(xy 127.085852 -249.04319) (xy 127.085598 -249.038872) (xy 127.085852 -249.03176) (xy 127.085852 -249.008646)
				(arc
					(start 127.088392 -249.005852)
					(mid 127.142334 -248.901806)
					(end 127.24638 -248.847864)
				)
				(xy 127.249174 -248.845324) (xy 127.272288 -248.845324) (xy 127.2794 -248.84507) (xy 127.283718 -248.845324)
				(xy 127.64389 -248.845324) (xy 127.64389 -248.654824) (xy 127.283718 -248.654824) (xy 127.2794 -248.654824)
				(xy 127.272288 -248.654824) (xy 127.249174 -248.654824)
				(arc
					(start 127.24638 -248.65203)
					(mid 127.142334 -248.598088)
					(end 127.088392 -248.494042)
				)
				(xy 127.085852 -248.491248) (xy 127.085852 -248.468134) (xy 127.085598 -248.461022) (xy 127.085852 -248.456704)
				(arc
					(start 127.085852 -248.371614)
					(mid 127.15875 -247.848378)
					(end 127.231648 -248.371614)
				)
				(xy 127.231648 -248.456704)
				(arc
					(start 127.231902 -248.461022)
					(mid 127.245814 -248.494608)
					(end 127.2794 -248.50852)
				)
				(xy 127.283718 -248.50852) (xy 127.64389 -248.50852)
			)
		)
	)
	(zone
		(layer "In5.Cu")
		(hatch none 0.5)
		(connect_pads
			(clearance 0)
		)
		(min_thickness 0.25)
		(keepout
			(tracks not_allowed)
			(vias allowed)
			(pads allowed)
			(copperpour not_allowed)
			(footprints allowed)
		)
		(placement
			(enabled no)
			(sheetname "")
		)
		(fill
			(thermal_gap 0.5)
			(thermal_bridge_width 0.5)
			(island_removal_mode 0)
		)
		(polygon
			(pts
				(arc
					(start 159.193992 -133.11505)
					(mid 158.708852 -132.62991)
					(end 158.223712 -133.11505)
				)
				(arc
					(start 158.223712 -134.384796)
					(mid 158.708725 -134.87019)
					(end 159.193992 -134.38505)
				)
				(xy 159.193992 -133.991096) (xy 158.83382 -133.991096)
				(arc
					(start 158.829502 -133.99135)
					(mid 158.795916 -134.005262)
					(end 158.782004 -134.038848)
				)
				(xy 158.782004 -134.043166)
				(arc
					(start 158.782004 -134.12851)
					(mid 158.708852 -134.651816)
					(end 158.6357 -134.12851)
				)
				(xy 158.6357 -134.043166) (xy 158.6357 -134.038848) (xy 158.6357 -134.031736) (xy 158.6357 -134.008622)
				(arc
					(start 158.638494 -134.005828)
					(mid 158.692436 -133.901782)
					(end 158.796482 -133.84784)
				)
				(xy 158.799276 -133.8453) (xy 158.82239 -133.8453) (xy 158.829502 -133.845046) (xy 158.83382 -133.8453)
				(xy 159.193992 -133.8453) (xy 159.193992 -133.6548) (xy 158.83382 -133.6548) (xy 158.829502 -133.6548)
				(xy 158.82239 -133.6548) (xy 158.799276 -133.6548)
				(arc
					(start 158.796482 -133.652006)
					(mid 158.692436 -133.598064)
					(end 158.638494 -133.494018)
				)
				(xy 158.6357 -133.491224) (xy 158.6357 -133.46811) (xy 158.6357 -133.460998) (xy 158.6357 -133.45668)
				(arc
					(start 158.6357 -133.37159)
					(mid 158.708852 -132.848284)
					(end 158.782004 -133.37159)
				)
				(xy 158.782004 -133.45668)
				(arc
					(start 158.782004 -133.460998)
					(mid 158.795916 -133.494584)
					(end 158.829502 -133.508496)
				)
				(xy 158.83382 -133.508496) (xy 159.193992 -133.508496)
			)
		)
	)
	(zone
		(net "GND")
		(layer "In5.Cu")
		(hatch none 0.5)
		(connect_pads
			(clearance 0.5)
		)
		(min_thickness 0.25)
		(fill yes
			(thermal_gap 0.5)
			(thermal_bridge_width 0.5)
			(island_removal_mode 0)
		)
		(polygon
			(pts
				(arc
					(start 311.999884 -0.763016)
					(mid 311.832312 -0.832426)
					(end 311.762902 -0.999998)
				)
				(arc
					(start 311.762902 -47.200058)
					(mid 311.246527 -48.446697)
					(end 309.999888 -48.963072)
				)
				(arc
					(start 269.999968 -48.963072)
					(mid 269.832396 -49.032482)
					(end 269.762986 -49.200054)
				)
				(arc
					(start 269.762986 -61.999876)
					(mid 269.734433 -62.315889)
					(end 269.649702 -62.621668)
				)
				(arc
					(start 270.967708 -62.621668)
					(mid 271.015916 -62.312433)
					(end 271.03197 -61.999876)
				)
				(xy 271.03197 -50.232056)
				(arc
					(start 309.999888 -50.232056)
					(mid 312.143834 -49.344004)
					(end 313.031886 -47.200058)
				)
				(xy 313.031886 -2.032) (xy 489.418122 -2.032) (xy 489.418122 -96.413574) (xy 489.418122 -119.586502)
				(xy 489.418122 -340.619334) (xy 490.687106 -340.619334) (xy 490.687106 -118.73484) (xy 490.687106 -97.265236)
				(arc
					(start 490.687106 -0.999998)
					(mid 490.617696 -0.832426)
					(end 490.450124 -0.763016)
				)
			)
		)
	)
	(zone
		(layer "In5.Cu")
		(hatch none 0.5)
		(connect_pads
			(clearance 0)
		)
		(min_thickness 0.25)
		(keepout
			(tracks not_allowed)
			(vias allowed)
			(pads allowed)
			(copperpour not_allowed)
			(footprints allowed)
		)
		(placement
			(enabled no)
			(sheetname "")
		)
		(fill
			(thermal_gap 0.5)
			(thermal_bridge_width 0.5)
			(island_removal_mode 0)
		)
		(polygon
			(pts
				(arc
					(start 286.436562 -202.1459)
					(mid 285.887922 -202.69454)
					(end 286.436562 -203.24318)
				)
				(arc
					(start 287.83661 -203.24318)
					(mid 288.38525 -202.69454)
					(end 287.83661 -202.1459)
				)
				(arc
					(start 287.39211 -202.1459)
					(mid 287.38148 -202.180366)
					(end 287.377886 -202.216258)
				)
				(xy 287.377632 -202.220576) (xy 287.377632 -202.46594)
				(arc
					(start 287.377886 -202.470258)
					(mid 287.398326 -202.546155)
					(end 287.454086 -202.601576)
				)
				(arc
					(start 287.454086 -202.601576)
					(mid 288.229995 -202.710984)
					(end 287.447736 -202.756262)
				)
				(arc
					(start 287.447736 -202.756262)
					(mid 287.301691 -202.661903)
					(end 287.23336 -202.502008)
				)
				(xy 287.231836 -202.500484) (xy 287.231836 -202.478894) (xy 287.231582 -202.470258) (xy 287.231836 -202.46594)
				(xy 287.231836 -202.220576) (xy 287.231582 -202.216258) (xy 287.231836 -202.207114) (xy 287.231836 -202.186032)
				(arc
					(start 287.233106 -202.184508)
					(mid 287.235573 -202.165112)
					(end 287.239202 -202.1459)
				)
				(arc
					(start 287.046162 -202.1459)
					(mid 287.042555 -202.180997)
					(end 287.041336 -202.216258)
				)
				(xy 287.041336 -202.220576) (xy 287.041336 -202.46594) (xy 287.041336 -202.470258) (xy 287.041336 -202.478894)
				(xy 287.041336 -202.500484)
				(arc
					(start 287.039558 -202.502008)
					(mid 286.971326 -202.661827)
					(end 286.825436 -202.756262)
				)
				(arc
					(start 286.825436 -202.756262)
					(mid 286.043148 -202.710605)
					(end 286.819086 -202.601322)
				)
				(arc
					(start 286.819086 -202.601322)
					(mid 286.874651 -202.545989)
					(end 286.895032 -202.470258)
				)
				(xy 286.895032 -202.46594) (xy 286.895032 -202.220576) (xy 286.895032 -202.216258) (xy 286.895032 -202.203304)
				(xy 286.895032 -202.186032) (xy 286.895794 -202.185524) (xy 286.898842 -202.1459)
			)
		)
	)
	(zone
		(layer "In5.Cu")
		(hatch none 0.5)
		(connect_pads
			(clearance 0)
		)
		(min_thickness 0.25)
		(keepout
			(tracks not_allowed)
			(vias allowed)
			(pads allowed)
			(copperpour not_allowed)
			(footprints allowed)
		)
		(placement
			(enabled no)
			(sheetname "")
		)
		(fill
			(thermal_gap 0.5)
			(thermal_bridge_width 0.5)
			(island_removal_mode 0)
		)
		(polygon
			(pts
				(arc
					(start 480.431856 -131.951984)
					(mid 479.946462 -132.436997)
					(end 480.431602 -132.922264)
				)
				(xy 480.825048 -132.922264) (xy 480.825048 -132.566918)
				(arc
					(start 480.825048 -132.5626)
					(mid 480.809723 -132.525601)
					(end 480.772724 -132.510276)
				)
				(xy 480.768406 -132.510276)
				(arc
					(start 480.688142 -132.510276)
					(mid 480.164836 -132.437124)
					(end 480.688142 -132.363972)
				)
				(xy 480.768406 -132.363972) (xy 480.772724 -132.363972) (xy 480.779836 -132.363972) (xy 480.80295 -132.363972)
				(arc
					(start 480.80549 -132.366766)
					(mid 480.913124 -132.4222)
					(end 480.968558 -132.529834)
				)
				(xy 480.971352 -132.532374) (xy 480.971352 -132.555488) (xy 480.971352 -132.5626) (xy 480.971352 -132.566918)
				(xy 480.971352 -132.922264) (xy 481.161852 -132.922264) (xy 481.161852 -132.567172) (xy 481.161598 -132.562854)
				(xy 481.161852 -132.555742) (xy 481.161852 -132.532628)
				(arc
					(start 481.164392 -132.530088)
					(mid 481.219902 -132.422276)
					(end 481.327714 -132.366766)
				)
				(xy 481.330254 -132.363972) (xy 481.353368 -132.363972) (xy 481.36048 -132.363972) (xy 481.364798 -132.363972)
				(arc
					(start 481.445062 -132.363972)
					(mid 481.968368 -132.437124)
					(end 481.445062 -132.510276)
				)
				(xy 481.364798 -132.510276)
				(arc
					(start 481.36048 -132.510276)
					(mid 481.323302 -132.525676)
					(end 481.307902 -132.562854)
				)
				(xy 481.307648 -132.567172) (xy 481.307648 -132.922264)
				(arc
					(start 481.701602 -132.922264)
					(mid 482.186742 -132.437124)
					(end 481.701602 -131.951984)
				)
			)
		)
	)
	(zone
		(layer "In5.Cu")
		(hatch none 0.5)
		(connect_pads
			(clearance 0)
		)
		(min_thickness 0.25)
		(keepout
			(tracks not_allowed)
			(vias allowed)
			(pads allowed)
			(copperpour not_allowed)
			(footprints allowed)
		)
		(placement
			(enabled no)
			(sheetname "")
		)
		(fill
			(thermal_gap 0.5)
			(thermal_bridge_width 0.5)
			(island_removal_mode 0)
		)
		(polygon
			(pts
				(arc
					(start 285.436564 -131.545838)
					(mid 284.887924 -132.094478)
					(end 285.436564 -132.643118)
				)
				(arc
					(start 286.836612 -132.643118)
					(mid 287.385252 -132.094478)
					(end 286.836612 -131.545838)
				)
				(xy 286.365188 -131.545838)
				(arc
					(start 286.365188 -131.875276)
					(mid 286.389429 -131.952978)
					(end 286.45358 -132.003038)
				)
				(arc
					(start 286.45358 -132.003038)
					(mid 287.230295 -132.100726)
					(end 286.450786 -132.17271)
				)
				(arc
					(start 286.450786 -132.17271)
					(mid 286.283253 -132.083346)
					(end 286.202374 -131.911598)
				)
				(xy 286.200088 -131.909566) (xy 286.200088 -131.545838) (xy 286.073088 -131.545838) (xy 286.073088 -131.909566)
				(arc
					(start 286.070802 -131.911598)
					(mid 285.989834 -132.083261)
					(end 285.82239 -132.17271)
				)
				(arc
					(start 285.82239 -132.17271)
					(mid 285.04289 -132.100726)
					(end 285.819596 -132.003038)
				)
				(arc
					(start 285.819596 -132.003038)
					(mid 285.883682 -131.952933)
					(end 285.907988 -131.875276)
				)
				(xy 285.907988 -131.545838)
			)
		)
	)
	(zone
		(layer "In5.Cu")
		(hatch none 0.5)
		(connect_pads
			(clearance 0)
		)
		(min_thickness 0.25)
		(keepout
			(tracks not_allowed)
			(vias allowed)
			(pads allowed)
			(copperpour not_allowed)
			(footprints allowed)
		)
		(placement
			(enabled no)
			(sheetname "")
		)
		(fill
			(thermal_gap 0.5)
			(thermal_bridge_width 0.5)
			(island_removal_mode 0)
		)
		(polygon
			(pts
				(arc
					(start 481.824792 -248.115328)
					(mid 481.339779 -247.629934)
					(end 480.854512 -248.115074)
				)
				(xy 480.854512 -248.50852) (xy 481.148136 -248.50852)
				(arc
					(start 481.152454 -248.50852)
					(mid 481.233097 -248.475117)
					(end 481.2665 -248.394474)
				)
				(xy 481.2665 -248.390156)
				(arc
					(start 481.2665 -248.371614)
					(mid 481.339652 -247.848308)
					(end 481.412804 -248.371614)
				)
				(xy 481.412804 -248.390156) (xy 481.412804 -248.394474) (xy 481.412804 -248.402602) (xy 481.412804 -248.4247)
				(arc
					(start 481.410772 -248.426478)
					(mid 481.336509 -248.578529)
					(end 481.184458 -248.652792)
				)
				(xy 481.18268 -248.654824) (xy 481.160582 -248.654824) (xy 481.152454 -248.654824) (xy 481.148136 -248.654824)
				(xy 480.854512 -248.654824) (xy 480.854512 -248.845324) (xy 481.147882 -248.845324) (xy 481.1522 -248.84507)
				(xy 481.160328 -248.845324) (xy 481.182426 -248.845324)
				(arc
					(start 481.184204 -248.847102)
					(mid 481.336433 -248.921441)
					(end 481.410772 -249.07367)
				)
				(xy 481.412804 -249.075448) (xy 481.412804 -249.097546) (xy 481.412804 -249.105674) (xy 481.412804 -249.109992)
				(arc
					(start 481.412804 -249.128534)
					(mid 481.339652 -249.65184)
					(end 481.2665 -249.128534)
				)
				(xy 481.2665 -249.109992)
				(arc
					(start 481.2665 -249.105674)
					(mid 481.233022 -249.024852)
					(end 481.1522 -248.991374)
				)
				(xy 481.147882 -248.99112) (xy 480.854512 -248.99112)
				(arc
					(start 480.854512 -249.385074)
					(mid 481.339652 -249.870214)
					(end 481.824792 -249.385074)
				)
			)
		)
	)
	(zone
		(layer "In5.Cu")
		(hatch none 0.5)
		(connect_pads
			(clearance 0)
		)
		(min_thickness 0.25)
		(keepout
			(tracks not_allowed)
			(vias allowed)
			(pads allowed)
			(copperpour not_allowed)
			(footprints allowed)
		)
		(placement
			(enabled no)
			(sheetname "")
		)
		(fill
			(thermal_gap 0.5)
			(thermal_bridge_width 0.5)
			(island_removal_mode 0)
		)
		(polygon
			(pts
				(arc
					(start 387.17474 -248.115328)
					(mid 386.689727 -247.629934)
					(end 386.20446 -248.115074)
				)
				(xy 386.20446 -248.50852) (xy 386.482336 -248.50852)
				(arc
					(start 386.486654 -248.50852)
					(mid 386.578432 -248.470504)
					(end 386.616448 -248.378726)
				)
				(xy 386.616448 -248.374408)
				(arc
					(start 386.616448 -248.371614)
					(mid 386.6896 -247.848308)
					(end 386.762752 -248.371614)
				)
				(xy 386.762752 -248.374408) (xy 386.762752 -248.378726) (xy 386.762752 -248.387108) (xy 386.762752 -248.408952)
				(arc
					(start 386.760974 -248.41073)
					(mid 386.681943 -248.574015)
					(end 386.518658 -248.653046)
				)
				(xy 386.51688 -248.654824) (xy 386.495036 -248.654824) (xy 386.486654 -248.654824) (xy 386.482336 -248.654824)
				(xy 386.20446 -248.654824) (xy 386.20446 -248.845324) (xy 386.482082 -248.845324) (xy 386.4864 -248.84507)
				(xy 386.494782 -248.845324) (xy 386.516626 -248.845324)
				(arc
					(start 386.518404 -248.846848)
					(mid 386.681868 -248.925954)
					(end 386.760974 -249.089418)
				)
				(xy 386.762752 -249.091196) (xy 386.762752 -249.11304) (xy 386.762752 -249.121422) (xy 386.762752 -249.12574)
				(arc
					(start 386.762752 -249.128534)
					(mid 386.6896 -249.65184)
					(end 386.616448 -249.128534)
				)
				(xy 386.616448 -249.12574)
				(arc
					(start 386.616448 -249.121422)
					(mid 386.578358 -249.029464)
					(end 386.4864 -248.991374)
				)
				(xy 386.482082 -248.99112) (xy 386.20446 -248.99112)
				(arc
					(start 386.20446 -249.385074)
					(mid 386.6896 -249.870214)
					(end 387.17474 -249.385074)
				)
			)
		)
	)
	(zone
		(layer "In5.Cu")
		(hatch none 0.5)
		(connect_pads
			(clearance 0)
		)
		(min_thickness 0.25)
		(keepout
			(tracks not_allowed)
			(vias allowed)
			(pads allowed)
			(copperpour not_allowed)
			(footprints allowed)
		)
		(placement
			(enabled no)
			(sheetname "")
		)
		(fill
			(thermal_gap 0.5)
			(thermal_bridge_width 0.5)
			(island_removal_mode 0)
		)
		(polygon
			(pts
				(arc
					(start 285.436564 -175.145954)
					(mid 284.887924 -175.694594)
					(end 285.436564 -176.243234)
				)
				(arc
					(start 286.836612 -176.243234)
					(mid 287.385252 -175.694594)
					(end 286.836612 -175.145954)
				)
				(xy 286.407098 -175.145954) (xy 286.399224 -175.154082)
				(arc
					(start 286.395922 -175.157384)
					(mid 286.382578 -175.177311)
					(end 286.377888 -175.200818)
				)
				(xy 286.377888 -175.205136) (xy 286.377888 -175.5013)
				(arc
					(start 286.377888 -175.505618)
					(mid 286.397974 -175.570806)
					(end 286.451294 -175.613314)
				)
				(arc
					(start 286.451294 -175.613314)
					(mid 287.230363 -175.700672)
					(end 286.449008 -175.763936)
				)
				(arc
					(start 286.449008 -175.763936)
					(mid 286.303859 -175.686401)
					(end 286.233616 -175.537622)
				)
				(xy 286.231584 -175.535844) (xy 286.231584 -175.513746) (xy 286.231584 -175.505618) (xy 286.231584 -175.5013)
				(xy 286.231584 -175.205136) (xy 286.231584 -175.200818) (xy 286.231584 -175.193706) (xy 286.231584 -175.170592)
				(xy 286.234124 -175.168052) (xy 286.23895 -175.145954)
				(arc
					(start 286.045148 -175.145954)
					(mid 286.04231 -175.173194)
					(end 286.041338 -175.200564)
				)
				(xy 286.041084 -175.204882) (xy 286.041084 -175.5013) (xy 286.041338 -175.505618) (xy 286.041084 -175.513746)
				(xy 286.041084 -175.535844)
				(arc
					(start 286.039306 -175.537622)
					(mid 285.969076 -175.686242)
					(end 285.824168 -175.763936)
				)
				(arc
					(start 285.824168 -175.763936)
					(mid 285.042853 -175.700671)
					(end 285.821882 -175.613314)
				)
				(arc
					(start 285.821882 -175.613314)
					(mid 285.875029 -175.570718)
					(end 285.895034 -175.505618)
				)
				(xy 285.895288 -175.5013) (xy 285.895288 -175.204882) (xy 285.895034 -175.200564) (xy 285.895288 -175.189134)
				(xy 285.895288 -175.170338) (xy 285.89605 -175.169576) (xy 285.897828 -175.145954)
			)
		)
	)
	(zone
		(layer "In5.Cu")
		(hatch none 0.5)
		(connect_pads
			(clearance 0)
		)
		(min_thickness 0.25)
		(keepout
			(tracks not_allowed)
			(vias allowed)
			(pads allowed)
			(copperpour not_allowed)
			(footprints allowed)
		)
		(placement
			(enabled no)
			(sheetname "")
		)
		(fill
			(thermal_gap 0.5)
			(thermal_bridge_width 0.5)
			(island_removal_mode 0)
		)
		(polygon
			(pts
				(arc
					(start 285.436564 -193.145918)
					(mid 284.887924 -193.694558)
					(end 285.436564 -194.243198)
				)
				(arc
					(start 286.836612 -194.243198)
					(mid 287.385252 -193.694558)
					(end 286.836612 -193.145918)
				)
				(arc
					(start 286.361378 -193.145918)
					(mid 286.372052 -193.208698)
					(end 286.37738 -193.272156)
				)
				(xy 286.377888 -193.272664) (xy 286.377888 -193.289174) (xy 286.377888 -193.30289) (xy 286.377888 -193.307208)
				(xy 286.377888 -193.527172)
				(arc
					(start 286.377888 -193.53149)
					(mid 286.398221 -193.588438)
					(end 286.450024 -193.619628)
				)
				(arc
					(start 286.450024 -193.619628)
					(mid 287.230346 -193.695076)
					(end 286.44977 -193.767456)
				)
				(xy 286.437578 -193.767456)
				(arc
					(start 286.435546 -193.765424)
					(mid 286.300822 -193.698472)
					(end 286.23387 -193.563748)
				)
				(xy 286.231584 -193.561716) (xy 286.231584 -193.53911) (xy 286.231584 -193.53149) (xy 286.231584 -193.527172)
				(xy 286.231584 -193.307208)
				(arc
					(start 286.231584 -193.30289)
					(mid 286.226335 -193.223719)
					(end 286.210756 -193.145918)
				)
				(arc
					(start 286.01035 -193.145918)
					(mid 286.030152 -193.207615)
					(end 286.040068 -193.271648)
				)
				(xy 286.041084 -193.272664) (xy 286.041084 -193.29273) (xy 286.041338 -193.30289) (xy 286.041084 -193.307208)
				(xy 286.041084 -193.527172) (xy 286.041338 -193.53149) (xy 286.041084 -193.53911) (xy 286.041084 -193.561716)
				(arc
					(start 286.039052 -193.563748)
					(mid 285.9721 -193.698472)
					(end 285.837376 -193.765424)
				)
				(xy 285.835344 -193.767456)
				(arc
					(start 285.823406 -193.767456)
					(mid 285.042867 -193.695076)
					(end 285.823152 -193.619628)
				)
				(arc
					(start 285.823152 -193.619628)
					(mid 285.874817 -193.588372)
					(end 285.895034 -193.53149)
				)
				(xy 285.895288 -193.527172) (xy 285.895288 -193.307208)
				(arc
					(start 285.895034 -193.30289)
					(mid 285.881954 -193.220354)
					(end 285.84398 -193.145918)
				)
			)
		)
	)
	(zone
		(layer "In5.Cu")
		(hatch none 0.5)
		(connect_pads
			(clearance 0)
		)
		(min_thickness 0.25)
		(keepout
			(tracks not_allowed)
			(vias allowed)
			(pads allowed)
			(copperpour not_allowed)
			(footprints allowed)
		)
		(placement
			(enabled no)
			(sheetname "")
		)
		(fill
			(thermal_gap 0.5)
			(thermal_bridge_width 0.5)
			(island_removal_mode 0)
		)
		(polygon
			(pts
				(arc
					(start 286.436562 -144.145762)
					(mid 285.887922 -144.694402)
					(end 286.436562 -145.243042)
				)
				(arc
					(start 287.83661 -145.243042)
					(mid 288.38525 -144.694402)
					(end 287.83661 -144.145762)
				)
				(arc
					(start 287.349184 -144.145762)
					(mid 287.35916 -144.203747)
					(end 287.364424 -144.262348)
				)
				(xy 287.365186 -144.26311)
				(arc
					(start 287.365186 -144.4752)
					(mid 287.389427 -144.552902)
					(end 287.453578 -144.602962)
				)
				(arc
					(start 287.453578 -144.602962)
					(mid 288.230293 -144.70065)
					(end 287.450784 -144.772634)
				)
				(arc
					(start 287.450784 -144.772634)
					(mid 287.283251 -144.68327)
					(end 287.202372 -144.511522)
				)
				(xy 287.200086 -144.50949)
				(arc
					(start 287.200086 -144.2974)
					(mid 287.194929 -144.220886)
					(end 287.179512 -144.145762)
				)
				(arc
					(start 287.046162 -144.145762)
					(mid 287.062811 -144.202937)
					(end 287.071562 -144.26184)
				)
				(xy 287.073086 -144.26311) (xy 287.073086 -144.50949)
				(arc
					(start 287.0708 -144.511522)
					(mid 286.989832 -144.683185)
					(end 286.822388 -144.772634)
				)
				(arc
					(start 286.822388 -144.772634)
					(mid 286.042888 -144.70065)
					(end 286.819594 -144.602962)
				)
				(arc
					(start 286.819594 -144.602962)
					(mid 286.88368 -144.552857)
					(end 286.907986 -144.4752)
				)
				(arc
					(start 286.907986 -144.2974)
					(mid 286.896307 -144.21821)
					(end 286.862266 -144.145762)
				)
			)
		)
	)
	(zone
		(layer "In5.Cu")
		(hatch none 0.5)
		(connect_pads
			(clearance 0)
		)
		(min_thickness 0.25)
		(keepout
			(tracks not_allowed)
			(vias allowed)
			(pads allowed)
			(copperpour not_allowed)
			(footprints allowed)
		)
		(placement
			(enabled no)
			(sheetname "")
		)
		(fill
			(thermal_gap 0.5)
			(thermal_bridge_width 0.5)
			(island_removal_mode 0)
		)
		(polygon
			(pts
				(arc
					(start 286.436562 -212.945726)
					(mid 285.887922 -213.494366)
					(end 286.436562 -214.043006)
				)
				(arc
					(start 287.83661 -214.043006)
					(mid 288.38525 -213.494366)
					(end 287.83661 -212.945726)
				)
				(arc
					(start 287.361376 -212.945726)
					(mid 287.37205 -213.008506)
					(end 287.377378 -213.071964)
				)
				(xy 287.377632 -213.072472) (xy 287.377632 -213.088982) (xy 287.377886 -213.102698) (xy 287.377632 -213.107016)
				(xy 287.377632 -213.32698)
				(arc
					(start 287.377886 -213.331298)
					(mid 287.398219 -213.388246)
					(end 287.450022 -213.419436)
				)
				(arc
					(start 287.450022 -213.419436)
					(mid 288.230344 -213.494884)
					(end 287.449768 -213.567264)
				)
				(xy 287.437576 -213.567264)
				(arc
					(start 287.435544 -213.565232)
					(mid 287.30082 -213.49828)
					(end 287.233868 -213.363556)
				)
				(xy 287.231836 -213.361524) (xy 287.231836 -213.338918) (xy 287.231582 -213.331298) (xy 287.231836 -213.32698)
				(xy 287.231836 -213.107016)
				(arc
					(start 287.231582 -213.102698)
					(mid 287.226333 -213.023527)
					(end 287.210754 -212.945726)
				)
				(arc
					(start 287.010348 -212.945726)
					(mid 287.03015 -213.007423)
					(end 287.040066 -213.071456)
				)
				(xy 287.041336 -213.072472) (xy 287.041336 -213.092538) (xy 287.041336 -213.102698) (xy 287.041336 -213.107016)
				(xy 287.041336 -213.32698) (xy 287.041336 -213.331298) (xy 287.041336 -213.338918) (xy 287.041336 -213.361524)
				(arc
					(start 287.03905 -213.363556)
					(mid 286.972098 -213.49828)
					(end 286.837374 -213.565232)
				)
				(xy 286.835342 -213.567264)
				(arc
					(start 286.823404 -213.567264)
					(mid 286.042865 -213.494884)
					(end 286.82315 -213.419436)
				)
				(arc
					(start 286.82315 -213.419436)
					(mid 286.874815 -213.38818)
					(end 286.895032 -213.331298)
				)
				(xy 286.895032 -213.32698) (xy 286.895032 -213.107016)
				(arc
					(start 286.895032 -213.102698)
					(mid 286.881952 -213.020162)
					(end 286.843978 -212.945726)
				)
			)
		)
	)
	(zone
		(layer "In5.Cu")
		(hatch none 0.5)
		(connect_pads
			(clearance 0)
		)
		(min_thickness 0.25)
		(keepout
			(tracks not_allowed)
			(vias allowed)
			(pads allowed)
			(copperpour not_allowed)
			(footprints allowed)
		)
		(placement
			(enabled no)
			(sheetname "")
		)
		(fill
			(thermal_gap 0.5)
			(thermal_bridge_width 0.5)
			(island_removal_mode 0)
		)
		(polygon
			(pts
				(arc
					(start 127.64389 -133.11505)
					(mid 127.15875 -132.62991)
					(end 126.67361 -133.11505)
				)
				(arc
					(start 126.67361 -134.384796)
					(mid 127.158623 -134.87019)
					(end 127.64389 -134.38505)
				)
				(xy 127.64389 -133.991096) (xy 127.283718 -133.991096)
				(arc
					(start 127.2794 -133.99135)
					(mid 127.245814 -134.005262)
					(end 127.231902 -134.038848)
				)
				(xy 127.231648 -134.043166)
				(arc
					(start 127.231648 -134.12851)
					(mid 127.15875 -134.651746)
					(end 127.085852 -134.12851)
				)
				(xy 127.085852 -134.043166) (xy 127.085598 -134.038848) (xy 127.085852 -134.031736) (xy 127.085852 -134.008622)
				(arc
					(start 127.088392 -134.005828)
					(mid 127.142334 -133.901782)
					(end 127.24638 -133.84784)
				)
				(xy 127.249174 -133.8453) (xy 127.272288 -133.8453) (xy 127.2794 -133.845046) (xy 127.283718 -133.8453)
				(xy 127.64389 -133.8453) (xy 127.64389 -133.6548) (xy 127.283718 -133.6548) (xy 127.2794 -133.6548)
				(xy 127.272288 -133.6548) (xy 127.249174 -133.6548)
				(arc
					(start 127.24638 -133.652006)
					(mid 127.142334 -133.598064)
					(end 127.088392 -133.494018)
				)
				(xy 127.085852 -133.491224) (xy 127.085852 -133.46811) (xy 127.085598 -133.460998) (xy 127.085852 -133.45668)
				(arc
					(start 127.085852 -133.37159)
					(mid 127.15875 -132.848354)
					(end 127.231648 -133.37159)
				)
				(xy 127.231648 -133.45668)
				(arc
					(start 127.231902 -133.460998)
					(mid 127.245814 -133.494584)
					(end 127.2794 -133.508496)
				)
				(xy 127.283718 -133.508496) (xy 127.64389 -133.508496)
			)
		)
	)
	(zone
		(layer "In5.Cu")
		(hatch none 0.5)
		(connect_pads
			(clearance 0)
		)
		(min_thickness 0.25)
		(keepout
			(tracks not_allowed)
			(vias allowed)
			(pads allowed)
			(copperpour not_allowed)
			(footprints allowed)
		)
		(placement
			(enabled no)
			(sheetname "")
		)
		(fill
			(thermal_gap 0.5)
			(thermal_bridge_width 0.5)
			(island_removal_mode 0)
		)
		(polygon
			(pts
				(arc
					(start 285.436564 -218.345766)
					(mid 284.887924 -218.894406)
					(end 285.436564 -219.443046)
				)
				(arc
					(start 285.900876 -219.443046)
					(mid 285.89772 -219.414144)
					(end 285.895796 -219.385134)
				)
				(xy 285.895288 -219.384626) (xy 285.895288 -219.367608) (xy 285.895034 -219.3544) (xy 285.895288 -219.350082)
				(xy 285.895288 -219.104718)
				(arc
					(start 285.895034 -219.1004)
					(mid 285.874895 -219.030079)
					(end 285.820612 -218.98102)
				)
				(arc
					(start 285.820612 -218.98102)
					(mid 285.04301 -218.88392)
					(end 285.824676 -218.828366)
				)
				(arc
					(start 285.824676 -218.828366)
					(mid 285.970193 -218.914276)
					(end 286.03956 -219.068396)
				)
				(xy 286.041084 -219.070174) (xy 286.041084 -219.092018) (xy 286.041338 -219.1004) (xy 286.041084 -219.104718)
				(xy 286.041084 -219.350082)
				(arc
					(start 286.041338 -219.3544)
					(mid 286.043168 -219.398877)
					(end 286.048704 -219.443046)
				)
				(arc
					(start 286.243268 -219.443046)
					(mid 286.23699 -219.414684)
					(end 286.233108 -219.385896)
				)
				(xy 286.231584 -219.384626) (xy 286.231584 -219.363798) (xy 286.231584 -219.3544) (xy 286.231584 -219.350082)
				(xy 286.231584 -219.104718) (xy 286.231584 -219.1004) (xy 286.231584 -219.092018) (xy 286.231584 -219.070174)
				(arc
					(start 286.233362 -219.068396)
					(mid 286.302744 -218.914123)
					(end 286.4485 -218.828366)
				)
				(arc
					(start 286.4485 -218.828366)
					(mid 287.230163 -218.88392)
					(end 286.452564 -218.98102)
				)
				(arc
					(start 286.452564 -218.98102)
					(mid 286.398126 -219.030006)
					(end 286.377888 -219.1004)
				)
				(xy 286.377888 -219.104718) (xy 286.377888 -219.350082)
				(arc
					(start 286.377888 -219.3544)
					(mid 286.383175 -219.399925)
					(end 286.398716 -219.443046)
				)
				(arc
					(start 286.836612 -219.443046)
					(mid 287.385252 -218.894406)
					(end 286.836612 -218.345766)
				)
			)
		)
	)
	(zone
		(layer "In5.Cu")
		(hatch none 0.5)
		(connect_pads
			(clearance 0)
		)
		(min_thickness 0.25)
		(keepout
			(tracks not_allowed)
			(vias allowed)
			(pads allowed)
			(copperpour not_allowed)
			(footprints allowed)
		)
		(placement
			(enabled no)
			(sheetname "")
		)
		(fill
			(thermal_gap 0.5)
			(thermal_bridge_width 0.5)
			(island_removal_mode 0)
		)
		(polygon
			(pts
				(arc
					(start 96.094042 -133.11505)
					(mid 95.608902 -132.62991)
					(end 95.123762 -133.11505)
				)
				(arc
					(start 95.123762 -134.384796)
					(mid 95.608775 -134.87019)
					(end 96.094042 -134.38505)
				)
				(xy 96.094042 -133.991096) (xy 95.73387 -133.991096)
				(arc
					(start 95.729552 -133.99135)
					(mid 95.695966 -134.005262)
					(end 95.682054 -134.038848)
				)
				(xy 95.6818 -134.043166)
				(arc
					(start 95.6818 -134.12851)
					(mid 95.608902 -134.651746)
					(end 95.536004 -134.12851)
				)
				(xy 95.536004 -134.043166) (xy 95.53575 -134.038848) (xy 95.536004 -134.031736) (xy 95.536004 -134.008622)
				(arc
					(start 95.538544 -134.005828)
					(mid 95.592486 -133.901782)
					(end 95.696532 -133.84784)
				)
				(xy 95.699326 -133.8453) (xy 95.72244 -133.8453) (xy 95.729552 -133.845046) (xy 95.73387 -133.8453)
				(xy 96.094042 -133.8453) (xy 96.094042 -133.6548) (xy 95.73387 -133.6548) (xy 95.729552 -133.6548)
				(xy 95.72244 -133.6548) (xy 95.699326 -133.6548)
				(arc
					(start 95.696532 -133.652006)
					(mid 95.592486 -133.598064)
					(end 95.538544 -133.494018)
				)
				(xy 95.536004 -133.491224) (xy 95.536004 -133.46811) (xy 95.53575 -133.460998) (xy 95.536004 -133.45668)
				(arc
					(start 95.536004 -133.37159)
					(mid 95.608902 -132.848354)
					(end 95.6818 -133.37159)
				)
				(xy 95.6818 -133.45668)
				(arc
					(start 95.682054 -133.460998)
					(mid 95.695966 -133.494584)
					(end 95.729552 -133.508496)
				)
				(xy 95.73387 -133.508496) (xy 96.094042 -133.508496)
			)
		)
	)
	(zone
		(layer "In5.Cu")
		(hatch none 0.5)
		(connect_pads
			(clearance 0)
		)
		(min_thickness 0.25)
		(keepout
			(tracks not_allowed)
			(vias allowed)
			(pads allowed)
			(copperpour not_allowed)
			(footprints allowed)
		)
		(placement
			(enabled no)
			(sheetname "")
		)
		(fill
			(thermal_gap 0.5)
			(thermal_bridge_width 0.5)
			(island_removal_mode 0)
		)
		(polygon
			(pts
				(arc
					(start 285.436564 -182.345838)
					(mid 284.887924 -182.894478)
					(end 285.436564 -183.443118)
				)
				(arc
					(start 286.836612 -183.443118)
					(mid 287.385252 -182.894478)
					(end 286.836612 -182.345838)
				)
				(arc
					(start 286.387286 -182.345838)
					(mid 286.380255 -182.37287)
					(end 286.377888 -182.400702)
				)
				(xy 286.377888 -182.40502) (xy 286.377888 -182.701184)
				(arc
					(start 286.377888 -182.705502)
					(mid 286.397974 -182.77069)
					(end 286.451294 -182.813198)
				)
				(arc
					(start 286.451294 -182.813198)
					(mid 287.230363 -182.900556)
					(end 286.449008 -182.96382)
				)
				(arc
					(start 286.449008 -182.96382)
					(mid 286.303859 -182.886285)
					(end 286.233616 -182.737506)
				)
				(xy 286.231584 -182.735728) (xy 286.231584 -182.71363) (xy 286.231584 -182.705502) (xy 286.231584 -182.701184)
				(xy 286.231584 -182.40502) (xy 286.231584 -182.400702) (xy 286.231584 -182.391812) (xy 286.231584 -182.370476)
				(xy 286.233108 -182.368952) (xy 286.23641 -182.345838)
				(arc
					(start 286.044386 -182.345838)
					(mid 286.042114 -182.373228)
					(end 286.041338 -182.400702)
				)
				(xy 286.041084 -182.40502) (xy 286.041084 -182.701184) (xy 286.041338 -182.705502) (xy 286.041084 -182.71363)
				(xy 286.041084 -182.735728)
				(arc
					(start 286.039306 -182.737506)
					(mid 285.969076 -182.886126)
					(end 285.824168 -182.96382)
				)
				(arc
					(start 285.824168 -182.96382)
					(mid 285.042853 -182.900555)
					(end 285.821882 -182.813198)
				)
				(arc
					(start 285.821882 -182.813198)
					(mid 285.875029 -182.770602)
					(end 285.895034 -182.705502)
				)
				(xy 285.895288 -182.701184) (xy 285.895288 -182.40502) (xy 285.895034 -182.400702) (xy 285.895288 -182.388002)
				(xy 285.895288 -182.370476) (xy 285.895796 -182.369968) (xy 285.89732 -182.345838)
			)
		)
	)
	(zone
		(layer "In5.Cu")
		(hatch none 0.5)
		(connect_pads
			(clearance 0)
		)
		(min_thickness 0.25)
		(keepout
			(tracks not_allowed)
			(vias allowed)
			(pads allowed)
			(copperpour not_allowed)
			(footprints allowed)
		)
		(placement
			(enabled no)
			(sheetname "")
		)
		(fill
			(thermal_gap 0.5)
			(thermal_bridge_width 0.5)
			(island_removal_mode 0)
		)
		(polygon
			(pts
				(arc
					(start 214.14867 -70.39991)
					(mid 213.60003 -69.85127)
					(end 213.05139 -70.39991)
				)
				(arc
					(start 213.05139 -71.799704)
					(mid 213.599903 -72.348598)
					(end 214.14867 -71.799958)
				)
				(arc
					(start 214.14867 -71.385938)
					(mid 214.065099 -71.343191)
					(end 213.972394 -71.328534)
				)
				(arc
					(start 213.784942 -71.328534)
					(mid 213.718364 -71.353144)
					(end 213.68385 -71.415148)
				)
				(arc
					(start 213.68385 -71.415148)
					(mid 213.599382 -72.193791)
					(end 213.51748 -71.414894)
				)
				(xy 213.51748 -71.396606)
				(arc
					(start 213.52002 -71.394066)
					(mid 213.595812 -71.241766)
					(end 213.748112 -71.165974)
				)
				(xy 213.750652 -71.163434) (xy 214.006684 -71.163434)
				(arc
					(start 214.007954 -71.164704)
					(mid 214.079631 -71.175938)
					(end 214.14867 -71.198232)
				)
				(arc
					(start 214.14867 -71.063358)
					(mid 214.061552 -71.043222)
					(end 213.972394 -71.036434)
				)
				(xy 213.750652 -71.036434)
				(arc
					(start 213.748112 -71.033894)
					(mid 213.595812 -70.958102)
					(end 213.52002 -70.805802)
				)
				(xy 213.51748 -70.803262)
				(arc
					(start 213.51748 -70.784974)
					(mid 213.599383 -70.006097)
					(end 213.68385 -70.78472)
				)
				(arc
					(start 213.68385 -70.78472)
					(mid 213.718397 -70.846686)
					(end 213.784942 -70.871334)
				)
				(xy 214.006684 -70.871334)
				(arc
					(start 214.007446 -70.872096)
					(mid 214.078532 -70.878793)
					(end 214.14867 -70.892162)
				)
			)
		)
	)
	(zone
		(layer "In5.Cu")
		(hatch none 0.5)
		(connect_pads
			(clearance 0)
		)
		(min_thickness 0.25)
		(keepout
			(tracks not_allowed)
			(vias allowed)
			(pads allowed)
			(copperpour not_allowed)
			(footprints allowed)
		)
		(placement
			(enabled no)
			(sheetname "")
		)
		(fill
			(thermal_gap 0.5)
			(thermal_bridge_width 0.5)
			(island_removal_mode 0)
		)
		(polygon
			(pts
				(arc
					(start 322.6816 -16.95196)
					(mid 322.19646 -17.4371)
					(end 322.6816 -17.92224)
				)
				(xy 323.0753 -17.92224) (xy 323.0753 -17.590516)
				(arc
					(start 323.075046 -17.586198)
					(mid 323.052802 -17.532496)
					(end 322.9991 -17.510252)
				)
				(xy 322.994782 -17.510252)
				(arc
					(start 322.93814 -17.510252)
					(mid 322.414834 -17.4371)
					(end 322.93814 -17.363948)
				)
				(xy 322.994782 -17.363948) (xy 322.9991 -17.363948) (xy 323.00672 -17.363948) (xy 323.029326 -17.363948)
				(arc
					(start 323.031612 -17.366234)
					(mid 323.156328 -17.42897)
					(end 323.219064 -17.553686)
				)
				(xy 323.221096 -17.555972) (xy 323.221096 -17.578578) (xy 323.22135 -17.586198) (xy 323.221096 -17.590516)
				(xy 323.221096 -17.92224) (xy 323.411596 -17.92224) (xy 323.411596 -17.59077) (xy 323.411596 -17.586452)
				(xy 323.411596 -17.578832) (xy 323.411596 -17.556226)
				(arc
					(start 323.413882 -17.55394)
					(mid 323.476694 -17.429046)
					(end 323.601588 -17.366234)
				)
				(xy 323.603874 -17.363948) (xy 323.62648 -17.363948) (xy 323.6341 -17.363948) (xy 323.638418 -17.363948)
				(arc
					(start 323.69506 -17.363948)
					(mid 324.218366 -17.4371)
					(end 323.69506 -17.510252)
				)
				(xy 323.638418 -17.510252)
				(arc
					(start 323.6341 -17.510252)
					(mid 323.580218 -17.53257)
					(end 323.5579 -17.586452)
				)
				(xy 323.5579 -17.59077) (xy 323.5579 -17.92224)
				(arc
					(start 323.951346 -17.92224)
					(mid 324.43674 -17.437227)
					(end 323.9516 -16.95196)
				)
			)
		)
	)
	(zone
		(layer "In5.Cu")
		(hatch none 0.5)
		(connect_pads
			(clearance 0)
		)
		(min_thickness 0.25)
		(keepout
			(tracks not_allowed)
			(vias allowed)
			(pads allowed)
			(copperpour not_allowed)
			(footprints allowed)
		)
		(placement
			(enabled no)
			(sheetname "")
		)
		(fill
			(thermal_gap 0.5)
			(thermal_bridge_width 0.5)
			(island_removal_mode 0)
		)
		(polygon
			(pts
				(arc
					(start 64.54394 -248.115328)
					(mid 64.058927 -247.629934)
					(end 63.57366 -248.115074)
				)
				(arc
					(start 63.57366 -249.385074)
					(mid 64.0588 -249.870214)
					(end 64.54394 -249.385074)
				)
				(xy 64.54394 -248.99112) (xy 64.183768 -248.99112)
				(arc
					(start 64.17945 -248.991374)
					(mid 64.145864 -249.005286)
					(end 64.131952 -249.038872)
				)
				(xy 64.131952 -249.04319)
				(arc
					(start 64.131952 -249.128534)
					(mid 64.0588 -249.65184)
					(end 63.985648 -249.128534)
				)
				(xy 63.985648 -249.04319) (xy 63.985648 -249.038872) (xy 63.985648 -249.03176) (xy 63.985648 -249.008646)
				(arc
					(start 63.988442 -249.005852)
					(mid 64.042384 -248.901806)
					(end 64.14643 -248.847864)
				)
				(xy 64.149224 -248.845324) (xy 64.172338 -248.845324) (xy 64.17945 -248.84507) (xy 64.183768 -248.845324)
				(xy 64.54394 -248.845324) (xy 64.54394 -248.654824) (xy 64.183768 -248.654824) (xy 64.17945 -248.654824)
				(xy 64.172338 -248.654824) (xy 64.149224 -248.654824)
				(arc
					(start 64.14643 -248.65203)
					(mid 64.042384 -248.598088)
					(end 63.988442 -248.494042)
				)
				(xy 63.985648 -248.491248) (xy 63.985648 -248.468134) (xy 63.985648 -248.461022) (xy 63.985648 -248.456704)
				(arc
					(start 63.985648 -248.371614)
					(mid 64.0588 -247.848308)
					(end 64.131952 -248.371614)
				)
				(xy 64.131952 -248.456704)
				(arc
					(start 64.131952 -248.461022)
					(mid 64.145864 -248.494608)
					(end 64.17945 -248.50852)
				)
				(xy 64.183768 -248.50852) (xy 64.54394 -248.50852)
			)
		)
	)
	(zone
		(layer "In5.Cu")
		(hatch none 0.5)
		(connect_pads
			(clearance 0)
		)
		(min_thickness 0.25)
		(keepout
			(tracks not_allowed)
			(vias allowed)
			(pads allowed)
			(copperpour not_allowed)
			(footprints allowed)
		)
		(placement
			(enabled no)
			(sheetname "")
		)
		(fill
			(thermal_gap 0.5)
			(thermal_bridge_width 0.5)
			(island_removal_mode 0)
		)
		(polygon
			(pts
				(arc
					(start 286.436562 -234.545886)
					(mid 285.887922 -235.094526)
					(end 286.436562 -235.643166)
				)
				(arc
					(start 287.83661 -235.643166)
					(mid 288.38525 -235.094526)
					(end 287.83661 -234.545886)
				)
				(arc
					(start 287.361376 -234.545886)
					(mid 287.37205 -234.608666)
					(end 287.377378 -234.672124)
				)
				(xy 287.377632 -234.672632) (xy 287.377632 -234.689142) (xy 287.377886 -234.702858) (xy 287.377632 -234.707176)
				(xy 287.377632 -234.92714)
				(arc
					(start 287.377886 -234.931458)
					(mid 287.398219 -234.988406)
					(end 287.450022 -235.019596)
				)
				(arc
					(start 287.450022 -235.019596)
					(mid 288.230344 -235.095044)
					(end 287.449768 -235.167424)
				)
				(xy 287.437576 -235.167424)
				(arc
					(start 287.435544 -235.165392)
					(mid 287.30082 -235.09844)
					(end 287.233868 -234.963716)
				)
				(xy 287.231836 -234.961684) (xy 287.231836 -234.939078) (xy 287.231582 -234.931458) (xy 287.231836 -234.92714)
				(xy 287.231836 -234.707176)
				(arc
					(start 287.231582 -234.702858)
					(mid 287.226333 -234.623687)
					(end 287.210754 -234.545886)
				)
				(arc
					(start 287.010348 -234.545886)
					(mid 287.03015 -234.607583)
					(end 287.040066 -234.671616)
				)
				(xy 287.041336 -234.672632) (xy 287.041336 -234.692698) (xy 287.041336 -234.702858) (xy 287.041336 -234.707176)
				(xy 287.041336 -234.92714) (xy 287.041336 -234.931458) (xy 287.041336 -234.939078) (xy 287.041336 -234.961684)
				(arc
					(start 287.03905 -234.963716)
					(mid 286.972098 -235.09844)
					(end 286.837374 -235.165392)
				)
				(xy 286.835342 -235.167424)
				(arc
					(start 286.823404 -235.167424)
					(mid 286.042865 -235.095044)
					(end 286.82315 -235.019596)
				)
				(arc
					(start 286.82315 -235.019596)
					(mid 286.874815 -234.98834)
					(end 286.895032 -234.931458)
				)
				(xy 286.895032 -234.92714) (xy 286.895032 -234.707176)
				(arc
					(start 286.895032 -234.702858)
					(mid 286.881952 -234.620322)
					(end 286.843978 -234.545886)
				)
			)
		)
	)
	(zone
		(layer "In5.Cu")
		(hatch none 0.5)
		(connect_pads
			(clearance 0)
		)
		(min_thickness 0.25)
		(keepout
			(tracks not_allowed)
			(vias allowed)
			(pads allowed)
			(copperpour not_allowed)
			(footprints allowed)
		)
		(placement
			(enabled no)
			(sheetname "")
		)
		(fill
			(thermal_gap 0.5)
			(thermal_bridge_width 0.5)
			(island_removal_mode 0)
		)
		(polygon
			(pts
				(arc
					(start 417.331906 -16.95196)
					(mid 416.846512 -17.436973)
					(end 417.331652 -17.92224)
				)
				(xy 417.725352 -17.92224) (xy 417.725352 -17.581118)
				(arc
					(start 417.725098 -17.5768)
					(mid 417.705607 -17.529743)
					(end 417.65855 -17.510252)
				)
				(xy 417.654232 -17.510252)
				(arc
					(start 417.588192 -17.510252)
					(mid 417.064886 -17.4371)
					(end 417.588192 -17.363948)
				)
				(xy 417.654232 -17.363948) (xy 417.65855 -17.363948) (xy 417.665916 -17.363948) (xy 417.688776 -17.363948)
				(arc
					(start 417.691062 -17.366488)
					(mid 417.80903 -17.42632)
					(end 417.868862 -17.544288)
				)
				(xy 417.871148 -17.546574) (xy 417.871148 -17.569434) (xy 417.871402 -17.5768) (xy 417.871148 -17.581118)
				(xy 417.871148 -17.92224) (xy 418.061648 -17.92224) (xy 418.061648 -17.581372) (xy 418.061648 -17.577054)
				(xy 418.061648 -17.569688) (xy 418.061648 -17.546828)
				(arc
					(start 418.064188 -17.544542)
					(mid 418.124097 -17.426397)
					(end 418.242242 -17.366488)
				)
				(xy 418.244528 -17.363948) (xy 418.267388 -17.363948) (xy 418.274754 -17.363948) (xy 418.279072 -17.363948)
				(arc
					(start 418.345112 -17.363948)
					(mid 418.868418 -17.4371)
					(end 418.345112 -17.510252)
				)
				(xy 418.279072 -17.510252)
				(arc
					(start 418.274754 -17.510252)
					(mid 418.227518 -17.529818)
					(end 418.207952 -17.577054)
				)
				(xy 418.207952 -17.581372) (xy 418.207952 -17.92224)
				(arc
					(start 418.601652 -17.92224)
					(mid 419.086792 -17.4371)
					(end 418.601652 -16.95196)
				)
			)
		)
	)
	(zone
		(layer "In5.Cu")
		(hatch none 0.5)
		(connect_pads
			(clearance 0)
		)
		(min_thickness 0.25)
		(keepout
			(tracks not_allowed)
			(vias allowed)
			(pads allowed)
			(copperpour not_allowed)
			(footprints allowed)
		)
		(placement
			(enabled no)
			(sheetname "")
		)
		(fill
			(thermal_gap 0.5)
			(thermal_bridge_width 0.5)
			(island_removal_mode 0)
		)
		(polygon
			(pts
				(arc
					(start 324.07479 -248.115328)
					(mid 323.589777 -247.629934)
					(end 323.10451 -248.115074)
				)
				(xy 323.10451 -248.50852) (xy 323.464682 -248.50852)
				(arc
					(start 323.469 -248.50852)
					(mid 323.502586 -248.494608)
					(end 323.516498 -248.461022)
				)
				(xy 323.516752 -248.456704)
				(arc
					(start 323.516752 -248.371614)
					(mid 323.58965 -247.848378)
					(end 323.662548 -248.371614)
				)
				(xy 323.662548 -248.456704) (xy 323.662802 -248.461022) (xy 323.662548 -248.468134) (xy 323.662548 -248.491248)
				(arc
					(start 323.660008 -248.494042)
					(mid 323.606066 -248.598088)
					(end 323.50202 -248.65203)
				)
				(xy 323.499226 -248.654824) (xy 323.476112 -248.654824) (xy 323.469 -248.654824) (xy 323.464682 -248.654824)
				(xy 323.10451 -248.654824) (xy 323.10451 -248.845324) (xy 323.464682 -248.845324) (xy 323.469 -248.84507)
				(xy 323.476112 -248.845324) (xy 323.499226 -248.845324)
				(arc
					(start 323.50202 -248.847864)
					(mid 323.606066 -248.901806)
					(end 323.660008 -249.005852)
				)
				(xy 323.662548 -249.008646) (xy 323.662548 -249.03176) (xy 323.662802 -249.038872) (xy 323.662548 -249.04319)
				(arc
					(start 323.662548 -249.128534)
					(mid 323.58965 -249.65177)
					(end 323.516752 -249.128534)
				)
				(xy 323.516752 -249.04319)
				(arc
					(start 323.516498 -249.038872)
					(mid 323.502586 -249.005286)
					(end 323.469 -248.991374)
				)
				(xy 323.464682 -248.99112) (xy 323.10451 -248.99112)
				(arc
					(start 323.10451 -249.385074)
					(mid 323.58965 -249.870214)
					(end 324.07479 -249.385074)
				)
			)
		)
	)
	(zone
		(layer "In5.Cu")
		(hatch none 0.5)
		(connect_pads
			(clearance 0)
		)
		(min_thickness 0.25)
		(keepout
			(tracks not_allowed)
			(vias allowed)
			(pads allowed)
			(copperpour not_allowed)
			(footprints allowed)
		)
		(placement
			(enabled no)
			(sheetname "")
		)
		(fill
			(thermal_gap 0.5)
			(thermal_bridge_width 0.5)
			(island_removal_mode 0)
		)
		(polygon
			(pts
				(arc
					(start 96.094042 -18.11528)
					(mid 95.609029 -17.629886)
					(end 95.123762 -18.115026)
				)
				(arc
					(start 95.123762 -19.385026)
					(mid 95.608902 -19.870166)
					(end 96.094042 -19.385026)
				)
				(xy 96.094042 -18.991072) (xy 95.73387 -18.991072)
				(arc
					(start 95.729552 -18.991326)
					(mid 95.695966 -19.005238)
					(end 95.682054 -19.038824)
				)
				(xy 95.6818 -19.043142)
				(arc
					(start 95.6818 -19.128486)
					(mid 95.608902 -19.651722)
					(end 95.536004 -19.128486)
				)
				(xy 95.536004 -19.043142) (xy 95.53575 -19.038824) (xy 95.536004 -19.031712) (xy 95.536004 -19.008598)
				(arc
					(start 95.538544 -19.005804)
					(mid 95.592486 -18.901758)
					(end 95.696532 -18.847816)
				)
				(xy 95.699326 -18.845276) (xy 95.72244 -18.845276) (xy 95.729552 -18.845022) (xy 95.73387 -18.845276)
				(xy 96.094042 -18.845276) (xy 96.094042 -18.654776) (xy 95.73387 -18.654776) (xy 95.729552 -18.654776)
				(xy 95.72244 -18.654776) (xy 95.699326 -18.654776)
				(arc
					(start 95.696532 -18.651982)
					(mid 95.592486 -18.59804)
					(end 95.538544 -18.493994)
				)
				(xy 95.536004 -18.4912) (xy 95.536004 -18.468086) (xy 95.53575 -18.460974) (xy 95.536004 -18.456656)
				(arc
					(start 95.536004 -18.371566)
					(mid 95.608902 -17.84833)
					(end 95.6818 -18.371566)
				)
				(xy 95.6818 -18.456656)
				(arc
					(start 95.682054 -18.460974)
					(mid 95.695966 -18.49456)
					(end 95.729552 -18.508472)
				)
				(xy 95.73387 -18.508472) (xy 96.094042 -18.508472)
			)
		)
	)
	(zone
		(layer "In5.Cu")
		(hatch none 0.5)
		(connect_pads
			(clearance 0)
		)
		(min_thickness 0.25)
		(keepout
			(tracks not_allowed)
			(vias allowed)
			(pads allowed)
			(copperpour not_allowed)
			(footprints allowed)
		)
		(placement
			(enabled no)
			(sheetname "")
		)
		(fill
			(thermal_gap 0.5)
			(thermal_bridge_width 0.5)
			(island_removal_mode 0)
		)
		(polygon
			(pts
				(arc
					(start 64.54394 -18.11528)
					(mid 64.058927 -17.629886)
					(end 63.57366 -18.115026)
				)
				(arc
					(start 63.57366 -19.385026)
					(mid 64.0588 -19.870166)
					(end 64.54394 -19.385026)
				)
				(xy 64.54394 -18.991072) (xy 64.183768 -18.991072)
				(arc
					(start 64.17945 -18.991326)
					(mid 64.145864 -19.005238)
					(end 64.131952 -19.038824)
				)
				(xy 64.131952 -19.043142)
				(arc
					(start 64.131952 -19.128486)
					(mid 64.0588 -19.651792)
					(end 63.985648 -19.128486)
				)
				(xy 63.985648 -19.043142) (xy 63.985648 -19.038824) (xy 63.985648 -19.031712) (xy 63.985648 -19.008598)
				(arc
					(start 63.988442 -19.005804)
					(mid 64.042384 -18.901758)
					(end 64.14643 -18.847816)
				)
				(xy 64.149224 -18.845276) (xy 64.172338 -18.845276) (xy 64.17945 -18.845022) (xy 64.183768 -18.845276)
				(xy 64.54394 -18.845276) (xy 64.54394 -18.654776) (xy 64.183768 -18.654776) (xy 64.17945 -18.654776)
				(xy 64.172338 -18.654776) (xy 64.149224 -18.654776)
				(arc
					(start 64.14643 -18.651982)
					(mid 64.042384 -18.59804)
					(end 63.988442 -18.493994)
				)
				(xy 63.985648 -18.4912) (xy 63.985648 -18.468086) (xy 63.985648 -18.460974) (xy 63.985648 -18.456656)
				(arc
					(start 63.985648 -18.371566)
					(mid 64.0588 -17.84826)
					(end 64.131952 -18.371566)
				)
				(xy 64.131952 -18.456656)
				(arc
					(start 64.131952 -18.460974)
					(mid 64.145864 -18.49456)
					(end 64.17945 -18.508472)
				)
				(xy 64.183768 -18.508472) (xy 64.54394 -18.508472)
			)
		)
	)
	(zone
		(layer "In5.Cu")
		(hatch none 0.5)
		(connect_pads
			(clearance 0)
		)
		(min_thickness 0.25)
		(keepout
			(tracks not_allowed)
			(vias allowed)
			(pads allowed)
			(copperpour not_allowed)
			(footprints allowed)
		)
		(placement
			(enabled no)
			(sheetname "")
		)
		(fill
			(thermal_gap 0.5)
			(thermal_bridge_width 0.5)
			(island_removal_mode 0)
		)
		(polygon
			(pts
				(arc
					(start 285.436564 -178.745896)
					(mid 284.887924 -179.294536)
					(end 285.436564 -179.843176)
				)
				(arc
					(start 286.836612 -179.843176)
					(mid 287.385252 -179.294536)
					(end 286.836612 -178.745896)
				)
				(arc
					(start 286.387286 -178.745896)
					(mid 286.380255 -178.772928)
					(end 286.377888 -178.80076)
				)
				(xy 286.377888 -178.805078) (xy 286.377888 -179.101242)
				(arc
					(start 286.377888 -179.10556)
					(mid 286.397974 -179.170748)
					(end 286.451294 -179.213256)
				)
				(arc
					(start 286.451294 -179.213256)
					(mid 287.230363 -179.300614)
					(end 286.449008 -179.363878)
				)
				(arc
					(start 286.449008 -179.363878)
					(mid 286.303859 -179.286343)
					(end 286.233616 -179.137564)
				)
				(xy 286.231584 -179.135786) (xy 286.231584 -179.113688) (xy 286.231584 -179.10556) (xy 286.231584 -179.101242)
				(xy 286.231584 -178.805078) (xy 286.231584 -178.80076) (xy 286.231584 -178.79187) (xy 286.231584 -178.770534)
				(xy 286.233108 -178.76901) (xy 286.23641 -178.745896)
				(arc
					(start 286.044386 -178.745896)
					(mid 286.042114 -178.773286)
					(end 286.041338 -178.80076)
				)
				(xy 286.041084 -178.805078) (xy 286.041084 -179.101242) (xy 286.041338 -179.10556) (xy 286.041084 -179.113688)
				(xy 286.041084 -179.135786)
				(arc
					(start 286.039306 -179.137564)
					(mid 285.969076 -179.286184)
					(end 285.824168 -179.363878)
				)
				(arc
					(start 285.824168 -179.363878)
					(mid 285.042853 -179.300613)
					(end 285.821882 -179.213256)
				)
				(arc
					(start 285.821882 -179.213256)
					(mid 285.875029 -179.17066)
					(end 285.895034 -179.10556)
				)
				(xy 285.895288 -179.101242) (xy 285.895288 -178.805078) (xy 285.895034 -178.80076) (xy 285.895288 -178.78806)
				(xy 285.895288 -178.770534) (xy 285.895796 -178.770026) (xy 285.89732 -178.745896)
			)
		)
	)
	(zone
		(layer "In5.Cu")
		(hatch none 0.5)
		(connect_pads
			(clearance 0)
		)
		(min_thickness 0.25)
		(keepout
			(tracks not_allowed)
			(vias allowed)
			(pads allowed)
			(copperpour not_allowed)
			(footprints allowed)
		)
		(placement
			(enabled no)
			(sheetname "")
		)
		(fill
			(thermal_gap 0.5)
			(thermal_bridge_width 0.5)
			(island_removal_mode 0)
		)
		(polygon
			(pts
				(arc
					(start 286.436562 -209.345784)
					(mid 285.887922 -209.894424)
					(end 286.436562 -210.443064)
				)
				(arc
					(start 287.83661 -210.443064)
					(mid 288.38525 -209.894424)
					(end 287.83661 -209.345784)
				)
				(arc
					(start 287.361376 -209.345784)
					(mid 287.37205 -209.408564)
					(end 287.377378 -209.472022)
				)
				(xy 287.377632 -209.47253) (xy 287.377632 -209.48904) (xy 287.377886 -209.502756) (xy 287.377632 -209.507074)
				(xy 287.377632 -209.727038)
				(arc
					(start 287.377886 -209.731356)
					(mid 287.398219 -209.788304)
					(end 287.450022 -209.819494)
				)
				(arc
					(start 287.450022 -209.819494)
					(mid 288.230344 -209.894818)
					(end 287.449768 -209.967576)
				)
				(xy 287.437576 -209.967576)
				(arc
					(start 287.435544 -209.96529)
					(mid 287.30082 -209.898338)
					(end 287.233868 -209.763614)
				)
				(xy 287.231836 -209.761582) (xy 287.231836 -209.738976) (xy 287.231582 -209.731356) (xy 287.231836 -209.727038)
				(xy 287.231836 -209.507074)
				(arc
					(start 287.231582 -209.502756)
					(mid 287.226333 -209.423585)
					(end 287.210754 -209.345784)
				)
				(arc
					(start 287.010348 -209.345784)
					(mid 287.03015 -209.407481)
					(end 287.040066 -209.471514)
				)
				(xy 287.041336 -209.47253) (xy 287.041336 -209.492596) (xy 287.041336 -209.502756) (xy 287.041336 -209.507074)
				(xy 287.041336 -209.727038) (xy 287.041336 -209.731356) (xy 287.041336 -209.738976) (xy 287.041336 -209.761582)
				(arc
					(start 287.03905 -209.763614)
					(mid 286.972098 -209.898338)
					(end 286.837374 -209.96529)
				)
				(xy 286.835342 -209.967576)
				(arc
					(start 286.823404 -209.967576)
					(mid 286.042817 -209.894818)
					(end 286.82315 -209.819494)
				)
				(arc
					(start 286.82315 -209.819494)
					(mid 286.874815 -209.788238)
					(end 286.895032 -209.731356)
				)
				(xy 286.895032 -209.727038) (xy 286.895032 -209.507074)
				(arc
					(start 286.895032 -209.502756)
					(mid 286.881952 -209.42022)
					(end 286.843978 -209.345784)
				)
			)
		)
	)
	(zone
		(layer "In5.Cu")
		(hatch none 0.5)
		(connect_pads
			(clearance 0)
		)
		(min_thickness 0.25)
		(keepout
			(tracks not_allowed)
			(vias allowed)
			(pads allowed)
			(copperpour not_allowed)
			(footprints allowed)
		)
		(placement
			(enabled no)
			(sheetname "")
		)
		(fill
			(thermal_gap 0.5)
			(thermal_bridge_width 0.5)
			(island_removal_mode 0)
		)
		(polygon
			(pts
				(arc
					(start 286.436562 -230.945944)
					(mid 285.887922 -231.494584)
					(end 286.436562 -232.043224)
				)
				(arc
					(start 287.83661 -232.043224)
					(mid 288.38525 -231.494584)
					(end 287.83661 -230.945944)
				)
				(arc
					(start 287.361376 -230.945944)
					(mid 287.37205 -231.008724)
					(end 287.377378 -231.072182)
				)
				(xy 287.377632 -231.07269) (xy 287.377632 -231.0892) (xy 287.377886 -231.102916) (xy 287.377632 -231.107234)
				(xy 287.377632 -231.327198)
				(arc
					(start 287.377886 -231.331516)
					(mid 287.398219 -231.388464)
					(end 287.450022 -231.419654)
				)
				(arc
					(start 287.450022 -231.419654)
					(mid 288.230344 -231.494978)
					(end 287.449768 -231.567736)
				)
				(xy 287.437576 -231.567736)
				(arc
					(start 287.435544 -231.56545)
					(mid 287.30082 -231.498498)
					(end 287.233868 -231.363774)
				)
				(xy 287.231836 -231.361742) (xy 287.231836 -231.339136) (xy 287.231582 -231.331516) (xy 287.231836 -231.327198)
				(xy 287.231836 -231.107234)
				(arc
					(start 287.231582 -231.102916)
					(mid 287.226333 -231.023745)
					(end 287.210754 -230.945944)
				)
				(arc
					(start 287.010348 -230.945944)
					(mid 287.03015 -231.007641)
					(end 287.040066 -231.071674)
				)
				(xy 287.041336 -231.07269) (xy 287.041336 -231.092756) (xy 287.041336 -231.102916) (xy 287.041336 -231.107234)
				(xy 287.041336 -231.327198) (xy 287.041336 -231.331516) (xy 287.041336 -231.339136) (xy 287.041336 -231.361742)
				(arc
					(start 287.03905 -231.363774)
					(mid 286.972098 -231.498498)
					(end 286.837374 -231.56545)
				)
				(xy 286.835342 -231.567736)
				(arc
					(start 286.823404 -231.567736)
					(mid 286.042817 -231.494978)
					(end 286.82315 -231.419654)
				)
				(arc
					(start 286.82315 -231.419654)
					(mid 286.874815 -231.388398)
					(end 286.895032 -231.331516)
				)
				(xy 286.895032 -231.327198) (xy 286.895032 -231.107234)
				(arc
					(start 286.895032 -231.102916)
					(mid 286.881952 -231.02038)
					(end 286.843978 -230.945944)
				)
			)
		)
	)
	(zone
		(layer "In5.Cu")
		(hatch none 0.5)
		(connect_pads
			(clearance 0)
		)
		(min_thickness 0.25)
		(keepout
			(tracks not_allowed)
			(vias allowed)
			(pads allowed)
			(copperpour not_allowed)
			(footprints allowed)
		)
		(placement
			(enabled no)
			(sheetname "")
		)
		(fill
			(thermal_gap 0.5)
			(thermal_bridge_width 0.5)
			(island_removal_mode 0)
		)
		(polygon
			(pts
				(arc
					(start 286.436562 -238.145828)
					(mid 285.887922 -238.694468)
					(end 286.436562 -239.243108)
				)
				(arc
					(start 287.83661 -239.243108)
					(mid 288.38525 -238.694468)
					(end 287.83661 -238.145828)
				)
				(arc
					(start 287.361376 -238.145828)
					(mid 287.37205 -238.208608)
					(end 287.377378 -238.272066)
				)
				(xy 287.377632 -238.272574) (xy 287.377632 -238.289084) (xy 287.377886 -238.3028) (xy 287.377632 -238.307118)
				(xy 287.377632 -238.527082)
				(arc
					(start 287.377886 -238.5314)
					(mid 287.398219 -238.588348)
					(end 287.450022 -238.619538)
				)
				(arc
					(start 287.450022 -238.619538)
					(mid 288.230344 -238.694862)
					(end 287.449768 -238.76762)
				)
				(xy 287.437576 -238.76762)
				(arc
					(start 287.435544 -238.765334)
					(mid 287.30082 -238.698382)
					(end 287.233868 -238.563658)
				)
				(xy 287.231836 -238.561626) (xy 287.231836 -238.53902) (xy 287.231582 -238.5314) (xy 287.231836 -238.527082)
				(xy 287.231836 -238.307118)
				(arc
					(start 287.231582 -238.3028)
					(mid 287.226333 -238.223629)
					(end 287.210754 -238.145828)
				)
				(arc
					(start 287.010348 -238.145828)
					(mid 287.03015 -238.207525)
					(end 287.040066 -238.271558)
				)
				(xy 287.041336 -238.272574) (xy 287.041336 -238.29264) (xy 287.041336 -238.3028) (xy 287.041336 -238.307118)
				(xy 287.041336 -238.527082) (xy 287.041336 -238.5314) (xy 287.041336 -238.53902) (xy 287.041336 -238.561626)
				(arc
					(start 287.03905 -238.563658)
					(mid 286.972098 -238.698382)
					(end 286.837374 -238.765334)
				)
				(xy 286.835342 -238.76762)
				(arc
					(start 286.823404 -238.76762)
					(mid 286.042817 -238.694862)
					(end 286.82315 -238.619538)
				)
				(arc
					(start 286.82315 -238.619538)
					(mid 286.874815 -238.588282)
					(end 286.895032 -238.5314)
				)
				(xy 286.895032 -238.527082) (xy 286.895032 -238.307118)
				(arc
					(start 286.895032 -238.3028)
					(mid 286.881952 -238.220264)
					(end 286.843978 -238.145828)
				)
			)
		)
	)
	(zone
		(net "P12V_B")
		(layer "In5.Cu")
		(hatch none 0.5)
		(connect_pads
			(clearance 0.5)
		)
		(min_thickness 0.25)
		(fill yes
			(thermal_gap 0.5)
			(thermal_bridge_width 0.5)
			(island_removal_mode 0)
		)
		(polygon
			(pts
				(xy 271.366996 -332.788006) (xy 261.573772 -332.788006) (xy 261.345172 -333.016606) (xy 261.345172 -336.217006)
				(xy 261.421372 -336.293206) (xy 264.006076 -336.293206) (xy 264.14984 -336.149442) (xy 268.55166 -336.149442)
				(xy 268.873224 -336.471006) (xy 268.873224 -338.176108) (xy 268.424914 -338.624418) (xy 261.559548 -338.624418)
				(xy 261.345172 -338.838794) (xy 261.345172 -343.337134) (xy 261.441184 -343.433146) (xy 264.132568 -343.433146)
				(xy 264.35939 -343.206324) (xy 268.632178 -343.206324) (xy 268.846554 -343.4207) (xy 268.846554 -344.87485)
				(xy 268.454378 -345.267026) (xy 261.505192 -345.267026) (xy 261.345172 -345.427046) (xy 261.345172 -350.47682)
				(xy 261.429246 -350.560894) (xy 263.898888 -350.560894) (xy 269.314422 -350.560894) (xy 271.570196 -350.560894)
				(xy 272.203672 -349.927418) (xy 272.203672 -333.624682)
			)
		)
	)
	(zone
		(layer "In5.Cu")
		(hatch none 0.5)
		(connect_pads
			(clearance 0)
		)
		(min_thickness 0.25)
		(keepout
			(tracks not_allowed)
			(vias allowed)
			(pads allowed)
			(copperpour not_allowed)
			(footprints allowed)
		)
		(placement
			(enabled no)
			(sheetname "")
		)
		(fill
			(thermal_gap 0.5)
			(thermal_bridge_width 0.5)
			(island_removal_mode 0)
		)
		(polygon
			(pts
				(arc
					(start 286.436562 -205.745842)
					(mid 285.887922 -206.294482)
					(end 286.436562 -206.843122)
				)
				(arc
					(start 287.83661 -206.843122)
					(mid 288.38525 -206.294482)
					(end 287.83661 -205.745842)
				)
				(arc
					(start 287.39211 -205.745842)
					(mid 287.38148 -205.780308)
					(end 287.377886 -205.8162)
				)
				(xy 287.377632 -205.820518) (xy 287.377632 -206.065882)
				(arc
					(start 287.377886 -206.0702)
					(mid 287.398326 -206.146097)
					(end 287.454086 -206.201518)
				)
				(arc
					(start 287.454086 -206.201518)
					(mid 288.229995 -206.310926)
					(end 287.447736 -206.356204)
				)
				(arc
					(start 287.447736 -206.356204)
					(mid 287.301691 -206.261845)
					(end 287.23336 -206.10195)
				)
				(xy 287.231836 -206.100426) (xy 287.231836 -206.078836) (xy 287.231582 -206.0702) (xy 287.231836 -206.065882)
				(xy 287.231836 -205.820518) (xy 287.231582 -205.8162) (xy 287.231836 -205.807056) (xy 287.231836 -205.785974)
				(arc
					(start 287.233106 -205.78445)
					(mid 287.235573 -205.765054)
					(end 287.239202 -205.745842)
				)
				(arc
					(start 287.046162 -205.745842)
					(mid 287.042555 -205.780939)
					(end 287.041336 -205.8162)
				)
				(xy 287.041336 -205.820518) (xy 287.041336 -206.065882) (xy 287.041336 -206.0702) (xy 287.041336 -206.078836)
				(xy 287.041336 -206.100426)
				(arc
					(start 287.039558 -206.10195)
					(mid 286.971326 -206.261769)
					(end 286.825436 -206.356204)
				)
				(arc
					(start 286.825436 -206.356204)
					(mid 286.043148 -206.310547)
					(end 286.819086 -206.201264)
				)
				(arc
					(start 286.819086 -206.201264)
					(mid 286.874651 -206.145931)
					(end 286.895032 -206.0702)
				)
				(xy 286.895032 -206.065882) (xy 286.895032 -205.820518) (xy 286.895032 -205.8162) (xy 286.895032 -205.803246)
				(xy 286.895032 -205.785974) (xy 286.895794 -205.785466) (xy 286.898842 -205.745842)
			)
		)
	)
	(zone
		(layer "In5.Cu")
		(hatch none 0.5)
		(connect_pads
			(clearance 0)
		)
		(min_thickness 0.25)
		(keepout
			(tracks not_allowed)
			(vias allowed)
			(pads allowed)
			(copperpour not_allowed)
			(footprints allowed)
		)
		(placement
			(enabled no)
			(sheetname "")
		)
		(fill
			(thermal_gap 0.5)
			(thermal_bridge_width 0.5)
			(island_removal_mode 0)
		)
		(polygon
			(pts
				(arc
					(start 286.436562 -133.345682)
					(mid 285.887922 -133.894322)
					(end 286.436562 -134.442962)
				)
				(arc
					(start 287.83661 -134.442962)
					(mid 288.38525 -133.894322)
					(end 287.83661 -133.345682)
				)
				(arc
					(start 287.349184 -133.345682)
					(mid 287.35916 -133.403667)
					(end 287.364424 -133.462268)
				)
				(xy 287.365186 -133.46303)
				(arc
					(start 287.365186 -133.67512)
					(mid 287.389427 -133.752822)
					(end 287.453578 -133.802882)
				)
				(arc
					(start 287.453578 -133.802882)
					(mid 288.230293 -133.90057)
					(end 287.450784 -133.972554)
				)
				(arc
					(start 287.450784 -133.972554)
					(mid 287.283251 -133.88319)
					(end 287.202372 -133.711442)
				)
				(xy 287.200086 -133.70941)
				(arc
					(start 287.200086 -133.49732)
					(mid 287.194929 -133.420806)
					(end 287.179512 -133.345682)
				)
				(arc
					(start 287.046162 -133.345682)
					(mid 287.062811 -133.402857)
					(end 287.071562 -133.46176)
				)
				(xy 287.073086 -133.46303) (xy 287.073086 -133.70941)
				(arc
					(start 287.0708 -133.711442)
					(mid 286.989832 -133.883105)
					(end 286.822388 -133.972554)
				)
				(arc
					(start 286.822388 -133.972554)
					(mid 286.042888 -133.90057)
					(end 286.819594 -133.802882)
				)
				(arc
					(start 286.819594 -133.802882)
					(mid 286.88368 -133.752777)
					(end 286.907986 -133.67512)
				)
				(arc
					(start 286.907986 -133.49732)
					(mid 286.896307 -133.41813)
					(end 286.862266 -133.345682)
				)
			)
		)
	)
	(zone
		(layer "In5.Cu")
		(hatch none 0.5)
		(connect_pads
			(clearance 0)
		)
		(min_thickness 0.25)
		(keepout
			(tracks not_allowed)
			(vias allowed)
			(pads allowed)
			(copperpour not_allowed)
			(footprints allowed)
		)
		(placement
			(enabled no)
			(sheetname "")
		)
		(fill
			(thermal_gap 0.5)
			(thermal_bridge_width 0.5)
			(island_removal_mode 0)
		)
		(polygon
			(pts
				(arc
					(start 286.436562 -191.34582)
					(mid 285.887922 -191.89446)
					(end 286.436562 -192.4431)
				)
				(arc
					(start 287.83661 -192.4431)
					(mid 288.38525 -191.89446)
					(end 287.83661 -191.34582)
				)
				(arc
					(start 287.361376 -191.34582)
					(mid 287.37205 -191.4086)
					(end 287.377378 -191.472058)
				)
				(xy 287.377632 -191.472566) (xy 287.377632 -191.489076) (xy 287.377886 -191.502792) (xy 287.377632 -191.50711)
				(xy 287.377632 -191.727074)
				(arc
					(start 287.377886 -191.731392)
					(mid 287.398219 -191.78834)
					(end 287.450022 -191.81953)
				)
				(arc
					(start 287.450022 -191.81953)
					(mid 288.230344 -191.894854)
					(end 287.449768 -191.967612)
				)
				(xy 287.437576 -191.967612)
				(arc
					(start 287.435544 -191.965326)
					(mid 287.30082 -191.898374)
					(end 287.233868 -191.76365)
				)
				(xy 287.231836 -191.761618) (xy 287.231836 -191.739012) (xy 287.231582 -191.731392) (xy 287.231836 -191.727074)
				(xy 287.231836 -191.50711)
				(arc
					(start 287.231582 -191.502792)
					(mid 287.226333 -191.423621)
					(end 287.210754 -191.34582)
				)
				(arc
					(start 287.010348 -191.34582)
					(mid 287.03015 -191.407517)
					(end 287.040066 -191.47155)
				)
				(xy 287.041336 -191.472566) (xy 287.041336 -191.492632) (xy 287.041336 -191.502792) (xy 287.041336 -191.50711)
				(xy 287.041336 -191.727074) (xy 287.041336 -191.731392) (xy 287.041336 -191.739012) (xy 287.041336 -191.761618)
				(arc
					(start 287.03905 -191.76365)
					(mid 286.972098 -191.898374)
					(end 286.837374 -191.965326)
				)
				(xy 286.835342 -191.967612)
				(arc
					(start 286.823404 -191.967612)
					(mid 286.042817 -191.894854)
					(end 286.82315 -191.81953)
				)
				(arc
					(start 286.82315 -191.81953)
					(mid 286.874815 -191.788274)
					(end 286.895032 -191.731392)
				)
				(xy 286.895032 -191.727074) (xy 286.895032 -191.50711)
				(arc
					(start 286.895032 -191.502792)
					(mid 286.881952 -191.420256)
					(end 286.843978 -191.34582)
				)
			)
		)
	)
	(zone
		(layer "In5.Cu")
		(hatch none 0.5)
		(connect_pads
			(clearance 0)
		)
		(min_thickness 0.25)
		(keepout
			(tracks not_allowed)
			(vias allowed)
			(pads allowed)
			(copperpour not_allowed)
			(footprints allowed)
		)
		(placement
			(enabled no)
			(sheetname "")
		)
		(fill
			(thermal_gap 0.5)
			(thermal_bridge_width 0.5)
			(island_removal_mode 0)
		)
		(polygon
			(pts
				(arc
					(start 212.348826 -65.600072)
					(mid 211.800186 -65.051432)
					(end 211.251546 -65.600072)
				)
				(arc
					(start 211.251546 -66.999612)
					(mid 211.800059 -67.548506)
					(end 212.348826 -66.999866)
				)
				(arc
					(start 212.348826 -66.585846)
					(mid 212.265255 -66.543099)
					(end 212.17255 -66.528442)
				)
				(arc
					(start 211.985098 -66.528442)
					(mid 211.91852 -66.553052)
					(end 211.884006 -66.615056)
				)
				(arc
					(start 211.884006 -66.615056)
					(mid 211.799538 -67.393699)
					(end 211.717636 -66.614802)
				)
				(xy 211.717636 -66.596514)
				(arc
					(start 211.720176 -66.593974)
					(mid 211.795968 -66.441674)
					(end 211.948268 -66.365882)
				)
				(xy 211.950808 -66.363342) (xy 212.20684 -66.363342)
				(arc
					(start 212.20811 -66.364612)
					(mid 212.279787 -66.375846)
					(end 212.348826 -66.39814)
				)
				(arc
					(start 212.348826 -66.263266)
					(mid 212.261708 -66.24313)
					(end 212.17255 -66.236342)
				)
				(xy 211.950808 -66.236342)
				(arc
					(start 211.948268 -66.233802)
					(mid 211.795968 -66.15801)
					(end 211.720176 -66.00571)
				)
				(xy 211.717636 -66.00317)
				(arc
					(start 211.717636 -65.985136)
					(mid 211.798507 -65.206367)
					(end 211.884006 -65.984628)
				)
				(arc
					(start 211.884006 -65.984628)
					(mid 211.918553 -66.046594)
					(end 211.985098 -66.071242)
				)
				(xy 212.20684 -66.071242)
				(arc
					(start 212.207602 -66.072004)
					(mid 212.278688 -66.078701)
					(end 212.348826 -66.09207)
				)
			)
		)
	)
	(zone
		(layer "In5.Cu")
		(hatch none 0.5)
		(connect_pads
			(clearance 0)
		)
		(min_thickness 0.25)
		(keepout
			(tracks not_allowed)
			(vias allowed)
			(pads allowed)
			(copperpour not_allowed)
			(footprints allowed)
		)
		(placement
			(enabled no)
			(sheetname "")
		)
		(fill
			(thermal_gap 0.5)
			(thermal_bridge_width 0.5)
			(island_removal_mode 0)
		)
		(polygon
			(pts
				(arc
					(start 285.436564 -138.745722)
					(mid 284.887924 -139.294362)
					(end 285.436564 -139.843002)
				)
				(arc
					(start 286.836612 -139.843002)
					(mid 287.385252 -139.294362)
					(end 286.836612 -138.745722)
				)
				(arc
					(start 286.349186 -138.745722)
					(mid 286.359162 -138.803707)
					(end 286.364426 -138.862308)
				)
				(xy 286.365188 -138.86307)
				(arc
					(start 286.365188 -139.07516)
					(mid 286.389429 -139.152862)
					(end 286.45358 -139.202922)
				)
				(arc
					(start 286.45358 -139.202922)
					(mid 287.230295 -139.30061)
					(end 286.450786 -139.372594)
				)
				(arc
					(start 286.450786 -139.372594)
					(mid 286.283253 -139.28323)
					(end 286.202374 -139.111482)
				)
				(xy 286.200088 -139.10945)
				(arc
					(start 286.200088 -138.89736)
					(mid 286.194931 -138.820846)
					(end 286.179514 -138.745722)
				)
				(arc
					(start 286.046164 -138.745722)
					(mid 286.062813 -138.802897)
					(end 286.071564 -138.8618)
				)
				(xy 286.073088 -138.86307) (xy 286.073088 -139.10945)
				(arc
					(start 286.070802 -139.111482)
					(mid 285.989834 -139.283145)
					(end 285.82239 -139.372594)
				)
				(arc
					(start 285.82239 -139.372594)
					(mid 285.04289 -139.30061)
					(end 285.819596 -139.202922)
				)
				(arc
					(start 285.819596 -139.202922)
					(mid 285.883682 -139.152817)
					(end 285.907988 -139.07516)
				)
				(arc
					(start 285.907988 -138.89736)
					(mid 285.896309 -138.81817)
					(end 285.862268 -138.745722)
				)
			)
		)
	)
	(zone
		(layer "In5.Cu")
		(hatch none 0.5)
		(connect_pads
			(clearance 0)
		)
		(min_thickness 0.25)
		(keepout
			(tracks not_allowed)
			(vias allowed)
			(pads allowed)
			(copperpour not_allowed)
			(footprints allowed)
		)
		(placement
			(enabled no)
			(sheetname "")
		)
		(fill
			(thermal_gap 0.5)
			(thermal_bridge_width 0.5)
			(island_removal_mode 0)
		)
		(polygon
			(pts
				(arc
					(start 285.436564 -135.14578)
					(mid 284.887924 -135.69442)
					(end 285.436564 -136.24306)
				)
				(arc
					(start 286.836612 -136.24306)
					(mid 287.385252 -135.69442)
					(end 286.836612 -135.14578)
				)
				(arc
					(start 286.349186 -135.14578)
					(mid 286.359162 -135.203765)
					(end 286.364426 -135.262366)
				)
				(xy 286.365188 -135.263128)
				(arc
					(start 286.365188 -135.475218)
					(mid 286.389429 -135.55292)
					(end 286.45358 -135.60298)
				)
				(arc
					(start 286.45358 -135.60298)
					(mid 287.230295 -135.700668)
					(end 286.450786 -135.772652)
				)
				(arc
					(start 286.450786 -135.772652)
					(mid 286.283253 -135.683288)
					(end 286.202374 -135.51154)
				)
				(xy 286.200088 -135.509508)
				(arc
					(start 286.200088 -135.297418)
					(mid 286.194931 -135.220904)
					(end 286.179514 -135.14578)
				)
				(arc
					(start 286.046164 -135.14578)
					(mid 286.062813 -135.202955)
					(end 286.071564 -135.261858)
				)
				(xy 286.073088 -135.263128) (xy 286.073088 -135.509508)
				(arc
					(start 286.070802 -135.51154)
					(mid 285.989834 -135.683203)
					(end 285.82239 -135.772652)
				)
				(arc
					(start 285.82239 -135.772652)
					(mid 285.04289 -135.700668)
					(end 285.819596 -135.60298)
				)
				(arc
					(start 285.819596 -135.60298)
					(mid 285.883682 -135.552875)
					(end 285.907988 -135.475218)
				)
				(arc
					(start 285.907988 -135.297418)
					(mid 285.896309 -135.218228)
					(end 285.862268 -135.14578)
				)
			)
		)
	)
	(zone
		(net "MB0_CM_GATE")
		(layer "In5.Cu")
		(hatch none 0.5)
		(connect_pads
			(clearance 0.5)
		)
		(min_thickness 0.25)
		(fill yes
			(thermal_gap 0.5)
			(thermal_bridge_width 0.5)
			(island_removal_mode 0)
		)
		(polygon
			(pts
				(xy 173.3042 -372.7704) (xy 173.5582 -372.5164) (xy 175.006 -372.5164) (xy 175.1838 -372.3386) (xy 175.1838 -370.9924)
				(xy 175.0822 -370.8908) (xy 174.625 -370.8908) (xy 172.4914 -370.8908) (xy 171.7548 -371.6274) (xy 171.7548 -372.618)
				(xy 172.6184 -373.4816) (xy 173.1772 -373.4816) (xy 173.3042 -373.3546)
			)
		)
	)
	(zone
		(layer "In5.Cu")
		(hatch none 0.5)
		(connect_pads
			(clearance 0)
		)
		(min_thickness 0.25)
		(keepout
			(tracks not_allowed)
			(vias allowed)
			(pads allowed)
			(copperpour not_allowed)
			(footprints allowed)
		)
		(placement
			(enabled no)
			(sheetname "")
		)
		(fill
			(thermal_gap 0.5)
			(thermal_bridge_width 0.5)
			(island_removal_mode 0)
		)
		(polygon
			(pts
				(arc
					(start 127.64389 -18.11528)
					(mid 127.158877 -17.629886)
					(end 126.67361 -18.115026)
				)
				(arc
					(start 126.67361 -19.385026)
					(mid 127.15875 -19.870166)
					(end 127.64389 -19.385026)
				)
				(xy 127.64389 -18.991072) (xy 127.283718 -18.991072)
				(arc
					(start 127.2794 -18.991326)
					(mid 127.245814 -19.005238)
					(end 127.231902 -19.038824)
				)
				(xy 127.231648 -19.043142)
				(arc
					(start 127.231648 -19.128486)
					(mid 127.15875 -19.651722)
					(end 127.085852 -19.128486)
				)
				(xy 127.085852 -19.043142) (xy 127.085598 -19.038824) (xy 127.085852 -19.031712) (xy 127.085852 -19.008598)
				(arc
					(start 127.088392 -19.005804)
					(mid 127.142334 -18.901758)
					(end 127.24638 -18.847816)
				)
				(xy 127.249174 -18.845276) (xy 127.272288 -18.845276) (xy 127.2794 -18.845022) (xy 127.283718 -18.845276)
				(xy 127.64389 -18.845276) (xy 127.64389 -18.654776) (xy 127.283718 -18.654776) (xy 127.2794 -18.654776)
				(xy 127.272288 -18.654776) (xy 127.249174 -18.654776)
				(arc
					(start 127.24638 -18.651982)
					(mid 127.142334 -18.59804)
					(end 127.088392 -18.493994)
				)
				(xy 127.085852 -18.4912) (xy 127.085852 -18.468086) (xy 127.085598 -18.460974) (xy 127.085852 -18.456656)
				(arc
					(start 127.085852 -18.371566)
					(mid 127.15875 -17.84833)
					(end 127.231648 -18.371566)
				)
				(xy 127.231648 -18.456656)
				(arc
					(start 127.231902 -18.460974)
					(mid 127.245814 -18.49456)
					(end 127.2794 -18.508472)
				)
				(xy 127.283718 -18.508472) (xy 127.64389 -18.508472)
			)
		)
	)
	(zone
		(layer "In5.Cu")
		(hatch none 0.5)
		(connect_pads
			(clearance 0)
		)
		(min_thickness 0.25)
		(keepout
			(tracks not_allowed)
			(vias allowed)
			(pads allowed)
			(copperpour not_allowed)
			(footprints allowed)
		)
		(placement
			(enabled no)
			(sheetname "")
		)
		(fill
			(thermal_gap 0.5)
			(thermal_bridge_width 0.5)
			(island_removal_mode 0)
		)
		(polygon
			(pts
				(arc
					(start 285.436564 -211.145882)
					(mid 284.887924 -211.694522)
					(end 285.436564 -212.243162)
				)
				(arc
					(start 286.836612 -212.243162)
					(mid 287.385252 -211.694522)
					(end 286.836612 -211.145882)
				)
				(arc
					(start 286.361378 -211.145882)
					(mid 286.372052 -211.208662)
					(end 286.37738 -211.27212)
				)
				(xy 286.377888 -211.272628) (xy 286.377888 -211.289138) (xy 286.377888 -211.302854) (xy 286.377888 -211.307172)
				(xy 286.377888 -211.527136)
				(arc
					(start 286.377888 -211.531454)
					(mid 286.398221 -211.588402)
					(end 286.450024 -211.619592)
				)
				(arc
					(start 286.450024 -211.619592)
					(mid 287.230346 -211.69504)
					(end 286.44977 -211.76742)
				)
				(xy 286.437578 -211.76742)
				(arc
					(start 286.435546 -211.765388)
					(mid 286.300822 -211.698436)
					(end 286.23387 -211.563712)
				)
				(xy 286.231584 -211.56168) (xy 286.231584 -211.539074) (xy 286.231584 -211.531454) (xy 286.231584 -211.527136)
				(xy 286.231584 -211.307172)
				(arc
					(start 286.231584 -211.302854)
					(mid 286.226335 -211.223683)
					(end 286.210756 -211.145882)
				)
				(arc
					(start 286.01035 -211.145882)
					(mid 286.030152 -211.207579)
					(end 286.040068 -211.271612)
				)
				(xy 286.041084 -211.272628) (xy 286.041084 -211.292694) (xy 286.041338 -211.302854) (xy 286.041084 -211.307172)
				(xy 286.041084 -211.527136) (xy 286.041338 -211.531454) (xy 286.041084 -211.539074) (xy 286.041084 -211.56168)
				(arc
					(start 286.039052 -211.563712)
					(mid 285.9721 -211.698436)
					(end 285.837376 -211.765388)
				)
				(xy 285.835344 -211.76742)
				(arc
					(start 285.823406 -211.76742)
					(mid 285.042867 -211.69504)
					(end 285.823152 -211.619592)
				)
				(arc
					(start 285.823152 -211.619592)
					(mid 285.874817 -211.588336)
					(end 285.895034 -211.531454)
				)
				(xy 285.895288 -211.527136) (xy 285.895288 -211.307172)
				(arc
					(start 285.895034 -211.302854)
					(mid 285.881954 -211.220318)
					(end 285.84398 -211.145882)
				)
			)
		)
	)
	(zone
		(layer "In5.Cu")
		(hatch none 0.5)
		(connect_pads
			(clearance 0)
		)
		(min_thickness 0.25)
		(keepout
			(tracks not_allowed)
			(vias allowed)
			(pads allowed)
			(copperpour not_allowed)
			(footprints allowed)
		)
		(placement
			(enabled no)
			(sheetname "")
		)
		(fill
			(thermal_gap 0.5)
			(thermal_bridge_width 0.5)
			(island_removal_mode 0)
		)
		(polygon
			(pts
				(arc
					(start 286.436562 -187.745878)
					(mid 285.887922 -188.294518)
					(end 286.436562 -188.843158)
				)
				(arc
					(start 287.83661 -188.843158)
					(mid 288.38525 -188.294518)
					(end 287.83661 -187.745878)
				)
				(arc
					(start 287.361376 -187.745878)
					(mid 287.37205 -187.808658)
					(end 287.377378 -187.872116)
				)
				(xy 287.377632 -187.872624) (xy 287.377632 -187.889134) (xy 287.377886 -187.90285) (xy 287.377632 -187.907168)
				(xy 287.377632 -188.127132)
				(arc
					(start 287.377886 -188.13145)
					(mid 287.398219 -188.188398)
					(end 287.450022 -188.219588)
				)
				(arc
					(start 287.450022 -188.219588)
					(mid 288.230344 -188.295036)
					(end 287.449768 -188.367416)
				)
				(xy 287.437576 -188.367416)
				(arc
					(start 287.435544 -188.365384)
					(mid 287.30082 -188.298432)
					(end 287.233868 -188.163708)
				)
				(xy 287.231836 -188.161676) (xy 287.231836 -188.13907) (xy 287.231582 -188.13145) (xy 287.231836 -188.127132)
				(xy 287.231836 -187.907168)
				(arc
					(start 287.231582 -187.90285)
					(mid 287.226333 -187.823679)
					(end 287.210754 -187.745878)
				)
				(arc
					(start 287.010348 -187.745878)
					(mid 287.03015 -187.807575)
					(end 287.040066 -187.871608)
				)
				(xy 287.041336 -187.872624) (xy 287.041336 -187.89269) (xy 287.041336 -187.90285) (xy 287.041336 -187.907168)
				(xy 287.041336 -188.127132) (xy 287.041336 -188.13145) (xy 287.041336 -188.13907) (xy 287.041336 -188.161676)
				(arc
					(start 287.03905 -188.163708)
					(mid 286.972098 -188.298432)
					(end 286.837374 -188.365384)
				)
				(xy 286.835342 -188.367416)
				(arc
					(start 286.823404 -188.367416)
					(mid 286.042865 -188.295036)
					(end 286.82315 -188.219588)
				)
				(arc
					(start 286.82315 -188.219588)
					(mid 286.874815 -188.188332)
					(end 286.895032 -188.13145)
				)
				(xy 286.895032 -188.127132) (xy 286.895032 -187.907168)
				(arc
					(start 286.895032 -187.90285)
					(mid 286.881952 -187.820314)
					(end 286.843978 -187.745878)
				)
			)
		)
	)
	(zone
		(layer "In5.Cu")
		(hatch none 0.5)
		(connect_pads
			(clearance 0)
		)
		(min_thickness 0.25)
		(keepout
			(tracks not_allowed)
			(vias allowed)
			(pads allowed)
			(copperpour not_allowed)
			(footprints allowed)
		)
		(placement
			(enabled no)
			(sheetname "")
		)
		(fill
			(thermal_gap 0.5)
			(thermal_bridge_width 0.5)
			(island_removal_mode 0)
		)
		(polygon
			(pts
				(arc
					(start 285.436564 -229.145846)
					(mid 284.887924 -229.694486)
					(end 285.436564 -230.243126)
				)
				(arc
					(start 286.836612 -230.243126)
					(mid 287.385252 -229.694486)
					(end 286.836612 -229.145846)
				)
				(arc
					(start 286.361378 -229.145846)
					(mid 286.372052 -229.208626)
					(end 286.37738 -229.272084)
				)
				(xy 286.377888 -229.272592) (xy 286.377888 -229.289102) (xy 286.377888 -229.302818) (xy 286.377888 -229.307136)
				(xy 286.377888 -229.5271)
				(arc
					(start 286.377888 -229.531418)
					(mid 286.398221 -229.588366)
					(end 286.450024 -229.619556)
				)
				(arc
					(start 286.450024 -229.619556)
					(mid 287.230346 -229.695004)
					(end 286.44977 -229.767384)
				)
				(xy 286.437578 -229.767384)
				(arc
					(start 286.435546 -229.765352)
					(mid 286.300822 -229.6984)
					(end 286.23387 -229.563676)
				)
				(xy 286.231584 -229.561644) (xy 286.231584 -229.539038) (xy 286.231584 -229.531418) (xy 286.231584 -229.5271)
				(xy 286.231584 -229.307136)
				(arc
					(start 286.231584 -229.302818)
					(mid 286.226335 -229.223647)
					(end 286.210756 -229.145846)
				)
				(arc
					(start 286.01035 -229.145846)
					(mid 286.030152 -229.207543)
					(end 286.040068 -229.271576)
				)
				(xy 286.041084 -229.272592) (xy 286.041084 -229.292658) (xy 286.041338 -229.302818) (xy 286.041084 -229.307136)
				(xy 286.041084 -229.5271) (xy 286.041338 -229.531418) (xy 286.041084 -229.539038) (xy 286.041084 -229.561644)
				(arc
					(start 286.039052 -229.563676)
					(mid 285.9721 -229.6984)
					(end 285.837376 -229.765352)
				)
				(xy 285.835344 -229.767384)
				(arc
					(start 285.823406 -229.767384)
					(mid 285.042867 -229.695004)
					(end 285.823152 -229.619556)
				)
				(arc
					(start 285.823152 -229.619556)
					(mid 285.874817 -229.5883)
					(end 285.895034 -229.531418)
				)
				(xy 285.895288 -229.5271) (xy 285.895288 -229.307136)
				(arc
					(start 285.895034 -229.302818)
					(mid 285.881954 -229.220282)
					(end 285.84398 -229.145846)
				)
			)
		)
	)
	(zone
		(layer "In5.Cu")
		(hatch none 0.5)
		(connect_pads
			(clearance 0)
		)
		(min_thickness 0.25)
		(keepout
			(tracks not_allowed)
			(vias allowed)
			(pads allowed)
			(copperpour not_allowed)
			(footprints allowed)
		)
		(placement
			(enabled no)
			(sheetname "")
		)
		(fill
			(thermal_gap 0.5)
			(thermal_bridge_width 0.5)
			(island_removal_mode 0)
		)
		(polygon
			(pts
				(arc
					(start 286.436562 -136.945878)
					(mid 285.887922 -137.494518)
					(end 286.436562 -138.043158)
				)
				(arc
					(start 287.83661 -138.043158)
					(mid 288.38525 -137.494518)
					(end 287.83661 -136.945878)
				)
				(arc
					(start 287.349184 -136.945878)
					(mid 287.35916 -137.003863)
					(end 287.364424 -137.062464)
				)
				(xy 287.365186 -137.063226)
				(arc
					(start 287.365186 -137.275316)
					(mid 287.389427 -137.353018)
					(end 287.453578 -137.403078)
				)
				(arc
					(start 287.453578 -137.403078)
					(mid 288.230293 -137.500766)
					(end 287.450784 -137.57275)
				)
				(arc
					(start 287.450784 -137.57275)
					(mid 287.283251 -137.483386)
					(end 287.202372 -137.311638)
				)
				(xy 287.200086 -137.309606)
				(arc
					(start 287.200086 -137.097516)
					(mid 287.194929 -137.021002)
					(end 287.179512 -136.945878)
				)
				(arc
					(start 287.046162 -136.945878)
					(mid 287.062811 -137.003053)
					(end 287.071562 -137.061956)
				)
				(xy 287.073086 -137.063226) (xy 287.073086 -137.309606)
				(arc
					(start 287.0708 -137.311638)
					(mid 286.989832 -137.483301)
					(end 286.822388 -137.57275)
				)
				(arc
					(start 286.822388 -137.57275)
					(mid 286.042888 -137.500766)
					(end 286.819594 -137.403078)
				)
				(arc
					(start 286.819594 -137.403078)
					(mid 286.88368 -137.352973)
					(end 286.907986 -137.275316)
				)
				(arc
					(start 286.907986 -137.097516)
					(mid 286.896307 -137.018326)
					(end 286.862266 -136.945878)
				)
			)
		)
	)
	(zone
		(layer "In5.Cu")
		(hatch none 0.5)
		(connect_pads
			(clearance 0)
		)
		(min_thickness 0.25)
		(keepout
			(tracks not_allowed)
			(vias allowed)
			(pads allowed)
			(copperpour not_allowed)
			(footprints allowed)
		)
		(placement
			(enabled no)
			(sheetname "")
		)
		(fill
			(thermal_gap 0.5)
			(thermal_bridge_width 0.5)
			(island_removal_mode 0)
		)
		(polygon
			(pts
				(arc
					(start 286.436562 -227.345748)
					(mid 285.887922 -227.894388)
					(end 286.436562 -228.443028)
				)
				(arc
					(start 286.9057 -228.443028)
					(mid 286.899272 -228.39734)
					(end 286.895794 -228.351334)
				)
				(xy 286.895032 -228.350826) (xy 286.895032 -228.334062) (xy 286.895032 -228.3206) (xy 286.895032 -228.316282)
				(xy 286.895032 -228.096318)
				(arc
					(start 286.895032 -228.092)
					(mid 286.874924 -228.024169)
					(end 286.821118 -227.978208)
				)
				(arc
					(start 286.821118 -227.978208)
					(mid 286.042964 -227.885212)
					(end 286.82442 -227.82657)
				)
				(arc
					(start 286.82442 -227.82657)
					(mid 286.969747 -227.908473)
					(end 287.039558 -228.059996)
				)
				(xy 287.041336 -228.061774) (xy 287.041336 -228.083618) (xy 287.041336 -228.092) (xy 287.041336 -228.096318)
				(xy 287.041336 -228.316282)
				(arc
					(start 287.041336 -228.3206)
					(mid 287.044622 -228.382172)
					(end 287.054544 -228.443028)
				)
				(arc
					(start 287.251902 -228.443028)
					(mid 287.239592 -228.398146)
					(end 287.232852 -228.352096)
				)
				(xy 287.231836 -228.350826) (xy 287.231836 -228.330506) (xy 287.231582 -228.3206) (xy 287.231836 -228.316282)
				(xy 287.231836 -228.096318) (xy 287.231582 -228.092) (xy 287.231836 -228.083618) (xy 287.231836 -228.061774)
				(arc
					(start 287.23336 -228.059996)
					(mid 287.303222 -227.90835)
					(end 287.448752 -227.82657)
				)
				(arc
					(start 287.448752 -227.82657)
					(mid 288.23017 -227.885213)
					(end 287.452054 -227.978208)
				)
				(arc
					(start 287.452054 -227.978208)
					(mid 287.398099 -228.024099)
					(end 287.377886 -228.092)
				)
				(xy 287.377632 -228.096318) (xy 287.377632 -228.316282)
				(arc
					(start 287.377886 -228.3206)
					(mid 287.386758 -228.384237)
					(end 287.412684 -228.443028)
				)
				(arc
					(start 287.83661 -228.443028)
					(mid 288.38525 -227.894388)
					(end 287.83661 -227.345748)
				)
			)
		)
	)
	(zone
		(layer "In5.Cu")
		(hatch none 0.5)
		(connect_pads
			(clearance 0)
		)
		(min_thickness 0.25)
		(keepout
			(tracks not_allowed)
			(vias allowed)
			(pads allowed)
			(copperpour not_allowed)
			(footprints allowed)
		)
		(placement
			(enabled no)
			(sheetname "")
		)
		(fill
			(thermal_gap 0.5)
			(thermal_bridge_width 0.5)
			(island_removal_mode 0)
		)
		(polygon
			(pts
				(arc
					(start 286.436562 -176.945798)
					(mid 285.887922 -177.494438)
					(end 286.436562 -178.043078)
				)
				(arc
					(start 287.83661 -178.043078)
					(mid 288.38525 -177.494438)
					(end 287.83661 -176.945798)
				)
				(arc
					(start 287.387284 -176.945798)
					(mid 287.380253 -176.97283)
					(end 287.377886 -177.000662)
				)
				(xy 287.377632 -177.00498) (xy 287.377632 -177.301144)
				(arc
					(start 287.377886 -177.305462)
					(mid 287.397972 -177.37065)
					(end 287.451292 -177.413158)
				)
				(arc
					(start 287.451292 -177.413158)
					(mid 288.230361 -177.500516)
					(end 287.449006 -177.56378)
				)
				(arc
					(start 287.449006 -177.56378)
					(mid 287.303857 -177.486245)
					(end 287.233614 -177.337466)
				)
				(xy 287.231836 -177.335688) (xy 287.231836 -177.31359) (xy 287.231582 -177.305462) (xy 287.231836 -177.301144)
				(xy 287.231836 -177.00498) (xy 287.231582 -177.000662) (xy 287.231836 -176.991772) (xy 287.231836 -176.970436)
				(xy 287.233106 -176.968912) (xy 287.236408 -176.945798)
				(arc
					(start 287.044384 -176.945798)
					(mid 287.042112 -176.973188)
					(end 287.041336 -177.000662)
				)
				(xy 287.041336 -177.00498) (xy 287.041336 -177.301144) (xy 287.041336 -177.305462) (xy 287.041336 -177.31359)
				(xy 287.041336 -177.335688)
				(arc
					(start 287.039304 -177.337466)
					(mid 286.969074 -177.486086)
					(end 286.824166 -177.56378)
				)
				(arc
					(start 286.824166 -177.56378)
					(mid 286.042851 -177.500515)
					(end 286.82188 -177.413158)
				)
				(arc
					(start 286.82188 -177.413158)
					(mid 286.875027 -177.370562)
					(end 286.895032 -177.305462)
				)
				(xy 286.895032 -177.301144) (xy 286.895032 -177.00498) (xy 286.895032 -177.000662) (xy 286.895032 -176.987962)
				(xy 286.895032 -176.970436) (xy 286.895794 -176.969928) (xy 286.897318 -176.945798)
			)
		)
	)
	(zone
		(layer "In5.Cu")
		(hatch none 0.5)
		(connect_pads
			(clearance 0)
		)
		(min_thickness 0.25)
		(keepout
			(tracks not_allowed)
			(vias allowed)
			(pads allowed)
			(copperpour not_allowed)
			(footprints allowed)
		)
		(placement
			(enabled no)
			(sheetname "")
		)
		(fill
			(thermal_gap 0.5)
			(thermal_bridge_width 0.5)
			(island_removal_mode 0)
		)
		(polygon
			(pts
				(arc
					(start 286.436562 -184.145936)
					(mid 285.887922 -184.694576)
					(end 286.436562 -185.243216)
				)
				(arc
					(start 287.83661 -185.243216)
					(mid 288.38525 -184.694576)
					(end 287.83661 -184.145936)
				)
				(arc
					(start 287.387284 -184.145936)
					(mid 287.380253 -184.172968)
					(end 287.377886 -184.2008)
				)
				(xy 287.377632 -184.205118) (xy 287.377632 -184.501282)
				(arc
					(start 287.377886 -184.5056)
					(mid 287.397972 -184.570788)
					(end 287.451292 -184.613296)
				)
				(arc
					(start 287.451292 -184.613296)
					(mid 288.230361 -184.700654)
					(end 287.449006 -184.763918)
				)
				(arc
					(start 287.449006 -184.763918)
					(mid 287.303857 -184.686383)
					(end 287.233614 -184.537604)
				)
				(xy 287.231836 -184.535826) (xy 287.231836 -184.513728) (xy 287.231582 -184.5056) (xy 287.231836 -184.501282)
				(xy 287.231836 -184.205118) (xy 287.231582 -184.2008) (xy 287.231836 -184.19191) (xy 287.231836 -184.170574)
				(xy 287.233106 -184.16905) (xy 287.236408 -184.145936)
				(arc
					(start 287.044384 -184.145936)
					(mid 287.042112 -184.173326)
					(end 287.041336 -184.2008)
				)
				(xy 287.041336 -184.205118) (xy 287.041336 -184.501282) (xy 287.041336 -184.5056) (xy 287.041336 -184.513728)
				(xy 287.041336 -184.535826)
				(arc
					(start 287.039304 -184.537604)
					(mid 286.969074 -184.686224)
					(end 286.824166 -184.763918)
				)
				(arc
					(start 286.824166 -184.763918)
					(mid 286.042851 -184.700653)
					(end 286.82188 -184.613296)
				)
				(arc
					(start 286.82188 -184.613296)
					(mid 286.875027 -184.5707)
					(end 286.895032 -184.5056)
				)
				(xy 286.895032 -184.501282) (xy 286.895032 -184.205118) (xy 286.895032 -184.2008) (xy 286.895032 -184.1881)
				(xy 286.895032 -184.170574) (xy 286.895794 -184.170066) (xy 286.897318 -184.145936)
			)
		)
	)
	(zone
		(layer "In5.Cu")
		(hatch none 0.5)
		(connect_pads
			(clearance 0)
		)
		(min_thickness 0.25)
		(keepout
			(tracks not_allowed)
			(vias allowed)
			(pads allowed)
			(copperpour not_allowed)
			(footprints allowed)
		)
		(placement
			(enabled no)
			(sheetname "")
		)
		(fill
			(thermal_gap 0.5)
			(thermal_bridge_width 0.5)
			(island_removal_mode 0)
		)
		(polygon
			(pts
				(arc
					(start 448.8815 -131.951984)
					(mid 448.39636 -132.437124)
					(end 448.8815 -132.922264)
				)
				(xy 449.2752 -132.922264) (xy 449.2752 -132.589016)
				(arc
					(start 449.274946 -132.584698)
					(mid 449.253148 -132.532074)
					(end 449.200524 -132.510276)
				)
				(xy 449.196206 -132.510276)
				(arc
					(start 449.13804 -132.510276)
					(mid 448.614734 -132.437124)
					(end 449.13804 -132.363972)
				)
				(xy 449.196206 -132.363972) (xy 449.200524 -132.363972) (xy 449.20789 -132.363972) (xy 449.23075 -132.363972)
				(arc
					(start 449.233036 -132.366258)
					(mid 449.356686 -132.428536)
					(end 449.418964 -132.552186)
				)
				(xy 449.420996 -132.554472) (xy 449.420996 -132.577332) (xy 449.42125 -132.584698) (xy 449.420996 -132.589016)
				(xy 449.420996 -132.922264) (xy 449.611496 -132.922264) (xy 449.611496 -132.58927) (xy 449.611496 -132.584952)
				(xy 449.611496 -132.577586) (xy 449.611496 -132.554726)
				(arc
					(start 449.613782 -132.55244)
					(mid 449.676136 -132.428612)
					(end 449.799964 -132.366258)
				)
				(xy 449.80225 -132.363972) (xy 449.82511 -132.363972) (xy 449.832476 -132.363972) (xy 449.836794 -132.363972)
				(arc
					(start 449.89496 -132.363972)
					(mid 450.418266 -132.437124)
					(end 449.89496 -132.510276)
				)
				(xy 449.836794 -132.510276)
				(arc
					(start 449.832476 -132.510276)
					(mid 449.779672 -132.532148)
					(end 449.7578 -132.584952)
				)
				(xy 449.7578 -132.58927) (xy 449.7578 -132.922264)
				(arc
					(start 450.151246 -132.922264)
					(mid 450.63664 -132.437251)
					(end 450.1515 -131.951984)
				)
			)
		)
	)
	(zone
		(net "GND")
		(layer "In5.Cu")
		(hatch none 0.5)
		(connect_pads
			(clearance 0.5)
		)
		(min_thickness 0.25)
		(fill yes
			(thermal_gap 0.5)
			(thermal_bridge_width 0.5)
			(island_removal_mode 0)
		)
		(polygon
			(pts
				(arc
					(start 0.999998 -0.763016)
					(mid 0.832426 -0.832426)
					(end 0.763016 -0.999998)
				)
				(xy 0.763016 -340.829138) (xy 0.763016 -356.170738)
				(arc
					(start 0.763016 -370.000022)
					(mid 0.832426 -370.167594)
					(end 0.999998 -370.237004)
				)
				(arc
					(start 1.999996 -370.237004)
					(mid 3.246635 -370.753379)
					(end 3.76301 -372.000018)
				)
				(arc
					(start 3.76301 -384.999992)
					(mid 3.83242 -385.167564)
					(end 3.999992 -385.236974)
				)
				(arc
					(start 15.249906 -385.236974)
					(mid 15.417478 -385.167564)
					(end 15.486888 -384.999992)
				)
				(arc
					(start 15.486888 -383.29997)
					(mid 16.003263 -382.053331)
					(end 17.249902 -381.536956)
				)
				(arc
					(start 23.750016 -381.536956)
					(mid 24.996655 -382.053331)
					(end 25.51303 -383.29997)
				)
				(arc
					(start 25.51303 -384.999992)
					(mid 25.58244 -385.167564)
					(end 25.750012 -385.236974)
				)
				(arc
					(start 71.300086 -385.236974)
					(mid 71.467658 -385.167564)
					(end 71.537068 -384.999992)
				)
				(arc
					(start 71.537068 -381)
					(mid 72.053443 -379.753361)
					(end 73.300082 -379.236986)
				)
				(arc
					(start 125.299978 -379.236986)
					(mid 126.546617 -379.753361)
					(end 127.062992 -381)
				)
				(arc
					(start 127.062992 -384.999992)
					(mid 127.132402 -385.167564)
					(end 127.299974 -385.236974)
				)
				(arc
					(start 172.850048 -385.236974)
					(mid 173.01762 -385.167564)
					(end 173.08703 -384.999992)
				)
				(arc
					(start 173.08703 -383.29997)
					(mid 173.603405 -382.053331)
					(end 174.850044 -381.536956)
				)
				(arc
					(start 181.349904 -381.536956)
					(mid 182.596543 -382.053331)
					(end 183.112918 -383.29997)
				)
				(arc
					(start 183.112918 -384.999992)
					(mid 183.182328 -385.167564)
					(end 183.3499 -385.236974)
				)
				(arc
					(start 197.000114 -385.236974)
					(mid 197.167686 -385.167564)
					(end 197.237096 -384.999992)
				)
				(arc
					(start 197.237096 -381)
					(mid 197.753471 -379.753361)
					(end 199.00011 -379.236986)
				)
				(arc
					(start 251.000006 -379.236986)
					(mid 252.246645 -379.753361)
					(end 252.76302 -381)
				)
				(arc
					(start 252.76302 -384.999992)
					(mid 252.83243 -385.167564)
					(end 253.000002 -385.236974)
				)
				(arc
					(start 269.036292 -385.236974)
					(mid 269.126761 -385.218921)
					(end 269.203424 -385.167632)
				)
				(arc
					(start 271.617694 -382.753362)
					(mid 271.668989 -382.676683)
					(end 271.687036 -382.58623)
				)
				(arc
					(start 271.687036 -361.00004)
					(mid 272.203411 -359.753401)
					(end 273.45005 -359.237026)
				)
				(arc
					(start 275.75002 -359.237026)
					(mid 276.996659 -359.753401)
					(end 277.513034 -361.00004)
				)
				(arc
					(start 277.513034 -382.58623)
					(mid 277.531087 -382.676699)
					(end 277.582376 -382.753362)
				)
				(arc
					(start 279.996646 -385.167632)
					(mid 280.07334 -385.218844)
					(end 280.163778 -385.236974)
				)
				(arc
					(start 306.649882 -385.236974)
					(mid 306.817454 -385.167564)
					(end 306.886864 -384.999992)
				)
				(arc
					(start 306.886864 -383.29997)
					(mid 307.403239 -382.053331)
					(end 308.649878 -381.536956)
				)
				(arc
					(start 315.149992 -381.536956)
					(mid 316.396631 -382.053331)
					(end 316.913006 -383.29997)
				)
				(arc
					(start 316.913006 -384.999992)
					(mid 316.982416 -385.167564)
					(end 317.149988 -385.236974)
				)
				(arc
					(start 362.700062 -385.236974)
					(mid 362.867634 -385.167564)
					(end 362.937044 -384.999992)
				)
				(arc
					(start 362.937044 -381)
					(mid 363.453419 -379.753361)
					(end 364.700058 -379.236986)
				)
				(arc
					(start 416.699954 -379.236986)
					(mid 417.946593 -379.753361)
					(end 418.462968 -381)
				)
				(arc
					(start 418.462968 -384.999992)
					(mid 418.532378 -385.167564)
					(end 418.69995 -385.236974)
				)
				(arc
					(start 464.250024 -385.236974)
					(mid 464.417596 -385.167564)
					(end 464.487006 -384.999992)
				)
				(arc
					(start 464.487006 -383.29997)
					(mid 465.003381 -382.053331)
					(end 466.25002 -381.536956)
				)
				(arc
					(start 472.74988 -381.536956)
					(mid 473.996519 -382.053331)
					(end 474.512894 -383.29997)
				)
				(arc
					(start 474.512894 -384.999992)
					(mid 474.582304 -385.167564)
					(end 474.749876 -385.236974)
				)
				(arc
					(start 487.449876 -385.236974)
					(mid 487.617448 -385.167564)
					(end 487.686858 -384.999992)
				)
				(arc
					(start 487.686858 -372.000018)
					(mid 488.203143 -370.753469)
					(end 489.449618 -370.237004)
				)
				(arc
					(start 490.450124 -370.237004)
					(mid 490.617696 -370.167594)
					(end 490.687106 -370.000022)
				)
				(xy 490.687106 -341.003636) (xy 489.418122 -341.003636)
				(arc
					(start 489.418122 -368.968274)
					(mid 487.294792 -369.867389)
					(end 486.417874 -372.000018)
				)
				(xy 486.417874 -383.96799) (xy 475.781878 -383.96799)
				(arc
					(start 475.781878 -383.29997)
					(mid 474.893826 -381.156024)
					(end 472.74988 -380.267972)
				)
				(arc
					(start 466.25002 -380.267972)
					(mid 464.106074 -381.156024)
					(end 463.218022 -383.29997)
				)
				(xy 463.218022 -383.96799) (xy 419.731952 -383.96799)
				(arc
					(start 419.731952 -381)
					(mid 418.8439 -378.856054)
					(end 416.699954 -377.968002)
				)
				(arc
					(start 364.700058 -377.968002)
					(mid 362.556112 -378.856054)
					(end 361.66806 -381)
				)
				(xy 361.66806 -383.96799) (xy 318.18199 -383.96799)
				(arc
					(start 318.18199 -383.29997)
					(mid 317.293938 -381.156024)
					(end 315.149992 -380.267972)
				)
				(arc
					(start 308.649878 -380.267972)
					(mid 306.505932 -381.156024)
					(end 305.61788 -383.29997)
				)
				(xy 305.61788 -383.96799) (xy 280.591514 -383.96799) (xy 278.782018 -382.158494)
				(arc
					(start 278.782018 -361.00004)
					(mid 277.893966 -358.856094)
					(end 275.75002 -357.968042)
				)
				(arc
					(start 273.45005 -357.968042)
					(mid 271.306104 -358.856094)
					(end 270.418052 -361.00004)
				)
				(xy 270.418052 -382.158494) (xy 268.608556 -383.96799) (xy 254.032004 -383.96799)
				(arc
					(start 254.032004 -381)
					(mid 253.143952 -378.856054)
					(end 251.000006 -377.968002)
				)
				(arc
					(start 199.00011 -377.968002)
					(mid 196.856164 -378.856054)
					(end 195.968112 -381)
				)
				(xy 195.968112 -383.96799) (xy 184.381902 -383.96799)
				(arc
					(start 184.381902 -383.29997)
					(mid 183.49385 -381.156024)
					(end 181.349904 -380.267972)
				)
				(arc
					(start 174.850044 -380.267972)
					(mid 172.706098 -381.156024)
					(end 171.818046 -383.29997)
				)
				(xy 171.818046 -383.96799) (xy 128.331976 -383.96799)
				(arc
					(start 128.331976 -381)
					(mid 127.443924 -378.856054)
					(end 125.299978 -377.968002)
				)
				(arc
					(start 73.300082 -377.968002)
					(mid 71.156136 -378.856054)
					(end 70.268084 -381)
				)
				(xy 70.268084 -383.96799) (xy 26.782014 -383.96799)
				(arc
					(start 26.782014 -383.29997)
					(mid 25.893962 -381.156024)
					(end 23.750016 -380.267972)
				)
				(arc
					(start 17.249902 -380.267972)
					(mid 15.105956 -381.156024)
					(end 14.217904 -383.29997)
				)
				(xy 14.217904 -383.96799) (xy 5.031994 -383.96799)
				(arc
					(start 5.031994 -372.000018)
					(mid 4.155228 -369.867417)
					(end 2.032 -368.968274)
				)
				(xy 2.032 -356.915974) (xy 2.032 -340.228174) (xy 2.032 -340.147402) (xy 2.032 -340.020402) (xy 2.032 -2.032)
				(xy 196.96811 -2.032)
				(arc
					(start 196.96811 -47.200058)
					(mid 197.856162 -49.344004)
					(end 200.000108 -50.232056)
				)
				(xy 204.968094 -50.232056)
				(arc
					(start 204.968094 -62.00013)
					(mid 205.856146 -64.143822)
					(end 207.999838 -65.031874)
				)
				(xy 226.324414 -65.031874) (xy 226.324414 -63.76289)
				(arc
					(start 207.999838 -63.76289)
					(mid 206.753453 -63.246515)
					(end 206.237078 -62.00013)
				)
				(arc
					(start 206.237078 -49.200054)
					(mid 206.167668 -49.032482)
					(end 206.000096 -48.963072)
				)
				(arc
					(start 200.000108 -48.963072)
					(mid 198.753469 -48.446697)
					(end 198.237094 -47.200058)
				)
				(arc
					(start 198.237094 -0.999998)
					(mid 198.167684 -0.832426)
					(end 198.000112 -0.763016)
				)
			)
		)
	)
	(zone
		(layer "In5.Cu")
		(hatch none 0.5)
		(connect_pads
			(clearance 0)
		)
		(min_thickness 0.25)
		(keepout
			(tracks not_allowed)
			(vias allowed)
			(pads allowed)
			(copperpour not_allowed)
			(footprints allowed)
		)
		(placement
			(enabled no)
			(sheetname "")
		)
		(fill
			(thermal_gap 0.5)
			(thermal_bridge_width 0.5)
			(island_removal_mode 0)
		)
		(polygon
			(pts
				(arc
					(start 219.54871 -65.600072)
					(mid 219.00007 -65.051432)
					(end 218.45143 -65.600072)
				)
				(arc
					(start 218.45143 -66.999612)
					(mid 218.999943 -67.548506)
					(end 219.54871 -66.999866)
				)
				(arc
					(start 219.54871 -66.585846)
					(mid 219.465139 -66.543099)
					(end 219.372434 -66.528442)
				)
				(arc
					(start 219.184982 -66.528442)
					(mid 219.118404 -66.553052)
					(end 219.08389 -66.615056)
				)
				(arc
					(start 219.08389 -66.615056)
					(mid 218.999422 -67.393699)
					(end 218.91752 -66.614802)
				)
				(xy 218.91752 -66.596514)
				(arc
					(start 218.92006 -66.593974)
					(mid 218.995852 -66.441674)
					(end 219.148152 -66.365882)
				)
				(xy 219.150692 -66.363342) (xy 219.406724 -66.363342)
				(arc
					(start 219.407994 -66.364612)
					(mid 219.479671 -66.375846)
					(end 219.54871 -66.39814)
				)
				(arc
					(start 219.54871 -66.263266)
					(mid 219.461592 -66.24313)
					(end 219.372434 -66.236342)
				)
				(xy 219.150692 -66.236342)
				(arc
					(start 219.148152 -66.233802)
					(mid 218.995852 -66.15801)
					(end 218.92006 -66.00571)
				)
				(xy 218.91752 -66.00317)
				(arc
					(start 218.91752 -65.985136)
					(mid 218.998391 -65.206367)
					(end 219.08389 -65.984628)
				)
				(arc
					(start 219.08389 -65.984628)
					(mid 219.118437 -66.046594)
					(end 219.184982 -66.071242)
				)
				(xy 219.406724 -66.071242)
				(arc
					(start 219.407486 -66.072004)
					(mid 219.478572 -66.078701)
					(end 219.54871 -66.09207)
				)
			)
		)
	)
	(zone
		(net "P3V3_STBY_A")
		(layer "In5.Cu")
		(hatch none 0.5)
		(connect_pads
			(clearance 0.5)
		)
		(min_thickness 0.25)
		(fill yes
			(thermal_gap 0.5)
			(thermal_bridge_width 0.5)
			(island_removal_mode 0)
		)
		(polygon
			(pts
				(xy 240.284 -314.071) (xy 251.587 -314.071) (xy 252.222 -313.436) (xy 252.222 -304.038) (xy 249.047 -300.863)
				(xy 241.935 -300.863) (xy 240.03 -302.768) (xy 240.03 -313.817)
			)
		)
	)
	(zone
		(layer "In5.Cu")
		(hatch none 0.5)
		(connect_pads
			(clearance 0)
		)
		(min_thickness 0.25)
		(keepout
			(tracks not_allowed)
			(vias allowed)
			(pads allowed)
			(copperpour not_allowed)
			(footprints allowed)
		)
		(placement
			(enabled no)
			(sheetname "")
		)
		(fill
			(thermal_gap 0.5)
			(thermal_bridge_width 0.5)
			(island_removal_mode 0)
		)
		(polygon
			(pts
				(arc
					(start 285.436564 -142.345664)
					(mid 284.887924 -142.894304)
					(end 285.436564 -143.442944)
				)
				(arc
					(start 286.836612 -143.442944)
					(mid 287.385252 -142.894304)
					(end 286.836612 -142.345664)
				)
				(arc
					(start 286.349186 -142.345664)
					(mid 286.359162 -142.403649)
					(end 286.364426 -142.46225)
				)
				(xy 286.365188 -142.463012)
				(arc
					(start 286.365188 -142.675102)
					(mid 286.389429 -142.752804)
					(end 286.45358 -142.802864)
				)
				(arc
					(start 286.45358 -142.802864)
					(mid 287.230295 -142.900552)
					(end 286.450786 -142.972536)
				)
				(arc
					(start 286.450786 -142.972536)
					(mid 286.283253 -142.883172)
					(end 286.202374 -142.711424)
				)
				(xy 286.200088 -142.709392)
				(arc
					(start 286.200088 -142.497302)
					(mid 286.194931 -142.420788)
					(end 286.179514 -142.345664)
				)
				(arc
					(start 286.046164 -142.345664)
					(mid 286.062813 -142.402839)
					(end 286.071564 -142.461742)
				)
				(xy 286.073088 -142.463012) (xy 286.073088 -142.709392)
				(arc
					(start 286.070802 -142.711424)
					(mid 285.989834 -142.883087)
					(end 285.82239 -142.972536)
				)
				(arc
					(start 285.82239 -142.972536)
					(mid 285.04289 -142.900552)
					(end 285.819596 -142.802864)
				)
				(arc
					(start 285.819596 -142.802864)
					(mid 285.883682 -142.752759)
					(end 285.907988 -142.675102)
				)
				(arc
					(start 285.907988 -142.497302)
					(mid 285.896309 -142.418112)
					(end 285.862268 -142.345664)
				)
			)
		)
	)
	(zone
		(layer "In5.Cu")
		(hatch none 0.5)
		(connect_pads
			(clearance 0)
		)
		(min_thickness 0.25)
		(keepout
			(tracks not_allowed)
			(vias allowed)
			(pads allowed)
			(copperpour not_allowed)
			(footprints allowed)
		)
		(placement
			(enabled no)
			(sheetname "")
		)
		(fill
			(thermal_gap 0.5)
			(thermal_bridge_width 0.5)
			(island_removal_mode 0)
		)
		(polygon
			(pts
				(arc
					(start 221.348808 -70.39991)
					(mid 220.800168 -69.85127)
					(end 220.251528 -70.39991)
				)
				(arc
					(start 220.251528 -71.799704)
					(mid 220.800041 -72.348598)
					(end 221.348808 -71.799958)
				)
				(arc
					(start 221.348808 -71.385938)
					(mid 221.265237 -71.343191)
					(end 221.172532 -71.328534)
				)
				(arc
					(start 220.98508 -71.328534)
					(mid 220.918502 -71.353144)
					(end 220.883988 -71.415148)
				)
				(arc
					(start 220.883988 -71.415148)
					(mid 220.79952 -72.193791)
					(end 220.717618 -71.414894)
				)
				(xy 220.717618 -71.396606)
				(arc
					(start 220.720158 -71.394066)
					(mid 220.79595 -71.241766)
					(end 220.94825 -71.165974)
				)
				(xy 220.95079 -71.163434) (xy 221.206822 -71.163434)
				(arc
					(start 221.208092 -71.164704)
					(mid 221.279769 -71.175938)
					(end 221.348808 -71.198232)
				)
				(arc
					(start 221.348808 -71.063358)
					(mid 221.26169 -71.043222)
					(end 221.172532 -71.036434)
				)
				(xy 220.95079 -71.036434)
				(arc
					(start 220.94825 -71.033894)
					(mid 220.79595 -70.958102)
					(end 220.720158 -70.805802)
				)
				(xy 220.717618 -70.803262)
				(arc
					(start 220.717618 -70.784974)
					(mid 220.799521 -70.006097)
					(end 220.883988 -70.78472)
				)
				(arc
					(start 220.883988 -70.78472)
					(mid 220.918535 -70.846686)
					(end 220.98508 -70.871334)
				)
				(xy 221.206822 -70.871334)
				(arc
					(start 221.207584 -70.872096)
					(mid 221.27867 -70.878793)
					(end 221.348808 -70.892162)
				)
			)
		)
	)
	(zone
		(layer "In5.Cu")
		(hatch none 0.5)
		(connect_pads
			(clearance 0)
		)
		(min_thickness 0.25)
		(keepout
			(tracks not_allowed)
			(vias allowed)
			(pads allowed)
			(copperpour not_allowed)
			(footprints allowed)
		)
		(placement
			(enabled no)
			(sheetname "")
		)
		(fill
			(thermal_gap 0.5)
			(thermal_bridge_width 0.5)
			(island_removal_mode 0)
		)
		(polygon
			(pts
				(arc
					(start 285.436564 -196.74586)
					(mid 284.887924 -197.2945)
					(end 285.436564 -197.84314)
				)
				(arc
					(start 286.836612 -197.84314)
					(mid 287.385252 -197.2945)
					(end 286.836612 -196.74586)
				)
				(arc
					(start 286.392112 -196.74586)
					(mid 286.381482 -196.780326)
					(end 286.377888 -196.816218)
				)
				(xy 286.377888 -196.820536) (xy 286.377888 -197.0659)
				(arc
					(start 286.377888 -197.070218)
					(mid 286.398328 -197.146115)
					(end 286.454088 -197.201536)
				)
				(arc
					(start 286.454088 -197.201536)
					(mid 287.229997 -197.310944)
					(end 286.447738 -197.356222)
				)
				(arc
					(start 286.447738 -197.356222)
					(mid 286.301693 -197.261863)
					(end 286.233362 -197.101968)
				)
				(xy 286.231584 -197.100444) (xy 286.231584 -197.078854) (xy 286.231584 -197.070218) (xy 286.231584 -197.0659)
				(xy 286.231584 -196.820536) (xy 286.231584 -196.816218) (xy 286.231584 -196.807074) (xy 286.231584 -196.785992)
				(arc
					(start 286.233108 -196.784468)
					(mid 286.235575 -196.765072)
					(end 286.239204 -196.74586)
				)
				(arc
					(start 286.046164 -196.74586)
					(mid 286.042557 -196.780957)
					(end 286.041338 -196.816218)
				)
				(xy 286.041084 -196.820536) (xy 286.041084 -197.0659) (xy 286.041338 -197.070218) (xy 286.041084 -197.078854)
				(xy 286.041084 -197.100444)
				(arc
					(start 286.03956 -197.101968)
					(mid 285.971328 -197.261787)
					(end 285.825438 -197.356222)
				)
				(arc
					(start 285.825438 -197.356222)
					(mid 285.04315 -197.310565)
					(end 285.819088 -197.201282)
				)
				(arc
					(start 285.819088 -197.201282)
					(mid 285.874653 -197.145949)
					(end 285.895034 -197.070218)
				)
				(xy 285.895288 -197.0659) (xy 285.895288 -196.820536) (xy 285.895034 -196.816218) (xy 285.895288 -196.803264)
				(xy 285.895288 -196.785992) (xy 285.895796 -196.785484) (xy 285.898844 -196.74586)
			)
		)
	)
	(zone
		(net "MB0_CM_GATE_R")
		(layer "In5.Cu")
		(hatch none 0.5)
		(connect_pads
			(clearance 0.5)
		)
		(min_thickness 0.25)
		(fill yes
			(thermal_gap 0.5)
			(thermal_bridge_width 0.5)
			(island_removal_mode 0)
		)
		(polygon
			(pts
				(xy 208.534 -328.549) (xy 208.788 -328.295) (xy 213.36 -328.295) (xy 214.249 -329.184) (xy 214.249 -356.235)
				(xy 213.741 -356.743) (xy 211.963 -356.743) (xy 211.455 -356.235) (xy 211.455 -353.568) (xy 212.598 -352.425)
				(xy 212.598 -349.885) (xy 211.963 -349.25) (xy 208.788 -349.25) (xy 208.534 -348.996) (xy 208.534 -347.472)
				(xy 208.788 -347.218) (xy 211.963 -347.218) (xy 212.598 -346.583) (xy 212.598 -340.487) (xy 211.709 -339.598)
				(xy 208.788 -339.598) (xy 208.534 -339.344) (xy 208.534 -337.693) (xy 208.788 -337.439) (xy 211.963 -337.439)
				(xy 212.598 -336.804) (xy 212.598 -330.708) (xy 212.09 -330.2) (xy 208.788 -330.2) (xy 208.534 -329.946)
			)
		)
	)
	(zone
		(layer "In5.Cu")
		(hatch none 0.5)
		(connect_pads
			(clearance 0)
		)
		(min_thickness 0.25)
		(keepout
			(tracks not_allowed)
			(vias allowed)
			(pads allowed)
			(copperpour not_allowed)
			(footprints allowed)
		)
		(placement
			(enabled no)
			(sheetname "")
		)
		(fill
			(thermal_gap 0.5)
			(thermal_bridge_width 0.5)
			(island_removal_mode 0)
		)
		(polygon
			(pts
				(arc
					(start 64.54394 -133.11505)
					(mid 64.0588 -132.62991)
					(end 63.57366 -133.11505)
				)
				(arc
					(start 63.57366 -134.384796)
					(mid 64.058673 -134.87019)
					(end 64.54394 -134.38505)
				)
				(xy 64.54394 -133.991096) (xy 64.183768 -133.991096)
				(arc
					(start 64.17945 -133.99135)
					(mid 64.145864 -134.005262)
					(end 64.131952 -134.038848)
				)
				(xy 64.131952 -134.043166)
				(arc
					(start 64.131952 -134.12851)
					(mid 64.0588 -134.651816)
					(end 63.985648 -134.12851)
				)
				(xy 63.985648 -134.043166) (xy 63.985648 -134.038848) (xy 63.985648 -134.031736) (xy 63.985648 -134.008622)
				(arc
					(start 63.988442 -134.005828)
					(mid 64.042384 -133.901782)
					(end 64.14643 -133.84784)
				)
				(xy 64.149224 -133.8453) (xy 64.172338 -133.8453) (xy 64.17945 -133.845046) (xy 64.183768 -133.8453)
				(xy 64.54394 -133.8453) (xy 64.54394 -133.6548) (xy 64.183768 -133.6548) (xy 64.17945 -133.6548)
				(xy 64.172338 -133.6548) (xy 64.149224 -133.6548)
				(arc
					(start 64.14643 -133.652006)
					(mid 64.042384 -133.598064)
					(end 63.988442 -133.494018)
				)
				(xy 63.985648 -133.491224) (xy 63.985648 -133.46811) (xy 63.985648 -133.460998) (xy 63.985648 -133.45668)
				(arc
					(start 63.985648 -133.37159)
					(mid 64.0588 -132.848284)
					(end 64.131952 -133.37159)
				)
				(xy 64.131952 -133.45668)
				(arc
					(start 64.131952 -133.460998)
					(mid 64.145864 -133.494584)
					(end 64.17945 -133.508496)
				)
				(xy 64.183768 -133.508496) (xy 64.54394 -133.508496)
			)
		)
	)
	(zone
		(layer "In5.Cu")
		(hatch none 0.5)
		(connect_pads
			(clearance 0)
		)
		(min_thickness 0.25)
		(keepout
			(tracks not_allowed)
			(vias allowed)
			(pads allowed)
			(copperpour not_allowed)
			(footprints allowed)
		)
		(placement
			(enabled no)
			(sheetname "")
		)
		(fill
			(thermal_gap 0.5)
			(thermal_bridge_width 0.5)
			(island_removal_mode 0)
		)
		(polygon
			(pts
				(arc
					(start 215.948768 -65.600072)
					(mid 215.400128 -65.051432)
					(end 214.851488 -65.600072)
				)
				(arc
					(start 214.851488 -66.999612)
					(mid 215.400001 -67.548506)
					(end 215.948768 -66.999866)
				)
				(arc
					(start 215.948768 -66.585846)
					(mid 215.865197 -66.543099)
					(end 215.772492 -66.528442)
				)
				(arc
					(start 215.58504 -66.528442)
					(mid 215.518462 -66.553052)
					(end 215.483948 -66.615056)
				)
				(arc
					(start 215.483948 -66.615056)
					(mid 215.39948 -67.393699)
					(end 215.317578 -66.614802)
				)
				(xy 215.317578 -66.596514)
				(arc
					(start 215.320118 -66.593974)
					(mid 215.39591 -66.441674)
					(end 215.54821 -66.365882)
				)
				(xy 215.55075 -66.363342) (xy 215.806782 -66.363342)
				(arc
					(start 215.808052 -66.364612)
					(mid 215.879729 -66.375846)
					(end 215.948768 -66.39814)
				)
				(arc
					(start 215.948768 -66.263266)
					(mid 215.86165 -66.24313)
					(end 215.772492 -66.236342)
				)
				(xy 215.55075 -66.236342)
				(arc
					(start 215.54821 -66.233802)
					(mid 215.39591 -66.15801)
					(end 215.320118 -66.00571)
				)
				(xy 215.317578 -66.00317)
				(arc
					(start 215.317578 -65.985136)
					(mid 215.398449 -65.206367)
					(end 215.483948 -65.984628)
				)
				(arc
					(start 215.483948 -65.984628)
					(mid 215.518495 -66.046594)
					(end 215.58504 -66.071242)
				)
				(xy 215.806782 -66.071242)
				(arc
					(start 215.807544 -66.072004)
					(mid 215.87863 -66.078701)
					(end 215.948768 -66.09207)
				)
			)
		)
	)
	(zone
		(net "GND")
		(layer "In6.Cu")
		(hatch none 0.5)
		(connect_pads
			(clearance 0.5)
		)
		(min_thickness 0.25)
		(fill yes
			(thermal_gap 0.5)
			(thermal_bridge_width 0.5)
			(island_removal_mode 0)
		)
		(polygon
			(pts
				(arc
					(start 0.999998 -0.763016)
					(mid 0.832426 -0.832426)
					(end 0.763016 -0.999998)
				)
				(arc
					(start 0.763016 -370.000022)
					(mid 0.832426 -370.167594)
					(end 0.999998 -370.237004)
				)
				(arc
					(start 1.999996 -370.237004)
					(mid 3.246635 -370.753379)
					(end 3.76301 -372.000018)
				)
				(arc
					(start 3.76301 -384.999992)
					(mid 3.83242 -385.167564)
					(end 3.999992 -385.236974)
				)
				(arc
					(start 15.249906 -385.236974)
					(mid 15.417478 -385.167564)
					(end 15.486888 -384.999992)
				)
				(arc
					(start 15.486888 -383.29997)
					(mid 16.003263 -382.053331)
					(end 17.249902 -381.536956)
				)
				(arc
					(start 23.750016 -381.536956)
					(mid 24.996655 -382.053331)
					(end 25.51303 -383.29997)
				)
				(arc
					(start 25.51303 -384.999992)
					(mid 25.58244 -385.167564)
					(end 25.750012 -385.236974)
				)
				(arc
					(start 71.300086 -385.236974)
					(mid 71.467658 -385.167564)
					(end 71.537068 -384.999992)
				)
				(arc
					(start 71.537068 -381)
					(mid 72.053443 -379.753361)
					(end 73.300082 -379.236986)
				)
				(arc
					(start 125.299978 -379.236986)
					(mid 126.546617 -379.753361)
					(end 127.062992 -381)
				)
				(arc
					(start 127.062992 -384.999992)
					(mid 127.132402 -385.167564)
					(end 127.299974 -385.236974)
				)
				(arc
					(start 172.850048 -385.236974)
					(mid 173.01762 -385.167564)
					(end 173.08703 -384.999992)
				)
				(arc
					(start 173.08703 -383.29997)
					(mid 173.603405 -382.053331)
					(end 174.850044 -381.536956)
				)
				(arc
					(start 181.349904 -381.536956)
					(mid 182.596543 -382.053331)
					(end 183.112918 -383.29997)
				)
				(arc
					(start 183.112918 -384.999992)
					(mid 183.182328 -385.167564)
					(end 183.3499 -385.236974)
				)
				(arc
					(start 197.000114 -385.236974)
					(mid 197.167686 -385.167564)
					(end 197.237096 -384.999992)
				)
				(arc
					(start 197.237096 -381)
					(mid 197.753471 -379.753361)
					(end 199.00011 -379.236986)
				)
				(arc
					(start 251.000006 -379.236986)
					(mid 252.246645 -379.753361)
					(end 252.76302 -381)
				)
				(arc
					(start 252.76302 -384.999992)
					(mid 252.83243 -385.167564)
					(end 253.000002 -385.236974)
				)
				(arc
					(start 269.036292 -385.236974)
					(mid 269.126761 -385.218921)
					(end 269.203424 -385.167632)
				)
				(arc
					(start 271.617694 -382.753362)
					(mid 271.668989 -382.676683)
					(end 271.687036 -382.58623)
				)
				(arc
					(start 271.687036 -361.00004)
					(mid 272.203411 -359.753401)
					(end 273.45005 -359.237026)
				)
				(arc
					(start 275.75002 -359.237026)
					(mid 276.996659 -359.753401)
					(end 277.513034 -361.00004)
				)
				(arc
					(start 277.513034 -382.58623)
					(mid 277.531087 -382.676699)
					(end 277.582376 -382.753362)
				)
				(arc
					(start 279.996646 -385.167632)
					(mid 280.07334 -385.218844)
					(end 280.163778 -385.236974)
				)
				(arc
					(start 306.649882 -385.236974)
					(mid 306.817454 -385.167564)
					(end 306.886864 -384.999992)
				)
				(arc
					(start 306.886864 -383.29997)
					(mid 307.403239 -382.053331)
					(end 308.649878 -381.536956)
				)
				(arc
					(start 315.149992 -381.536956)
					(mid 316.396631 -382.053331)
					(end 316.913006 -383.29997)
				)
				(arc
					(start 316.913006 -384.999992)
					(mid 316.982416 -385.167564)
					(end 317.149988 -385.236974)
				)
				(arc
					(start 362.700062 -385.236974)
					(mid 362.867634 -385.167564)
					(end 362.937044 -384.999992)
				)
				(arc
					(start 362.937044 -381)
					(mid 363.453419 -379.753361)
					(end 364.700058 -379.236986)
				)
				(arc
					(start 416.699954 -379.236986)
					(mid 417.946593 -379.753361)
					(end 418.462968 -381)
				)
				(arc
					(start 418.462968 -384.999992)
					(mid 418.532378 -385.167564)
					(end 418.69995 -385.236974)
				)
				(arc
					(start 464.250024 -385.236974)
					(mid 464.417596 -385.167564)
					(end 464.487006 -384.999992)
				)
				(arc
					(start 464.487006 -383.29997)
					(mid 465.003381 -382.053331)
					(end 466.25002 -381.536956)
				)
				(arc
					(start 472.74988 -381.536956)
					(mid 473.996519 -382.053331)
					(end 474.512894 -383.29997)
				)
				(arc
					(start 474.512894 -384.999992)
					(mid 474.582304 -385.167564)
					(end 474.749876 -385.236974)
				)
				(arc
					(start 487.449876 -385.236974)
					(mid 487.617448 -385.167564)
					(end 487.686858 -384.999992)
				)
				(arc
					(start 487.686858 -372.000018)
					(mid 488.203143 -370.753469)
					(end 489.449618 -370.237004)
				)
				(arc
					(start 490.450124 -370.237004)
					(mid 490.617696 -370.167594)
					(end 490.687106 -370.000022)
				)
				(arc
					(start 490.687106 -0.999998)
					(mid 490.617696 -0.832426)
					(end 490.450124 -0.763016)
				)
				(arc
					(start 311.999884 -0.763016)
					(mid 311.832312 -0.832426)
					(end 311.762902 -0.999998)
				)
				(arc
					(start 311.762902 -47.200058)
					(mid 311.246527 -48.446697)
					(end 309.999888 -48.963072)
				)
				(arc
					(start 269.999968 -48.963072)
					(mid 269.832396 -49.032482)
					(end 269.762986 -49.200054)
				)
				(arc
					(start 269.762986 -61.999876)
					(mid 269.246611 -63.246515)
					(end 267.999972 -63.76289)
				)
				(arc
					(start 207.999838 -63.76289)
					(mid 206.753453 -63.246515)
					(end 206.237078 -62.00013)
				)
				(arc
					(start 206.237078 -49.200054)
					(mid 206.167668 -49.032482)
					(end 206.000096 -48.963072)
				)
				(arc
					(start 200.000108 -48.963072)
					(mid 198.753469 -48.446697)
					(end 198.237094 -47.200058)
				)
				(arc
					(start 198.237094 -0.999998)
					(mid 198.167684 -0.832426)
					(end 198.000112 -0.763016)
				)
			)
		)
		(polygon
			(pts
				(xy 204.307694 -328.7395) (xy 166.0144 -328.7395) (xy 166.0144 -358.5845) (xy 204.269594 -358.5845)
				(xy 204.8256 -358.028494) (xy 204.8256 -329.257406)
			)
		)
		(polygon
			(pts
				(xy 157.431994 -326.8345) (xy 152.194006 -326.8345) (xy 151.4475 -327.581006) (xy 151.4475 -330.756006)
				(xy 151.18461 -331.018896) (xy 104.06761 -331.018896) (xy 102.5525 -332.534006) (xy 102.5525 -346.280994)
				(xy 103.4415 -347.169994) (xy 103.4415 -364.348776) (xy 103.964994 -364.87227) (xy 109.369606 -364.87227)
				(xy 112.286796 -361.95508) (xy 123.153932 -361.95508) (xy 126.524512 -358.5845) (xy 160.9725 -358.5845)
				(xy 160.9725 -328.7395) (xy 158.066994 -328.7395) (xy 157.7975 -328.470006) (xy 157.7975 -327.200006)
			)
		)
		(polygon
			(pts
				(arc
					(start 159.193992 -248.115074)
					(mid 158.708852 -247.629934)
					(end 158.223712 -248.115074)
				)
				(arc
					(start 158.223712 -249.385328)
					(mid 158.708979 -249.870214)
					(end 159.193992 -249.385074)
				)
			)
		)
		(polygon
			(pts
				(arc
					(start 481.824792 -248.11482)
					(mid 481.339525 -247.629934)
					(end 480.854512 -248.115074)
				)
				(arc
					(start 480.854512 -249.385074)
					(mid 481.339652 -249.870214)
					(end 481.824792 -249.385074)
				)
			)
		)
		(polygon
			(pts
				(arc
					(start 450.27469 -248.11482)
					(mid 449.789423 -247.629934)
					(end 449.30441 -248.115074)
				)
				(arc
					(start 449.30441 -249.385074)
					(mid 449.78955 -249.870214)
					(end 450.27469 -249.385074)
				)
			)
		)
		(polygon
			(pts
				(arc
					(start 418.724842 -248.11482)
					(mid 418.239575 -247.629934)
					(end 417.754562 -248.115074)
				)
				(arc
					(start 417.754562 -249.385074)
					(mid 418.239702 -249.870214)
					(end 418.724842 -249.385074)
				)
			)
		)
		(polygon
			(pts
				(arc
					(start 387.17474 -248.11482)
					(mid 386.689473 -247.629934)
					(end 386.20446 -248.115074)
				)
				(arc
					(start 386.20446 -249.385074)
					(mid 386.6896 -249.870214)
					(end 387.17474 -249.385074)
				)
			)
		)
		(polygon
			(pts
				(arc
					(start 355.624892 -248.11482)
					(mid 355.139625 -247.629934)
					(end 354.654612 -248.115074)
				)
				(arc
					(start 354.654612 -249.385074)
					(mid 355.139752 -249.870214)
					(end 355.624892 -249.385074)
				)
			)
		)
		(polygon
			(pts
				(arc
					(start 324.07479 -248.11482)
					(mid 323.589523 -247.629934)
					(end 323.10451 -248.115074)
				)
				(arc
					(start 323.10451 -249.385074)
					(mid 323.58965 -249.870214)
					(end 324.07479 -249.385074)
				)
			)
		)
		(polygon
			(pts
				(arc
					(start 190.744094 -248.11482)
					(mid 190.258827 -247.629934)
					(end 189.773814 -248.115074)
				)
				(arc
					(start 189.773814 -249.385074)
					(mid 190.258954 -249.870214)
					(end 190.744094 -249.385074)
				)
			)
		)
		(polygon
			(pts
				(arc
					(start 127.64389 -248.11482)
					(mid 127.158623 -247.629934)
					(end 126.67361 -248.115074)
				)
				(arc
					(start 126.67361 -249.385074)
					(mid 127.15875 -249.870214)
					(end 127.64389 -249.385074)
				)
			)
		)
		(polygon
			(pts
				(arc
					(start 96.094042 -248.11482)
					(mid 95.608775 -247.629934)
					(end 95.123762 -248.115074)
				)
				(arc
					(start 95.123762 -249.385074)
					(mid 95.608902 -249.870214)
					(end 96.094042 -249.385074)
				)
			)
		)
		(polygon
			(pts
				(arc
					(start 64.54394 -248.11482)
					(mid 64.058673 -247.629934)
					(end 63.57366 -248.115074)
				)
				(arc
					(start 63.57366 -249.385074)
					(mid 64.0588 -249.870214)
					(end 64.54394 -249.385074)
				)
			)
		)
		(polygon
			(pts
				(arc
					(start 32.994092 -248.11482)
					(mid 32.508825 -247.629934)
					(end 32.023812 -248.115074)
				)
				(arc
					(start 32.023812 -249.385074)
					(mid 32.508952 -249.870214)
					(end 32.994092 -249.385074)
				)
			)
		)
		(polygon
			(pts
				(arc
					(start 414.527492 -244.444774)
					(mid 414.042352 -243.959634)
					(end 413.557212 -244.444774)
				)
				(arc
					(start 413.557212 -245.588028)
					(mid 414.042479 -246.072914)
					(end 414.527492 -245.587774)
				)
			)
		)
		(polygon
			(pts
				(arc
					(start 192.520824 -244.419374)
					(mid 192.035684 -243.934234)
					(end 191.550544 -244.419374)
				)
				(arc
					(start 191.550544 -245.562628)
					(mid 192.035811 -246.047514)
					(end 192.520824 -245.562374)
				)
			)
		)
		(polygon
			(pts
				(arc
					(start 160.970722 -244.419374)
					(mid 160.485582 -243.934234)
					(end 160.000442 -244.419374)
				)
				(arc
					(start 160.000442 -245.562628)
					(mid 160.485709 -246.047514)
					(end 160.970722 -245.562374)
				)
			)
		)
		(polygon
			(pts
				(arc
					(start 129.42062 -244.419374)
					(mid 128.93548 -243.934234)
					(end 128.45034 -244.419374)
				)
				(arc
					(start 128.45034 -245.562628)
					(mid 128.935607 -246.047514)
					(end 129.42062 -245.562374)
				)
			)
		)
		(polygon
			(pts
				(arc
					(start 97.870772 -244.419374)
					(mid 97.385632 -243.934234)
					(end 96.900492 -244.419374)
				)
				(arc
					(start 96.900492 -245.562628)
					(mid 97.385759 -246.047514)
					(end 97.870772 -245.562374)
				)
			)
		)
		(polygon
			(pts
				(arc
					(start 66.32067 -244.419374)
					(mid 65.83553 -243.934234)
					(end 65.35039 -244.419374)
				)
				(arc
					(start 65.35039 -245.562628)
					(mid 65.835657 -246.047514)
					(end 66.32067 -245.562374)
				)
			)
		)
		(polygon
			(pts
				(arc
					(start 34.770822 -244.419374)
					(mid 34.285682 -243.934234)
					(end 33.800542 -244.419374)
				)
				(arc
					(start 33.800542 -245.562628)
					(mid 34.285809 -246.047514)
					(end 34.770822 -245.562374)
				)
			)
		)
		(polygon
			(pts
				(arc
					(start 351.427542 -244.317774)
					(mid 350.942402 -243.832634)
					(end 350.457262 -244.317774)
				)
				(arc
					(start 350.457262 -245.461028)
					(mid 350.942529 -245.945914)
					(end 351.427542 -245.460774)
				)
			)
		)
		(polygon
			(pts
				(arc
					(start 477.637602 -244.312694)
					(mid 477.152462 -243.827554)
					(end 476.667322 -244.312694)
				)
				(arc
					(start 476.667322 -245.455948)
					(mid 477.152589 -245.940834)
					(end 477.637602 -245.455694)
				)
			)
		)
		(polygon
			(pts
				(arc
					(start 446.0875 -244.312694)
					(mid 445.60236 -243.827554)
					(end 445.11722 -244.312694)
				)
				(arc
					(start 445.11722 -245.455948)
					(mid 445.602487 -245.940834)
					(end 446.0875 -245.455694)
				)
			)
		)
		(polygon
			(pts
				(arc
					(start 319.8876 -244.312694)
					(mid 319.40246 -243.827554)
					(end 318.91732 -244.312694)
				)
				(arc
					(start 318.91732 -245.455948)
					(mid 319.402587 -245.940834)
					(end 319.8876 -245.455694)
				)
			)
		)
		(polygon
			(pts
				(arc
					(start 382.97739 -244.302534)
					(mid 382.49225 -243.817394)
					(end 382.00711 -244.302534)
				)
				(arc
					(start 382.00711 -245.445788)
					(mid 382.492377 -245.930674)
					(end 382.97739 -245.445534)
				)
			)
		)
		(polygon
			(pts
				(arc
					(start 287.83661 -239.243108)
					(mid 288.38525 -238.694468)
					(end 287.83661 -238.145828)
				)
				(arc
					(start 286.436562 -238.145828)
					(mid 285.887922 -238.694468)
					(end 286.436562 -239.243108)
				)
			)
		)
		(polygon
			(pts
				(arc
					(start 280.636726 -239.243108)
					(mid 281.185366 -238.694468)
					(end 280.636726 -238.145828)
				)
				(arc
					(start 279.236678 -238.145828)
					(mid 278.688038 -238.694468)
					(end 279.236678 -239.243108)
				)
			)
		)
		(polygon
			(pts
				(arc
					(start 286.836612 -237.44301)
					(mid 287.385252 -236.89437)
					(end 286.836612 -236.34573)
				)
				(arc
					(start 285.436564 -236.34573)
					(mid 284.887924 -236.89437)
					(end 285.436564 -237.44301)
				)
			)
		)
		(polygon
			(pts
				(arc
					(start 279.636728 -237.44301)
					(mid 280.185368 -236.89437)
					(end 279.636728 -236.34573)
				)
				(arc
					(start 278.23668 -236.34573)
					(mid 277.68804 -236.89437)
					(end 278.23668 -237.44301)
				)
			)
		)
		(polygon
			(pts
				(arc
					(start 287.83661 -235.643166)
					(mid 288.38525 -235.094526)
					(end 287.83661 -234.545886)
				)
				(arc
					(start 286.436562 -234.545886)
					(mid 285.887922 -235.094526)
					(end 286.436562 -235.643166)
				)
			)
		)
		(polygon
			(pts
				(arc
					(start 280.636726 -235.643166)
					(mid 281.185366 -235.094526)
					(end 280.636726 -234.545886)
				)
				(arc
					(start 279.236678 -234.545886)
					(mid 278.688038 -235.094526)
					(end 279.236678 -235.643166)
				)
			)
		)
		(polygon
			(pts
				(arc
					(start 286.836612 -233.843068)
					(mid 287.385252 -233.294428)
					(end 286.836612 -232.745788)
				)
				(arc
					(start 285.436564 -232.745788)
					(mid 284.887924 -233.294428)
					(end 285.436564 -233.843068)
				)
			)
		)
		(polygon
			(pts
				(arc
					(start 279.636728 -233.843068)
					(mid 280.185368 -233.294428)
					(end 279.636728 -232.745788)
				)
				(arc
					(start 278.23668 -232.745788)
					(mid 277.68804 -233.294428)
					(end 278.23668 -233.843068)
				)
			)
		)
		(polygon
			(pts
				(arc
					(start 287.83661 -232.043224)
					(mid 288.38525 -231.494584)
					(end 287.83661 -230.945944)
				)
				(arc
					(start 286.436562 -230.945944)
					(mid 285.887922 -231.494584)
					(end 286.436562 -232.043224)
				)
			)
		)
		(polygon
			(pts
				(arc
					(start 280.636726 -232.043224)
					(mid 281.185366 -231.494584)
					(end 280.636726 -230.945944)
				)
				(arc
					(start 279.236678 -230.945944)
					(mid 278.688038 -231.494584)
					(end 279.236678 -232.043224)
				)
			)
		)
		(polygon
			(pts
				(arc
					(start 286.836612 -230.243126)
					(mid 287.385252 -229.694486)
					(end 286.836612 -229.145846)
				)
				(arc
					(start 285.436564 -229.145846)
					(mid 284.887924 -229.694486)
					(end 285.436564 -230.243126)
				)
			)
		)
		(polygon
			(pts
				(arc
					(start 279.636728 -230.243126)
					(mid 280.185368 -229.694486)
					(end 279.636728 -229.145846)
				)
				(arc
					(start 278.23668 -229.145846)
					(mid 277.68804 -229.694486)
					(end 278.23668 -230.243126)
				)
			)
		)
		(polygon
			(pts
				(arc
					(start 287.83661 -228.443028)
					(mid 288.38525 -227.894388)
					(end 287.83661 -227.345748)
				)
				(arc
					(start 286.436562 -227.345748)
					(mid 285.887922 -227.894388)
					(end 286.436562 -228.443028)
				)
			)
		)
		(polygon
			(pts
				(arc
					(start 280.636726 -228.443028)
					(mid 281.185366 -227.894388)
					(end 280.636726 -227.345748)
				)
				(arc
					(start 279.236678 -227.345748)
					(mid 278.688038 -227.894388)
					(end 279.236678 -228.443028)
				)
			)
		)
		(polygon
			(pts
				(arc
					(start 286.836612 -226.643184)
					(mid 287.385252 -226.094544)
					(end 286.836612 -225.545904)
				)
				(arc
					(start 285.436564 -225.545904)
					(mid 284.887924 -226.094544)
					(end 285.436564 -226.643184)
				)
			)
		)
		(polygon
			(pts
				(arc
					(start 279.636728 -226.643184)
					(mid 280.185368 -226.094544)
					(end 279.636728 -225.545904)
				)
				(arc
					(start 278.23668 -225.545904)
					(mid 277.68804 -226.094544)
					(end 278.23668 -226.643184)
				)
			)
		)
		(polygon
			(pts
				(arc
					(start 280.636726 -224.843086)
					(mid 281.185366 -224.294446)
					(end 280.636726 -223.745806)
				)
				(arc
					(start 279.236678 -223.745806)
					(mid 278.688038 -224.294446)
					(end 279.236678 -224.843086)
				)
			)
		)
		(polygon
			(pts
				(arc
					(start 287.83661 -224.906586)
					(mid 288.44875 -224.294446)
					(end 287.83661 -223.682306)
				)
				(arc
					(start 286.436562 -223.682306)
					(mid 285.824422 -224.294446)
					(end 286.436562 -224.906586)
				)
			)
		)
		(polygon
			(pts
				(arc
					(start 286.836612 -223.042988)
					(mid 287.385252 -222.494348)
					(end 286.836612 -221.945708)
				)
				(arc
					(start 285.436564 -221.945708)
					(mid 284.887924 -222.494348)
					(end 285.436564 -223.042988)
				)
			)
		)
		(polygon
			(pts
				(arc
					(start 279.636728 -223.042988)
					(mid 280.185368 -222.494348)
					(end 279.636728 -221.945708)
				)
				(arc
					(start 278.23668 -221.945708)
					(mid 277.68804 -222.494348)
					(end 278.23668 -223.042988)
				)
			)
		)
		(polygon
			(pts
				(arc
					(start 287.83661 -221.243144)
					(mid 288.38525 -220.694504)
					(end 287.83661 -220.145864)
				)
				(arc
					(start 286.436562 -220.145864)
					(mid 285.887922 -220.694504)
					(end 286.436562 -221.243144)
				)
			)
		)
		(polygon
			(pts
				(arc
					(start 280.636726 -221.243144)
					(mid 281.185366 -220.694504)
					(end 280.636726 -220.145864)
				)
				(arc
					(start 279.236678 -220.145864)
					(mid 278.688038 -220.694504)
					(end 279.236678 -221.243144)
				)
			)
		)
		(polygon
			(pts
				(arc
					(start 286.836612 -219.443046)
					(mid 287.385252 -218.894406)
					(end 286.836612 -218.345766)
				)
				(arc
					(start 285.436564 -218.345766)
					(mid 284.887924 -218.894406)
					(end 285.436564 -219.443046)
				)
			)
		)
		(polygon
			(pts
				(arc
					(start 279.636728 -219.443046)
					(mid 280.185368 -218.894406)
					(end 279.636728 -218.345766)
				)
				(arc
					(start 278.23668 -218.345766)
					(mid 277.68804 -218.894406)
					(end 278.23668 -219.443046)
				)
			)
		)
		(polygon
			(pts
				(arc
					(start 287.83661 -217.643202)
					(mid 288.38525 -217.094562)
					(end 287.83661 -216.545922)
				)
				(arc
					(start 286.436562 -216.545922)
					(mid 285.887922 -217.094562)
					(end 286.436562 -217.643202)
				)
			)
		)
		(polygon
			(pts
				(arc
					(start 280.636726 -217.643202)
					(mid 281.185366 -217.094562)
					(end 280.636726 -216.545922)
				)
				(arc
					(start 279.236678 -216.545922)
					(mid 278.688038 -217.094562)
					(end 279.236678 -217.643202)
				)
			)
		)
		(polygon
			(pts
				(arc
					(start 286.836612 -215.843104)
					(mid 287.385252 -215.294464)
					(end 286.836612 -214.745824)
				)
				(arc
					(start 285.436564 -214.745824)
					(mid 284.887924 -215.294464)
					(end 285.436564 -215.843104)
				)
			)
		)
		(polygon
			(pts
				(arc
					(start 279.636728 -215.843104)
					(mid 280.185368 -215.294464)
					(end 279.636728 -214.745824)
				)
				(arc
					(start 278.23668 -214.745824)
					(mid 277.68804 -215.294464)
					(end 278.23668 -215.843104)
				)
			)
		)
		(polygon
			(pts
				(arc
					(start 287.83661 -214.043006)
					(mid 288.38525 -213.494366)
					(end 287.83661 -212.945726)
				)
				(arc
					(start 286.436562 -212.945726)
					(mid 285.887922 -213.494366)
					(end 286.436562 -214.043006)
				)
			)
		)
		(polygon
			(pts
				(arc
					(start 280.636726 -214.043006)
					(mid 281.185366 -213.494366)
					(end 280.636726 -212.945726)
				)
				(arc
					(start 279.236678 -212.945726)
					(mid 278.688038 -213.494366)
					(end 279.236678 -214.043006)
				)
			)
		)
		(polygon
			(pts
				(arc
					(start 286.836612 -212.243162)
					(mid 287.385252 -211.694522)
					(end 286.836612 -211.145882)
				)
				(arc
					(start 285.436564 -211.145882)
					(mid 284.887924 -211.694522)
					(end 285.436564 -212.243162)
				)
			)
		)
		(polygon
			(pts
				(arc
					(start 279.636728 -212.243162)
					(mid 280.185368 -211.694522)
					(end 279.636728 -211.145882)
				)
				(arc
					(start 278.23668 -211.145882)
					(mid 277.68804 -211.694522)
					(end 278.23668 -212.243162)
				)
			)
		)
		(polygon
			(pts
				(arc
					(start 287.83661 -210.443064)
					(mid 288.38525 -209.894424)
					(end 287.83661 -209.345784)
				)
				(arc
					(start 286.436562 -209.345784)
					(mid 285.887922 -209.894424)
					(end 286.436562 -210.443064)
				)
			)
		)
		(polygon
			(pts
				(arc
					(start 280.636726 -210.443064)
					(mid 281.185366 -209.894424)
					(end 280.636726 -209.345784)
				)
				(arc
					(start 279.236678 -209.345784)
					(mid 278.688038 -209.894424)
					(end 279.236678 -210.443064)
				)
			)
		)
		(polygon
			(pts
				(arc
					(start 286.836612 -208.64322)
					(mid 287.385252 -208.09458)
					(end 286.836612 -207.54594)
				)
				(arc
					(start 285.436564 -207.54594)
					(mid 284.887924 -208.09458)
					(end 285.436564 -208.64322)
				)
			)
		)
		(polygon
			(pts
				(arc
					(start 279.636728 -208.64322)
					(mid 280.185368 -208.09458)
					(end 279.636728 -207.54594)
				)
				(arc
					(start 278.23668 -207.54594)
					(mid 277.68804 -208.09458)
					(end 278.23668 -208.64322)
				)
			)
		)
		(polygon
			(pts
				(arc
					(start 287.83661 -206.843122)
					(mid 288.38525 -206.294482)
					(end 287.83661 -205.745842)
				)
				(arc
					(start 286.436562 -205.745842)
					(mid 285.887922 -206.294482)
					(end 286.436562 -206.843122)
				)
			)
		)
		(polygon
			(pts
				(arc
					(start 280.636726 -206.843122)
					(mid 281.185366 -206.294482)
					(end 280.636726 -205.745842)
				)
				(arc
					(start 279.236678 -205.745842)
					(mid 278.688038 -206.294482)
					(end 279.236678 -206.843122)
				)
			)
		)
		(polygon
			(pts
				(arc
					(start 286.836612 -205.043024)
					(mid 287.385252 -204.494384)
					(end 286.836612 -203.945744)
				)
				(arc
					(start 285.436564 -203.945744)
					(mid 284.887924 -204.494384)
					(end 285.436564 -205.043024)
				)
			)
		)
		(polygon
			(pts
				(arc
					(start 279.636728 -205.043024)
					(mid 280.185368 -204.494384)
					(end 279.636728 -203.945744)
				)
				(arc
					(start 278.23668 -203.945744)
					(mid 277.68804 -204.494384)
					(end 278.23668 -205.043024)
				)
			)
		)
		(polygon
			(pts
				(arc
					(start 287.83661 -203.24318)
					(mid 288.38525 -202.69454)
					(end 287.83661 -202.1459)
				)
				(arc
					(start 286.436562 -202.1459)
					(mid 285.887922 -202.69454)
					(end 286.436562 -203.24318)
				)
			)
		)
		(polygon
			(pts
				(arc
					(start 280.636726 -203.24318)
					(mid 281.185366 -202.69454)
					(end 280.636726 -202.1459)
				)
				(arc
					(start 279.236678 -202.1459)
					(mid 278.688038 -202.69454)
					(end 279.236678 -203.24318)
				)
			)
		)
		(polygon
			(pts
				(arc
					(start 286.836612 -201.443082)
					(mid 287.385252 -200.894442)
					(end 286.836612 -200.345802)
				)
				(arc
					(start 285.436564 -200.345802)
					(mid 284.887924 -200.894442)
					(end 285.436564 -201.443082)
				)
			)
		)
		(polygon
			(pts
				(arc
					(start 279.636728 -201.443082)
					(mid 280.185368 -200.894442)
					(end 279.636728 -200.345802)
				)
				(arc
					(start 278.23668 -200.345802)
					(mid 277.68804 -200.894442)
					(end 278.23668 -201.443082)
				)
			)
		)
		(polygon
			(pts
				(arc
					(start 287.83661 -199.642984)
					(mid 288.38525 -199.094344)
					(end 287.83661 -198.545704)
				)
				(arc
					(start 286.436562 -198.545704)
					(mid 285.887922 -199.094344)
					(end 286.436562 -199.642984)
				)
			)
		)
		(polygon
			(pts
				(arc
					(start 280.636726 -199.642984)
					(mid 281.185366 -199.094344)
					(end 280.636726 -198.545704)
				)
				(arc
					(start 279.236678 -198.545704)
					(mid 278.688038 -199.094344)
					(end 279.236678 -199.642984)
				)
			)
		)
		(polygon
			(pts
				(arc
					(start 286.836612 -197.84314)
					(mid 287.385252 -197.2945)
					(end 286.836612 -196.74586)
				)
				(arc
					(start 285.436564 -196.74586)
					(mid 284.887924 -197.2945)
					(end 285.436564 -197.84314)
				)
			)
		)
		(polygon
			(pts
				(arc
					(start 279.636728 -197.84314)
					(mid 280.185368 -197.2945)
					(end 279.636728 -196.74586)
				)
				(arc
					(start 278.23668 -196.74586)
					(mid 277.68804 -197.2945)
					(end 278.23668 -197.84314)
				)
			)
		)
		(polygon
			(pts
				(arc
					(start 287.83661 -196.043042)
					(mid 288.38525 -195.494402)
					(end 287.83661 -194.945762)
				)
				(arc
					(start 286.436562 -194.945762)
					(mid 285.887922 -195.494402)
					(end 286.436562 -196.043042)
				)
			)
		)
		(polygon
			(pts
				(arc
					(start 280.636726 -196.043042)
					(mid 281.185366 -195.494402)
					(end 280.636726 -194.945762)
				)
				(arc
					(start 279.236678 -194.945762)
					(mid 278.688038 -195.494402)
					(end 279.236678 -196.043042)
				)
			)
		)
		(polygon
			(pts
				(arc
					(start 286.836612 -194.243198)
					(mid 287.385252 -193.694558)
					(end 286.836612 -193.145918)
				)
				(arc
					(start 285.436564 -193.145918)
					(mid 284.887924 -193.694558)
					(end 285.436564 -194.243198)
				)
			)
		)
		(polygon
			(pts
				(arc
					(start 279.636728 -194.243198)
					(mid 280.185368 -193.694558)
					(end 279.636728 -193.145918)
				)
				(arc
					(start 278.23668 -193.145918)
					(mid 277.68804 -193.694558)
					(end 278.23668 -194.243198)
				)
			)
		)
		(polygon
			(pts
				(arc
					(start 287.83661 -192.4431)
					(mid 288.38525 -191.89446)
					(end 287.83661 -191.34582)
				)
				(arc
					(start 286.436562 -191.34582)
					(mid 285.887922 -191.89446)
					(end 286.436562 -192.4431)
				)
			)
		)
		(polygon
			(pts
				(arc
					(start 280.636726 -192.4431)
					(mid 281.185366 -191.89446)
					(end 280.636726 -191.34582)
				)
				(arc
					(start 279.236678 -191.34582)
					(mid 278.688038 -191.89446)
					(end 279.236678 -192.4431)
				)
			)
		)
		(polygon
			(pts
				(arc
					(start 286.836612 -190.643002)
					(mid 287.385252 -190.094362)
					(end 286.836612 -189.545722)
				)
				(arc
					(start 285.436564 -189.545722)
					(mid 284.887924 -190.094362)
					(end 285.436564 -190.643002)
				)
			)
		)
		(polygon
			(pts
				(arc
					(start 279.636728 -190.643002)
					(mid 280.185368 -190.094362)
					(end 279.636728 -189.545722)
				)
				(arc
					(start 278.23668 -189.545722)
					(mid 277.68804 -190.094362)
					(end 278.23668 -190.643002)
				)
			)
		)
		(polygon
			(pts
				(arc
					(start 287.83661 -188.843158)
					(mid 288.38525 -188.294518)
					(end 287.83661 -187.745878)
				)
				(arc
					(start 286.436562 -187.745878)
					(mid 285.887922 -188.294518)
					(end 286.436562 -188.843158)
				)
			)
		)
		(polygon
			(pts
				(arc
					(start 280.636726 -188.843158)
					(mid 281.185366 -188.294518)
					(end 280.636726 -187.745878)
				)
				(arc
					(start 279.236678 -187.745878)
					(mid 278.688038 -188.294518)
					(end 279.236678 -188.843158)
				)
			)
		)
		(polygon
			(pts
				(arc
					(start 286.836612 -187.04306)
					(mid 287.385252 -186.49442)
					(end 286.836612 -185.94578)
				)
				(arc
					(start 285.436564 -185.94578)
					(mid 284.887924 -186.49442)
					(end 285.436564 -187.04306)
				)
			)
		)
		(polygon
			(pts
				(arc
					(start 279.636728 -187.04306)
					(mid 280.185368 -186.49442)
					(end 279.636728 -185.94578)
				)
				(arc
					(start 278.23668 -185.94578)
					(mid 277.68804 -186.49442)
					(end 278.23668 -187.04306)
				)
			)
		)
		(polygon
			(pts
				(arc
					(start 287.83661 -185.243216)
					(mid 288.38525 -184.694576)
					(end 287.83661 -184.145936)
				)
				(arc
					(start 286.436562 -184.145936)
					(mid 285.887922 -184.694576)
					(end 286.436562 -185.243216)
				)
			)
		)
		(polygon
			(pts
				(arc
					(start 280.636726 -185.243216)
					(mid 281.185366 -184.694576)
					(end 280.636726 -184.145936)
				)
				(arc
					(start 279.236678 -184.145936)
					(mid 278.688038 -184.694576)
					(end 279.236678 -185.243216)
				)
			)
		)
		(polygon
			(pts
				(arc
					(start 286.836612 -183.443118)
					(mid 287.385252 -182.894478)
					(end 286.836612 -182.345838)
				)
				(arc
					(start 285.436564 -182.345838)
					(mid 284.887924 -182.894478)
					(end 285.436564 -183.443118)
				)
			)
		)
		(polygon
			(pts
				(arc
					(start 279.636728 -183.443118)
					(mid 280.185368 -182.894478)
					(end 279.636728 -182.345838)
				)
				(arc
					(start 278.23668 -182.345838)
					(mid 277.68804 -182.894478)
					(end 278.23668 -183.443118)
				)
			)
		)
		(polygon
			(pts
				(arc
					(start 287.83661 -181.64302)
					(mid 288.38525 -181.09438)
					(end 287.83661 -180.54574)
				)
				(arc
					(start 286.436562 -180.54574)
					(mid 285.887922 -181.09438)
					(end 286.436562 -181.64302)
				)
			)
		)
		(polygon
			(pts
				(arc
					(start 280.636726 -181.64302)
					(mid 281.185366 -181.09438)
					(end 280.636726 -180.54574)
				)
				(arc
					(start 279.236678 -180.54574)
					(mid 278.688038 -181.09438)
					(end 279.236678 -181.64302)
				)
			)
		)
		(polygon
			(pts
				(arc
					(start 286.836612 -179.843176)
					(mid 287.385252 -179.294536)
					(end 286.836612 -178.745896)
				)
				(arc
					(start 285.436564 -178.745896)
					(mid 284.887924 -179.294536)
					(end 285.436564 -179.843176)
				)
			)
		)
		(polygon
			(pts
				(arc
					(start 279.636728 -179.843176)
					(mid 280.185368 -179.294536)
					(end 279.636728 -178.745896)
				)
				(arc
					(start 278.23668 -178.745896)
					(mid 277.68804 -179.294536)
					(end 278.23668 -179.843176)
				)
			)
		)
		(polygon
			(pts
				(arc
					(start 287.83661 -178.043078)
					(mid 288.38525 -177.494438)
					(end 287.83661 -176.945798)
				)
				(arc
					(start 286.436562 -176.945798)
					(mid 285.887922 -177.494438)
					(end 286.436562 -178.043078)
				)
			)
		)
		(polygon
			(pts
				(arc
					(start 280.636726 -178.043078)
					(mid 281.185366 -177.494438)
					(end 280.636726 -176.945798)
				)
				(arc
					(start 279.236678 -176.945798)
					(mid 278.688038 -177.494438)
					(end 279.236678 -178.043078)
				)
			)
		)
		(polygon
			(pts
				(arc
					(start 286.836612 -176.243234)
					(mid 287.385252 -175.694594)
					(end 286.836612 -175.145954)
				)
				(arc
					(start 285.436564 -175.145954)
					(mid 284.887924 -175.694594)
					(end 285.436564 -176.243234)
				)
			)
		)
		(polygon
			(pts
				(arc
					(start 279.636728 -176.243234)
					(mid 280.185368 -175.694594)
					(end 279.636728 -175.145954)
				)
				(arc
					(start 278.23668 -175.145954)
					(mid 277.68804 -175.694594)
					(end 278.23668 -176.243234)
				)
			)
		)
		(polygon
			(pts
				(arc
					(start 287.83661 -145.243042)
					(mid 288.38525 -144.694402)
					(end 287.83661 -144.145762)
				)
				(arc
					(start 286.436562 -144.145762)
					(mid 285.887922 -144.694402)
					(end 286.436562 -145.243042)
				)
			)
		)
		(polygon
			(pts
				(arc
					(start 284.236668 -145.243042)
					(mid 284.785308 -144.694402)
					(end 284.236668 -144.145762)
				)
				(arc
					(start 282.83662 -144.145762)
					(mid 282.28798 -144.694402)
					(end 282.83662 -145.243042)
				)
			)
		)
		(polygon
			(pts
				(arc
					(start 280.636726 -145.243042)
					(mid 281.185366 -144.694402)
					(end 280.636726 -144.145762)
				)
				(arc
					(start 279.236678 -144.145762)
					(mid 278.688038 -144.694402)
					(end 279.236678 -145.243042)
				)
			)
		)
		(polygon
			(pts
				(arc
					(start 286.836612 -143.442944)
					(mid 287.385252 -142.894304)
					(end 286.836612 -142.345664)
				)
				(arc
					(start 285.436564 -142.345664)
					(mid 284.887924 -142.894304)
					(end 285.436564 -143.442944)
				)
			)
		)
		(polygon
			(pts
				(arc
					(start 279.636728 -143.442944)
					(mid 280.185368 -142.894304)
					(end 279.636728 -142.345664)
				)
				(arc
					(start 278.23668 -142.345664)
					(mid 277.68804 -142.894304)
					(end 278.23668 -143.442944)
				)
			)
		)
		(polygon
			(pts
				(arc
					(start 287.83661 -141.6431)
					(mid 288.38525 -141.09446)
					(end 287.83661 -140.54582)
				)
				(arc
					(start 286.436562 -140.54582)
					(mid 285.887922 -141.09446)
					(end 286.436562 -141.6431)
				)
			)
		)
		(polygon
			(pts
				(arc
					(start 280.636726 -141.6431)
					(mid 281.185366 -141.09446)
					(end 280.636726 -140.54582)
				)
				(arc
					(start 279.236678 -140.54582)
					(mid 278.688038 -141.09446)
					(end 279.236678 -141.6431)
				)
			)
		)
		(polygon
			(pts
				(arc
					(start 286.836612 -139.843002)
					(mid 287.385252 -139.294362)
					(end 286.836612 -138.745722)
				)
				(arc
					(start 285.436564 -138.745722)
					(mid 284.887924 -139.294362)
					(end 285.436564 -139.843002)
				)
			)
		)
		(polygon
			(pts
				(arc
					(start 279.636728 -139.843002)
					(mid 280.185368 -139.294362)
					(end 279.636728 -138.745722)
				)
				(arc
					(start 278.23668 -138.745722)
					(mid 277.68804 -139.294362)
					(end 278.23668 -139.843002)
				)
			)
		)
		(polygon
			(pts
				(arc
					(start 287.83661 -138.043158)
					(mid 288.38525 -137.494518)
					(end 287.83661 -136.945878)
				)
				(arc
					(start 286.436562 -136.945878)
					(mid 285.887922 -137.494518)
					(end 286.436562 -138.043158)
				)
			)
		)
		(polygon
			(pts
				(arc
					(start 280.636726 -138.045698)
					(mid 281.187906 -137.494518)
					(end 280.636726 -136.943338)
				)
				(arc
					(start 279.236678 -136.943338)
					(mid 278.685498 -137.494518)
					(end 279.236678 -138.045698)
				)
			)
		)
		(polygon
			(pts
				(arc
					(start 286.836612 -136.24306)
					(mid 287.385252 -135.69442)
					(end 286.836612 -135.14578)
				)
				(arc
					(start 285.436564 -135.14578)
					(mid 284.887924 -135.69442)
					(end 285.436564 -136.24306)
				)
			)
		)
		(polygon
			(pts
				(arc
					(start 279.636728 -136.24306)
					(mid 280.185368 -135.69442)
					(end 279.636728 -135.14578)
				)
				(arc
					(start 278.23668 -135.14578)
					(mid 277.68804 -135.69442)
					(end 278.23668 -136.24306)
				)
			)
		)
		(polygon
			(pts
				(arc
					(start 287.83661 -134.442962)
					(mid 288.38525 -133.894322)
					(end 287.83661 -133.345682)
				)
				(arc
					(start 286.436562 -133.345682)
					(mid 285.887922 -133.894322)
					(end 286.436562 -134.442962)
				)
			)
		)
		(polygon
			(pts
				(arc
					(start 280.636726 -134.442962)
					(mid 281.185366 -133.894322)
					(end 280.636726 -133.345682)
				)
				(arc
					(start 279.236678 -133.345682)
					(mid 278.688038 -133.894322)
					(end 279.236678 -134.442962)
				)
			)
		)
		(polygon
			(pts
				(arc
					(start 159.193992 -133.11505)
					(mid 158.708852 -132.62991)
					(end 158.223712 -133.11505)
				)
				(arc
					(start 158.223712 -134.385304)
					(mid 158.708979 -134.87019)
					(end 159.193992 -134.38505)
				)
			)
		)
		(polygon
			(pts
				(arc
					(start 127.64389 -133.11505)
					(mid 127.15875 -132.62991)
					(end 126.67361 -133.11505)
				)
				(arc
					(start 126.67361 -134.385304)
					(mid 127.158877 -134.87019)
					(end 127.64389 -134.38505)
				)
			)
		)
		(polygon
			(pts
				(arc
					(start 96.094042 -133.11505)
					(mid 95.608902 -132.62991)
					(end 95.123762 -133.11505)
				)
				(arc
					(start 95.123762 -134.385304)
					(mid 95.609029 -134.87019)
					(end 96.094042 -134.38505)
				)
			)
		)
		(polygon
			(pts
				(arc
					(start 64.54394 -133.11505)
					(mid 64.0588 -132.62991)
					(end 63.57366 -133.11505)
				)
				(arc
					(start 63.57366 -134.385304)
					(mid 64.058927 -134.87019)
					(end 64.54394 -134.38505)
				)
			)
		)
		(polygon
			(pts
				(arc
					(start 32.994092 -133.11505)
					(mid 32.508952 -132.62991)
					(end 32.023812 -133.11505)
				)
				(arc
					(start 32.023812 -134.385304)
					(mid 32.509079 -134.87019)
					(end 32.994092 -134.38505)
				)
			)
		)
		(polygon
			(pts
				(arc
					(start 190.744094 -133.114796)
					(mid 190.258827 -132.62991)
					(end 189.773814 -133.11505)
				)
				(arc
					(start 189.773814 -134.38505)
					(mid 190.258954 -134.87019)
					(end 190.744094 -134.38505)
				)
			)
		)
		(polygon
			(pts
				(arc
					(start 481.701602 -132.922264)
					(mid 482.186742 -132.437124)
					(end 481.701602 -131.951984)
				)
				(arc
					(start 480.431348 -131.951984)
					(mid 479.946462 -132.437251)
					(end 480.431602 -132.922264)
				)
			)
		)
		(polygon
			(pts
				(arc
					(start 450.151754 -132.922264)
					(mid 450.63664 -132.436997)
					(end 450.1515 -131.951984)
				)
				(arc
					(start 448.8815 -131.951984)
					(mid 448.39636 -132.437124)
					(end 448.8815 -132.922264)
				)
			)
		)
		(polygon
			(pts
				(arc
					(start 418.601652 -132.922264)
					(mid 419.086792 -132.437124)
					(end 418.601652 -131.951984)
				)
				(arc
					(start 417.331398 -131.951984)
					(mid 416.846512 -132.437251)
					(end 417.331652 -132.922264)
				)
			)
		)
		(polygon
			(pts
				(arc
					(start 387.051804 -132.922264)
					(mid 387.53669 -132.436997)
					(end 387.05155 -131.951984)
				)
				(arc
					(start 385.78155 -131.951984)
					(mid 385.29641 -132.437124)
					(end 385.78155 -132.922264)
				)
			)
		)
		(polygon
			(pts
				(arc
					(start 355.501702 -132.922264)
					(mid 355.986842 -132.437124)
					(end 355.501702 -131.951984)
				)
				(arc
					(start 354.231448 -131.951984)
					(mid 353.746562 -132.437251)
					(end 354.231702 -132.922264)
				)
			)
		)
		(polygon
			(pts
				(arc
					(start 323.951854 -132.922264)
					(mid 324.43674 -132.436997)
					(end 323.9516 -131.951984)
				)
				(arc
					(start 322.6816 -131.951984)
					(mid 322.19646 -132.437124)
					(end 322.6816 -132.922264)
				)
			)
		)
		(polygon
			(pts
				(arc
					(start 286.836612 -132.643118)
					(mid 287.385252 -132.094478)
					(end 286.836612 -131.545838)
				)
				(arc
					(start 285.436564 -131.545838)
					(mid 284.887924 -132.094478)
					(end 285.436564 -132.643118)
				)
			)
		)
		(polygon
			(pts
				(arc
					(start 279.636728 -132.643118)
					(mid 280.185368 -132.094478)
					(end 279.636728 -131.545838)
				)
				(arc
					(start 278.23668 -131.545838)
					(mid 277.68804 -132.094478)
					(end 278.23668 -132.643118)
				)
			)
		)
		(polygon
			(pts
				(arc
					(start 192.520824 -129.419096)
					(mid 192.035557 -128.93421)
					(end 191.550544 -129.41935)
				)
				(arc
					(start 191.550544 -130.56235)
					(mid 192.035684 -131.04749)
					(end 192.520824 -130.56235)
				)
			)
		)
		(polygon
			(pts
				(arc
					(start 160.970722 -129.419096)
					(mid 160.485455 -128.93421)
					(end 160.000442 -129.41935)
				)
				(arc
					(start 160.000442 -130.56235)
					(mid 160.485582 -131.04749)
					(end 160.970722 -130.56235)
				)
			)
		)
		(polygon
			(pts
				(arc
					(start 129.42062 -129.419096)
					(mid 128.935353 -128.93421)
					(end 128.45034 -129.41935)
				)
				(arc
					(start 128.45034 -130.56235)
					(mid 128.93548 -131.04749)
					(end 129.42062 -130.56235)
				)
			)
		)
		(polygon
			(pts
				(arc
					(start 97.870772 -129.419096)
					(mid 97.385505 -128.93421)
					(end 96.900492 -129.41935)
				)
				(arc
					(start 96.900492 -130.56235)
					(mid 97.385632 -131.04749)
					(end 97.870772 -130.56235)
				)
			)
		)
		(polygon
			(pts
				(arc
					(start 66.32067 -129.419096)
					(mid 65.835403 -128.93421)
					(end 65.35039 -129.41935)
				)
				(arc
					(start 65.35039 -130.56235)
					(mid 65.83553 -131.04749)
					(end 66.32067 -130.56235)
				)
			)
		)
		(polygon
			(pts
				(arc
					(start 34.770822 -129.419096)
					(mid 34.285555 -128.93421)
					(end 33.800542 -129.41935)
				)
				(arc
					(start 33.800542 -130.56235)
					(mid 34.285682 -131.04749)
					(end 34.770822 -130.56235)
				)
			)
		)
		(polygon
			(pts
				(arc
					(start 478.107502 -129.112264)
					(mid 478.592642 -128.627124)
					(end 478.107502 -128.141984)
				)
				(arc
					(start 476.964248 -128.141984)
					(mid 476.479362 -128.627251)
					(end 476.964502 -129.112264)
				)
			)
		)
		(polygon
			(pts
				(arc
					(start 446.5574 -129.112264)
					(mid 447.04254 -128.627124)
					(end 446.5574 -128.141984)
				)
				(arc
					(start 445.414146 -128.141984)
					(mid 444.92926 -128.627251)
					(end 445.4144 -129.112264)
				)
			)
		)
		(polygon
			(pts
				(arc
					(start 415.007552 -129.112264)
					(mid 415.492692 -128.627124)
					(end 415.007552 -128.141984)
				)
				(arc
					(start 413.864298 -128.141984)
					(mid 413.379412 -128.627251)
					(end 413.864552 -129.112264)
				)
			)
		)
		(polygon
			(pts
				(arc
					(start 383.45745 -129.112264)
					(mid 383.94259 -128.627124)
					(end 383.45745 -128.141984)
				)
				(arc
					(start 382.314196 -128.141984)
					(mid 381.82931 -128.627251)
					(end 382.31445 -129.112264)
				)
			)
		)
		(polygon
			(pts
				(arc
					(start 351.907602 -129.112264)
					(mid 352.392742 -128.627124)
					(end 351.907602 -128.141984)
				)
				(arc
					(start 350.764348 -128.141984)
					(mid 350.279462 -128.627251)
					(end 350.764602 -129.112264)
				)
			)
		)
		(polygon
			(pts
				(arc
					(start 320.3575 -129.112264)
					(mid 320.84264 -128.627124)
					(end 320.3575 -128.141984)
				)
				(arc
					(start 319.214246 -128.141984)
					(mid 318.72936 -128.627251)
					(end 319.2145 -129.112264)
				)
			)
		)
		(polygon
			(pts
				(arc
					(start 221.348808 -77.599794)
					(mid 220.800041 -77.051408)
					(end 220.251528 -77.600048)
				)
				(arc
					(start 220.251528 -78.999842)
					(mid 220.800168 -79.548482)
					(end 221.348808 -78.999842)
				)
			)
		)
		(polygon
			(pts
				(arc
					(start 217.748612 -77.599794)
					(mid 217.199845 -77.051408)
					(end 216.651332 -77.600048)
				)
				(arc
					(start 216.651332 -78.999842)
					(mid 217.199972 -79.548482)
					(end 217.748612 -78.999842)
				)
			)
		)
		(polygon
			(pts
				(arc
					(start 214.14867 -77.599794)
					(mid 213.599903 -77.051408)
					(end 213.05139 -77.600048)
				)
				(arc
					(start 213.05139 -78.999842)
					(mid 213.60003 -79.548482)
					(end 214.14867 -78.999842)
				)
			)
		)
		(polygon
			(pts
				(arc
					(start 210.548728 -77.599794)
					(mid 209.999961 -77.051408)
					(end 209.451448 -77.600048)
				)
				(arc
					(start 209.451448 -78.999842)
					(mid 210.000088 -79.548482)
					(end 210.548728 -78.999842)
				)
			)
		)
		(polygon
			(pts
				(arc
					(start 223.148652 -76.399898)
					(mid 222.600012 -75.851258)
					(end 222.051372 -76.399898)
				)
				(arc
					(start 222.051372 -77.8002)
					(mid 222.600139 -78.348586)
					(end 223.148652 -77.799946)
				)
			)
		)
		(polygon
			(pts
				(arc
					(start 219.54871 -76.399898)
					(mid 219.00007 -75.851258)
					(end 218.45143 -76.399898)
				)
				(arc
					(start 218.45143 -77.8002)
					(mid 219.000197 -78.348586)
					(end 219.54871 -77.799946)
				)
			)
		)
		(polygon
			(pts
				(arc
					(start 215.948768 -76.399898)
					(mid 215.400128 -75.851258)
					(end 214.851488 -76.399898)
				)
				(arc
					(start 214.851488 -77.8002)
					(mid 215.400255 -78.348586)
					(end 215.948768 -77.799946)
				)
			)
		)
		(polygon
			(pts
				(arc
					(start 212.348826 -76.399898)
					(mid 211.800186 -75.851258)
					(end 211.251546 -76.399898)
				)
				(arc
					(start 211.251546 -77.8002)
					(mid 211.800313 -78.348586)
					(end 212.348826 -77.799946)
				)
			)
		)
		(polygon
			(pts
				(arc
					(start 210.548728 -73.999852)
					(mid 210.000088 -73.451212)
					(end 209.451448 -73.999852)
				)
				(arc
					(start 209.451448 -75.400154)
					(mid 210.000215 -75.94854)
					(end 210.548728 -75.3999)
				)
			)
		)
		(polygon
			(pts
				(arc
					(start 221.348808 -70.39991)
					(mid 220.800168 -69.85127)
					(end 220.251528 -70.39991)
				)
				(arc
					(start 220.251528 -71.800212)
					(mid 220.800295 -72.348598)
					(end 221.348808 -71.799958)
				)
			)
		)
		(polygon
			(pts
				(arc
					(start 217.748612 -70.39991)
					(mid 217.199972 -69.85127)
					(end 216.651332 -70.39991)
				)
				(arc
					(start 216.651332 -71.800212)
					(mid 217.200099 -72.348598)
					(end 217.748612 -71.799958)
				)
			)
		)
		(polygon
			(pts
				(arc
					(start 214.14867 -70.39991)
					(mid 213.60003 -69.85127)
					(end 213.05139 -70.39991)
				)
				(arc
					(start 213.05139 -71.800212)
					(mid 213.600157 -72.348598)
					(end 214.14867 -71.799958)
				)
			)
		)
		(polygon
			(pts
				(arc
					(start 210.548728 -70.39991)
					(mid 210.000088 -69.85127)
					(end 209.451448 -70.39991)
				)
				(arc
					(start 209.451448 -71.800212)
					(mid 210.000215 -72.348598)
					(end 210.548728 -71.799958)
				)
			)
		)
		(polygon
			(pts
				(arc
					(start 219.54871 -65.600072)
					(mid 219.00007 -65.051432)
					(end 218.45143 -65.600072)
				)
				(arc
					(start 218.45143 -67.00012)
					(mid 219.000197 -67.548506)
					(end 219.54871 -66.999866)
				)
			)
		)
		(polygon
			(pts
				(arc
					(start 215.948768 -65.600072)
					(mid 215.400128 -65.051432)
					(end 214.851488 -65.600072)
				)
				(arc
					(start 214.851488 -67.00012)
					(mid 215.400255 -67.548506)
					(end 215.948768 -66.999866)
				)
			)
		)
		(polygon
			(pts
				(arc
					(start 212.348826 -65.600072)
					(mid 211.800186 -65.051432)
					(end 211.251546 -65.600072)
				)
				(arc
					(start 211.251546 -67.00012)
					(mid 211.800313 -67.548506)
					(end 212.348826 -66.999866)
				)
			)
		)
		(polygon
			(pts
				(arc
					(start 223.148652 -65.599818)
					(mid 222.599885 -65.051432)
					(end 222.051372 -65.600072)
				)
				(arc
					(start 222.051372 -66.999866)
					(mid 222.600012 -67.548506)
					(end 223.148652 -66.999866)
				)
			)
		)
		(polygon
			(pts
				(arc
					(start 190.744094 -18.114772)
					(mid 190.258827 -17.629886)
					(end 189.773814 -18.115026)
				)
				(arc
					(start 189.773814 -19.385026)
					(mid 190.258954 -19.870166)
					(end 190.744094 -19.385026)
				)
			)
		)
		(polygon
			(pts
				(arc
					(start 159.193992 -18.114772)
					(mid 158.708725 -17.629886)
					(end 158.223712 -18.115026)
				)
				(arc
					(start 158.223712 -19.385026)
					(mid 158.708852 -19.870166)
					(end 159.193992 -19.385026)
				)
			)
		)
		(polygon
			(pts
				(arc
					(start 127.64389 -18.114772)
					(mid 127.158623 -17.629886)
					(end 126.67361 -18.115026)
				)
				(arc
					(start 126.67361 -19.385026)
					(mid 127.15875 -19.870166)
					(end 127.64389 -19.385026)
				)
			)
		)
		(polygon
			(pts
				(arc
					(start 96.094042 -18.114772)
					(mid 95.608775 -17.629886)
					(end 95.123762 -18.115026)
				)
				(arc
					(start 95.123762 -19.385026)
					(mid 95.608902 -19.870166)
					(end 96.094042 -19.385026)
				)
			)
		)
		(polygon
			(pts
				(arc
					(start 64.54394 -18.114772)
					(mid 64.058673 -17.629886)
					(end 63.57366 -18.115026)
				)
				(arc
					(start 63.57366 -19.385026)
					(mid 64.0588 -19.870166)
					(end 64.54394 -19.385026)
				)
			)
		)
		(polygon
			(pts
				(arc
					(start 32.994092 -18.114772)
					(mid 32.508825 -17.629886)
					(end 32.023812 -18.115026)
				)
				(arc
					(start 32.023812 -19.385026)
					(mid 32.508952 -19.870166)
					(end 32.994092 -19.385026)
				)
			)
		)
		(polygon
			(pts
				(arc
					(start 481.701602 -17.92224)
					(mid 482.186742 -17.4371)
					(end 481.701602 -16.95196)
				)
				(arc
					(start 480.431348 -16.95196)
					(mid 479.946462 -17.437227)
					(end 480.431602 -17.92224)
				)
			)
		)
		(polygon
			(pts
				(arc
					(start 450.151754 -17.92224)
					(mid 450.63664 -17.436973)
					(end 450.1515 -16.95196)
				)
				(arc
					(start 448.8815 -16.95196)
					(mid 448.39636 -17.4371)
					(end 448.8815 -17.92224)
				)
			)
		)
		(polygon
			(pts
				(arc
					(start 418.601652 -17.92224)
					(mid 419.086792 -17.4371)
					(end 418.601652 -16.95196)
				)
				(arc
					(start 417.331398 -16.95196)
					(mid 416.846512 -17.437227)
					(end 417.331652 -17.92224)
				)
			)
		)
		(polygon
			(pts
				(arc
					(start 387.051804 -17.92224)
					(mid 387.53669 -17.436973)
					(end 387.05155 -16.95196)
				)
				(arc
					(start 385.78155 -16.95196)
					(mid 385.29641 -17.4371)
					(end 385.78155 -17.92224)
				)
			)
		)
		(polygon
			(pts
				(arc
					(start 355.501702 -17.92224)
					(mid 355.986842 -17.4371)
					(end 355.501702 -16.95196)
				)
				(arc
					(start 354.231448 -16.95196)
					(mid 353.746562 -17.437227)
					(end 354.231702 -17.92224)
				)
			)
		)
		(polygon
			(pts
				(arc
					(start 323.951854 -17.92224)
					(mid 324.43674 -17.436973)
					(end 323.9516 -16.95196)
				)
				(arc
					(start 322.6816 -16.95196)
					(mid 322.19646 -17.4371)
					(end 322.6816 -17.92224)
				)
			)
		)
		(polygon
			(pts
				(arc
					(start 192.520824 -14.419072)
					(mid 192.035557 -13.934186)
					(end 191.550544 -14.419326)
				)
				(arc
					(start 191.550544 -15.562326)
					(mid 192.035684 -16.047466)
					(end 192.520824 -15.562326)
				)
			)
		)
		(polygon
			(pts
				(arc
					(start 160.970722 -14.419072)
					(mid 160.485455 -13.934186)
					(end 160.000442 -14.419326)
				)
				(arc
					(start 160.000442 -15.562326)
					(mid 160.485582 -16.047466)
					(end 160.970722 -15.562326)
				)
			)
		)
		(polygon
			(pts
				(arc
					(start 129.42062 -14.419072)
					(mid 128.935353 -13.934186)
					(end 128.45034 -14.419326)
				)
				(arc
					(start 128.45034 -15.562326)
					(mid 128.93548 -16.047466)
					(end 129.42062 -15.562326)
				)
			)
		)
		(polygon
			(pts
				(arc
					(start 97.870772 -14.419072)
					(mid 97.385505 -13.934186)
					(end 96.900492 -14.419326)
				)
				(arc
					(start 96.900492 -15.562326)
					(mid 97.385632 -16.047466)
					(end 97.870772 -15.562326)
				)
			)
		)
		(polygon
			(pts
				(arc
					(start 66.32067 -14.419072)
					(mid 65.835403 -13.934186)
					(end 65.35039 -14.419326)
				)
				(arc
					(start 65.35039 -15.562326)
					(mid 65.83553 -16.047466)
					(end 66.32067 -15.562326)
				)
			)
		)
		(polygon
			(pts
				(arc
					(start 34.770822 -14.419072)
					(mid 34.285555 -13.934186)
					(end 33.800542 -14.419326)
				)
				(arc
					(start 33.800542 -15.562326)
					(mid 34.285682 -16.047466)
					(end 34.770822 -15.562326)
				)
			)
		)
		(polygon
			(pts
				(arc
					(start 478.107502 -14.11224)
					(mid 478.592642 -13.6271)
					(end 478.107502 -13.14196)
				)
				(arc
					(start 476.964248 -13.14196)
					(mid 476.479362 -13.627227)
					(end 476.964502 -14.11224)
				)
			)
		)
		(polygon
			(pts
				(arc
					(start 446.5574 -14.11224)
					(mid 447.04254 -13.6271)
					(end 446.5574 -13.14196)
				)
				(arc
					(start 445.414146 -13.14196)
					(mid 444.92926 -13.627227)
					(end 445.4144 -14.11224)
				)
			)
		)
		(polygon
			(pts
				(arc
					(start 415.007552 -14.11224)
					(mid 415.492692 -13.6271)
					(end 415.007552 -13.14196)
				)
				(arc
					(start 413.864298 -13.14196)
					(mid 413.379412 -13.627227)
					(end 413.864552 -14.11224)
				)
			)
		)
		(polygon
			(pts
				(arc
					(start 383.45745 -14.11224)
					(mid 383.94259 -13.6271)
					(end 383.45745 -13.14196)
				)
				(arc
					(start 382.314196 -13.14196)
					(mid 381.82931 -13.627227)
					(end 382.31445 -14.11224)
				)
			)
		)
		(polygon
			(pts
				(arc
					(start 351.907602 -14.11224)
					(mid 352.392742 -13.6271)
					(end 351.907602 -13.14196)
				)
				(arc
					(start 350.764348 -13.14196)
					(mid 350.279462 -13.627227)
					(end 350.764602 -14.11224)
				)
			)
		)
		(polygon
			(pts
				(arc
					(start 320.3575 -14.11224)
					(mid 320.84264 -13.6271)
					(end 320.3575 -13.14196)
				)
				(arc
					(start 319.214246 -13.14196)
					(mid 318.72936 -13.627227)
					(end 319.2145 -14.11224)
				)
			)
		)
	)
	(zone
		(layer "Cmts.User")
		(hatch none 0.5)
		(connect_pads
			(clearance 0)
		)
		(min_thickness 0.25)
		(keepout
			(tracks allowed)
			(vias allowed)
			(pads allowed)
			(copperpour allowed)
			(footprints allowed)
		)
		(placement
			(enabled no)
			(sheetname "")
		)
		(fill
			(thermal_gap 0.5)
			(thermal_bridge_width 0.5)
			(island_removal_mode 0)
		)
		(polygon
			(pts
				(xy 387.562598 -132.907278) (xy 385.378198 -132.907278) (xy 385.378198 -131.840478) (xy 387.562598 -131.840478)
			)
		)
	)
	(zone
		(layer "Cmts.User")
		(hatch none 0.5)
		(connect_pads
			(clearance 0)
		)
		(min_thickness 0.25)
		(keepout
			(tracks allowed)
			(vias allowed)
			(pads allowed)
			(copperpour allowed)
			(footprints allowed)
		)
		(placement
			(enabled no)
			(sheetname "")
		)
		(fill
			(thermal_gap 0.5)
			(thermal_bridge_width 0.5)
			(island_removal_mode 0)
		)
		(polygon
			(pts
				(xy 447.068448 -14.097254) (xy 444.884048 -14.097254) (xy 444.884048 -13.030454) (xy 447.068448 -13.030454)
			)
		)
	)
	(zone
		(layer "Cmts.User")
		(hatch none 0.5)
		(connect_pads
			(clearance 0)
		)
		(min_thickness 0.25)
		(keepout
			(tracks allowed)
			(vias allowed)
			(pads allowed)
			(copperpour allowed)
			(footprints allowed)
		)
		(placement
			(enabled no)
			(sheetname "")
		)
		(fill
			(thermal_gap 0.5)
			(thermal_bridge_width 0.5)
			(island_removal_mode 0)
		)
		(polygon
			(pts
				(xy 159.7787 -131.027424) (xy 159.7787 -128.843024) (xy 160.8455 -128.843024) (xy 160.8455 -131.027424)
			)
		)
	)
	(zone
		(layer "Cmts.User")
		(hatch none 0.5)
		(connect_pads
			(clearance 0)
		)
		(min_thickness 0.25)
		(keepout
			(tracks allowed)
			(vias allowed)
			(pads allowed)
			(copperpour allowed)
			(footprints allowed)
		)
		(placement
			(enabled no)
			(sheetname "")
		)
		(fill
			(thermal_gap 0.5)
			(thermal_bridge_width 0.5)
			(island_removal_mode 0)
		)
		(polygon
			(pts
				(xy 32.038798 -19.896074) (xy 32.038798 -17.711674) (xy 33.105598 -17.711674) (xy 33.105598 -19.896074)
			)
		)
	)
	(zone
		(layer "Cmts.User")
		(hatch none 0.5)
		(connect_pads
			(clearance 0)
		)
		(min_thickness 0.25)
		(keepout
			(tracks allowed)
			(vias allowed)
			(pads allowed)
			(copperpour allowed)
			(footprints allowed)
		)
		(placement
			(enabled no)
			(sheetname "")
		)
		(fill
			(thermal_gap 0.5)
			(thermal_bridge_width 0.5)
			(island_removal_mode 0)
		)
		(polygon
			(pts
				(xy 191.328802 -16.0274) (xy 191.328802 -13.843) (xy 192.395602 -13.843) (xy 192.395602 -16.0274)
			)
		)
	)
	(zone
		(layer "Cmts.User")
		(hatch none 0.5)
		(connect_pads
			(clearance 0)
		)
		(min_thickness 0.25)
		(keepout
			(tracks allowed)
			(vias allowed)
			(pads allowed)
			(copperpour allowed)
			(footprints allowed)
		)
		(placement
			(enabled no)
			(sheetname "")
		)
		(fill
			(thermal_gap 0.5)
			(thermal_bridge_width 0.5)
			(island_removal_mode 0)
		)
		(polygon
			(pts
				(xy 189.7888 -19.896074) (xy 189.7888 -17.711674) (xy 190.8556 -17.711674) (xy 190.8556 -19.896074)
			)
		)
	)
	(zone
		(layer "Cmts.User")
		(hatch none 0.5)
		(connect_pads
			(clearance 0)
		)
		(min_thickness 0.25)
		(keepout
			(tracks allowed)
			(vias allowed)
			(pads allowed)
			(copperpour allowed)
			(footprints allowed)
		)
		(placement
			(enabled no)
			(sheetname "")
		)
		(fill
			(thermal_gap 0.5)
			(thermal_bridge_width 0.5)
			(island_removal_mode 0)
		)
		(polygon
			(pts
				(xy 128.228598 -16.0274) (xy 128.228598 -13.843) (xy 129.295398 -13.843) (xy 129.295398 -16.0274)
			)
		)
	)
	(zone
		(layer "Cmts.User")
		(hatch none 0.5)
		(connect_pads
			(clearance 0)
		)
		(min_thickness 0.25)
		(keepout
			(tracks allowed)
			(vias allowed)
			(pads allowed)
			(copperpour allowed)
			(footprints allowed)
		)
		(placement
			(enabled no)
			(sheetname "")
		)
		(fill
			(thermal_gap 0.5)
			(thermal_bridge_width 0.5)
			(island_removal_mode 0)
		)
		(polygon
			(pts
				(xy 478.61855 -129.097278) (xy 476.43415 -129.097278) (xy 476.43415 -128.030478) (xy 478.61855 -128.030478)
			)
		)
	)
	(zone
		(layer "Cmts.User")
		(hatch none 0.5)
		(connect_pads
			(clearance 0)
		)
		(min_thickness 0.25)
		(keepout
			(tracks allowed)
			(vias allowed)
			(pads allowed)
			(copperpour allowed)
			(footprints allowed)
		)
		(placement
			(enabled no)
			(sheetname "")
		)
		(fill
			(thermal_gap 0.5)
			(thermal_bridge_width 0.5)
			(island_removal_mode 0)
		)
		(polygon
			(pts
				(xy 159.7787 -16.0274) (xy 159.7787 -13.843) (xy 160.8455 -13.843) (xy 160.8455 -16.0274)
			)
		)
	)
	(zone
		(layer "Cmts.User")
		(hatch none 0.5)
		(connect_pads
			(clearance 0)
		)
		(min_thickness 0.25)
		(keepout
			(tracks allowed)
			(vias allowed)
			(pads allowed)
			(copperpour allowed)
			(footprints allowed)
		)
		(placement
			(enabled no)
			(sheetname "")
		)
		(fill
			(thermal_gap 0.5)
			(thermal_bridge_width 0.5)
			(island_removal_mode 0)
		)
		(polygon
			(pts
				(xy 33.5788 -16.0274) (xy 33.5788 -13.843) (xy 34.6456 -13.843) (xy 34.6456 -16.0274)
			)
		)
	)
	(zone
		(layer "Cmts.User")
		(hatch none 0.5)
		(connect_pads
			(clearance 0)
		)
		(min_thickness 0.25)
		(keepout
			(tracks allowed)
			(vias allowed)
			(pads allowed)
			(copperpour allowed)
			(footprints allowed)
		)
		(placement
			(enabled no)
			(sheetname "")
		)
		(fill
			(thermal_gap 0.5)
			(thermal_bridge_width 0.5)
			(island_removal_mode 0)
		)
		(polygon
			(pts
				(xy 191.328802 -131.027424) (xy 191.328802 -128.843024) (xy 192.395602 -128.843024) (xy 192.395602 -131.027424)
			)
		)
	)
	(zone
		(layer "Cmts.User")
		(hatch none 0.5)
		(connect_pads
			(clearance 0)
		)
		(min_thickness 0.25)
		(keepout
			(tracks allowed)
			(vias allowed)
			(pads allowed)
			(copperpour allowed)
			(footprints allowed)
		)
		(placement
			(enabled no)
			(sheetname "")
		)
		(fill
			(thermal_gap 0.5)
			(thermal_bridge_width 0.5)
			(island_removal_mode 0)
		)
		(polygon
			(pts
				(xy 419.1127 -132.907278) (xy 416.9283 -132.907278) (xy 416.9283 -131.840478) (xy 419.1127 -131.840478)
			)
		)
	)
	(zone
		(layer "Cmts.User")
		(hatch none 0.5)
		(connect_pads
			(clearance 0)
		)
		(min_thickness 0.25)
		(keepout
			(tracks allowed)
			(vias allowed)
			(pads allowed)
			(copperpour allowed)
			(footprints allowed)
		)
		(placement
			(enabled no)
			(sheetname "")
		)
		(fill
			(thermal_gap 0.5)
			(thermal_bridge_width 0.5)
			(island_removal_mode 0)
		)
		(polygon
			(pts
				(xy 63.588646 -134.896098) (xy 63.588646 -132.711698) (xy 64.655446 -132.711698) (xy 64.655446 -134.896098)
			)
		)
	)
	(zone
		(layer "Cmts.User")
		(hatch none 0.5)
		(connect_pads
			(clearance 0)
		)
		(min_thickness 0.25)
		(keepout
			(tracks allowed)
			(vias allowed)
			(pads allowed)
			(copperpour allowed)
			(footprints allowed)
		)
		(placement
			(enabled no)
			(sheetname "")
		)
		(fill
			(thermal_gap 0.5)
			(thermal_bridge_width 0.5)
			(island_removal_mode 0)
		)
		(polygon
			(pts
				(xy 482.21265 -132.907278) (xy 480.02825 -132.907278) (xy 480.02825 -131.840478) (xy 482.21265 -131.840478)
			)
		)
	)
	(zone
		(layer "Cmts.User")
		(hatch none 0.5)
		(connect_pads
			(clearance 0)
		)
		(min_thickness 0.25)
		(keepout
			(tracks allowed)
			(vias allowed)
			(pads allowed)
			(copperpour allowed)
			(footprints allowed)
		)
		(placement
			(enabled no)
			(sheetname "")
		)
		(fill
			(thermal_gap 0.5)
			(thermal_bridge_width 0.5)
			(island_removal_mode 0)
		)
		(polygon
			(pts
				(xy 356.01275 -17.907254) (xy 353.82835 -17.907254) (xy 353.82835 -16.840454) (xy 356.01275 -16.840454)
			)
		)
	)
	(zone
		(layer "Cmts.User")
		(hatch none 0.5)
		(connect_pads
			(clearance 0)
		)
		(min_thickness 0.25)
		(keepout
			(tracks allowed)
			(vias allowed)
			(pads allowed)
			(copperpour allowed)
			(footprints allowed)
		)
		(placement
			(enabled no)
			(sheetname "")
		)
		(fill
			(thermal_gap 0.5)
			(thermal_bridge_width 0.5)
			(island_removal_mode 0)
		)
		(polygon
			(pts
				(xy 352.41865 -129.097278) (xy 350.23425 -129.097278) (xy 350.23425 -128.030478) (xy 352.41865 -128.030478)
			)
		)
	)
	(zone
		(layer "Cmts.User")
		(hatch none 0.5)
		(connect_pads
			(clearance 0)
		)
		(min_thickness 0.25)
		(keepout
			(tracks allowed)
			(vias allowed)
			(pads allowed)
			(copperpour allowed)
			(footprints allowed)
		)
		(placement
			(enabled no)
			(sheetname "")
		)
		(fill
			(thermal_gap 0.5)
			(thermal_bridge_width 0.5)
			(island_removal_mode 0)
		)
		(polygon
			(pts
				(xy 447.068448 -129.097278) (xy 444.884048 -129.097278) (xy 444.884048 -128.030478) (xy 447.068448 -128.030478)
			)
		)
	)
	(zone
		(layer "Cmts.User")
		(hatch none 0.5)
		(connect_pads
			(clearance 0)
		)
		(min_thickness 0.25)
		(keepout
			(tracks allowed)
			(vias allowed)
			(pads allowed)
			(copperpour allowed)
			(footprints allowed)
		)
		(placement
			(enabled no)
			(sheetname "")
		)
		(fill
			(thermal_gap 0.5)
			(thermal_bridge_width 0.5)
			(island_removal_mode 0)
		)
		(polygon
			(pts
				(xy 450.662548 -17.907254) (xy 448.478148 -17.907254) (xy 448.478148 -16.840454) (xy 450.662548 -16.840454)
			)
		)
	)
	(zone
		(layer "Cmts.User")
		(hatch none 0.5)
		(connect_pads
			(clearance 0)
		)
		(min_thickness 0.25)
		(keepout
			(tracks allowed)
			(vias allowed)
			(pads allowed)
			(copperpour allowed)
			(footprints allowed)
		)
		(placement
			(enabled no)
			(sheetname "")
		)
		(fill
			(thermal_gap 0.5)
			(thermal_bridge_width 0.5)
			(island_removal_mode 0)
		)
		(polygon
			(pts
				(xy 324.462648 -17.907254) (xy 322.278248 -17.907254) (xy 322.278248 -16.840454) (xy 324.462648 -16.840454)
			)
		)
	)
	(zone
		(layer "Cmts.User")
		(hatch none 0.5)
		(connect_pads
			(clearance 0)
		)
		(min_thickness 0.25)
		(keepout
			(tracks allowed)
			(vias allowed)
			(pads allowed)
			(copperpour allowed)
			(footprints allowed)
		)
		(placement
			(enabled no)
			(sheetname "")
		)
		(fill
			(thermal_gap 0.5)
			(thermal_bridge_width 0.5)
			(island_removal_mode 0)
		)
		(polygon
			(pts
				(xy 189.7888 -134.896098) (xy 189.7888 -132.711698) (xy 190.8556 -132.711698) (xy 190.8556 -134.896098)
			)
		)
	)
	(zone
		(layer "Cmts.User")
		(hatch none 0.5)
		(connect_pads
			(clearance 0)
		)
		(min_thickness 0.25)
		(keepout
			(tracks allowed)
			(vias allowed)
			(pads allowed)
			(copperpour allowed)
			(footprints allowed)
		)
		(placement
			(enabled no)
			(sheetname "")
		)
		(fill
			(thermal_gap 0.5)
			(thermal_bridge_width 0.5)
			(island_removal_mode 0)
		)
		(polygon
			(pts
				(xy 209.47126 -64.58966) (xy 223.63176 -64.58966) (xy 223.63176 -80.47736) (xy 209.47126 -80.47736)
			)
		)
	)
	(zone
		(layer "Cmts.User")
		(hatch none 0.5)
		(connect_pads
			(clearance 0)
		)
		(min_thickness 0.25)
		(keepout
			(tracks allowed)
			(vias allowed)
			(pads allowed)
			(copperpour allowed)
			(footprints allowed)
		)
		(placement
			(enabled no)
			(sheetname "")
		)
		(fill
			(thermal_gap 0.5)
			(thermal_bridge_width 0.5)
			(island_removal_mode 0)
		)
		(polygon
			(pts
				(xy 65.128648 -16.0274) (xy 65.128648 -13.843) (xy 66.195448 -13.843) (xy 66.195448 -16.0274)
			)
		)
	)
	(zone
		(layer "Cmts.User")
		(hatch none 0.5)
		(connect_pads
			(clearance 0)
		)
		(min_thickness 0.25)
		(keepout
			(tracks allowed)
			(vias allowed)
			(pads allowed)
			(copperpour allowed)
			(footprints allowed)
		)
		(placement
			(enabled no)
			(sheetname "")
		)
		(fill
			(thermal_gap 0.5)
			(thermal_bridge_width 0.5)
			(island_removal_mode 0)
		)
		(polygon
			(pts
				(xy 158.238698 -134.896098) (xy 158.238698 -132.711698) (xy 159.305498 -132.711698) (xy 159.305498 -134.896098)
			)
		)
	)
	(zone
		(layer "Cmts.User")
		(hatch none 0.5)
		(connect_pads
			(clearance 0)
		)
		(min_thickness 0.25)
		(keepout
			(tracks allowed)
			(vias allowed)
			(pads allowed)
			(copperpour allowed)
			(footprints allowed)
		)
		(placement
			(enabled no)
			(sheetname "")
		)
		(fill
			(thermal_gap 0.5)
			(thermal_bridge_width 0.5)
			(island_removal_mode 0)
		)
		(polygon
			(pts
				(xy 320.868548 -14.097254) (xy 318.684148 -14.097254) (xy 318.684148 -13.030454) (xy 320.868548 -13.030454)
			)
		)
	)
	(zone
		(layer "Cmts.User")
		(hatch none 0.5)
		(connect_pads
			(clearance 0)
		)
		(min_thickness 0.25)
		(keepout
			(tracks allowed)
			(vias allowed)
			(pads allowed)
			(copperpour allowed)
			(footprints allowed)
		)
		(placement
			(enabled no)
			(sheetname "")
		)
		(fill
			(thermal_gap 0.5)
			(thermal_bridge_width 0.5)
			(island_removal_mode 0)
		)
		(polygon
			(pts
				(xy 33.5788 -131.027424) (xy 33.5788 -128.843024) (xy 34.6456 -128.843024) (xy 34.6456 -131.027424)
			)
		)
	)
	(zone
		(layer "Cmts.User")
		(hatch none 0.5)
		(connect_pads
			(clearance 0)
		)
		(min_thickness 0.25)
		(keepout
			(tracks allowed)
			(vias allowed)
			(pads allowed)
			(copperpour allowed)
			(footprints allowed)
		)
		(placement
			(enabled no)
			(sheetname "")
		)
		(fill
			(thermal_gap 0.5)
			(thermal_bridge_width 0.5)
			(island_removal_mode 0)
		)
		(polygon
			(pts
				(xy 63.588646 -19.896074) (xy 63.588646 -17.711674) (xy 64.655446 -17.711674) (xy 64.655446 -19.896074)
			)
		)
	)
	(zone
		(layer "Cmts.User")
		(hatch none 0.5)
		(connect_pads
			(clearance 0)
		)
		(min_thickness 0.25)
		(keepout
			(tracks allowed)
			(vias allowed)
			(pads allowed)
			(copperpour allowed)
			(footprints allowed)
		)
		(placement
			(enabled no)
			(sheetname "")
		)
		(fill
			(thermal_gap 0.5)
			(thermal_bridge_width 0.5)
			(island_removal_mode 0)
		)
		(polygon
			(pts
				(xy 95.138748 -134.896098) (xy 95.138748 -132.711698) (xy 96.205548 -132.711698) (xy 96.205548 -134.896098)
			)
		)
	)
	(zone
		(layer "Cmts.User")
		(hatch none 0.5)
		(connect_pads
			(clearance 0)
		)
		(min_thickness 0.25)
		(keepout
			(tracks allowed)
			(vias allowed)
			(pads allowed)
			(copperpour allowed)
			(footprints allowed)
		)
		(placement
			(enabled no)
			(sheetname "")
		)
		(fill
			(thermal_gap 0.5)
			(thermal_bridge_width 0.5)
			(island_removal_mode 0)
		)
		(polygon
			(pts
				(xy 95.138748 -19.896074) (xy 95.138748 -17.711674) (xy 96.205548 -17.711674) (xy 96.205548 -19.896074)
			)
		)
	)
	(zone
		(layer "Cmts.User")
		(hatch none 0.5)
		(connect_pads
			(clearance 0)
		)
		(min_thickness 0.25)
		(keepout
			(tracks allowed)
			(vias allowed)
			(pads allowed)
			(copperpour allowed)
			(footprints allowed)
		)
		(placement
			(enabled no)
			(sheetname "")
		)
		(fill
			(thermal_gap 0.5)
			(thermal_bridge_width 0.5)
			(island_removal_mode 0)
		)
		(polygon
			(pts
				(xy 128.228598 -131.027424) (xy 128.228598 -128.843024) (xy 129.295398 -128.843024) (xy 129.295398 -131.027424)
			)
		)
	)
	(zone
		(layer "Cmts.User")
		(hatch none 0.5)
		(connect_pads
			(clearance 0)
		)
		(min_thickness 0.25)
		(keepout
			(tracks allowed)
			(vias allowed)
			(pads allowed)
			(copperpour allowed)
			(footprints allowed)
		)
		(placement
			(enabled no)
			(sheetname "")
		)
		(fill
			(thermal_gap 0.5)
			(thermal_bridge_width 0.5)
			(island_removal_mode 0)
		)
		(polygon
			(pts
				(xy 126.688596 -134.896098) (xy 126.688596 -132.711698) (xy 127.755396 -132.711698) (xy 127.755396 -134.896098)
			)
		)
	)
	(zone
		(layer "Cmts.User")
		(hatch none 0.5)
		(connect_pads
			(clearance 0)
		)
		(min_thickness 0.25)
		(keepout
			(tracks allowed)
			(vias allowed)
			(pads allowed)
			(copperpour allowed)
			(footprints allowed)
		)
		(placement
			(enabled no)
			(sheetname "")
		)
		(fill
			(thermal_gap 0.5)
			(thermal_bridge_width 0.5)
			(island_removal_mode 0)
		)
		(polygon
			(pts
				(xy 387.562598 -17.907254) (xy 385.378198 -17.907254) (xy 385.378198 -16.840454) (xy 387.562598 -16.840454)
			)
		)
	)
	(zone
		(layer "Cmts.User")
		(hatch none 0.5)
		(connect_pads
			(clearance 0)
		)
		(min_thickness 0.25)
		(keepout
			(tracks allowed)
			(vias allowed)
			(pads allowed)
			(copperpour allowed)
			(footprints allowed)
		)
		(placement
			(enabled no)
			(sheetname "")
		)
		(fill
			(thermal_gap 0.5)
			(thermal_bridge_width 0.5)
			(island_removal_mode 0)
		)
		(polygon
			(pts
				(xy 276.75586 -131.54406) (xy 288.8742 -131.54406) (xy 288.8742 -145.1864) (xy 276.75586 -145.1864)
			)
		)
	)
	(zone
		(layer "Cmts.User")
		(hatch none 0.5)
		(connect_pads
			(clearance 0)
		)
		(min_thickness 0.25)
		(keepout
			(tracks allowed)
			(vias allowed)
			(pads allowed)
			(copperpour allowed)
			(footprints allowed)
		)
		(placement
			(enabled no)
			(sheetname "")
		)
		(fill
			(thermal_gap 0.5)
			(thermal_bridge_width 0.5)
			(island_removal_mode 0)
		)
		(polygon
			(pts
				(xy 32.038798 -134.896098) (xy 32.038798 -132.711698) (xy 33.105598 -132.711698) (xy 33.105598 -134.896098)
			)
		)
	)
	(zone
		(layer "Cmts.User")
		(hatch none 0.5)
		(connect_pads
			(clearance 0)
		)
		(min_thickness 0.25)
		(keepout
			(tracks allowed)
			(vias allowed)
			(pads allowed)
			(copperpour allowed)
			(footprints allowed)
		)
		(placement
			(enabled no)
			(sheetname "")
		)
		(fill
			(thermal_gap 0.5)
			(thermal_bridge_width 0.5)
			(island_removal_mode 0)
		)
		(polygon
			(pts
				(xy 482.21265 -17.907254) (xy 480.02825 -17.907254) (xy 480.02825 -16.840454) (xy 482.21265 -16.840454)
			)
		)
	)
	(zone
		(layer "Cmts.User")
		(hatch none 0.5)
		(connect_pads
			(clearance 0)
		)
		(min_thickness 0.25)
		(keepout
			(tracks allowed)
			(vias allowed)
			(pads allowed)
			(copperpour allowed)
			(footprints allowed)
		)
		(placement
			(enabled no)
			(sheetname "")
		)
		(fill
			(thermal_gap 0.5)
			(thermal_bridge_width 0.5)
			(island_removal_mode 0)
		)
		(polygon
			(pts
				(xy 352.41865 -14.097254) (xy 350.23425 -14.097254) (xy 350.23425 -13.030454) (xy 352.41865 -13.030454)
			)
		)
	)
	(zone
		(layer "Cmts.User")
		(hatch none 0.5)
		(connect_pads
			(clearance 0)
		)
		(min_thickness 0.25)
		(keepout
			(tracks allowed)
			(vias allowed)
			(pads allowed)
			(copperpour allowed)
			(footprints allowed)
		)
		(placement
			(enabled no)
			(sheetname "")
		)
		(fill
			(thermal_gap 0.5)
			(thermal_bridge_width 0.5)
			(island_removal_mode 0)
		)
		(polygon
			(pts
				(xy 65.128648 -131.027424) (xy 65.128648 -128.843024) (xy 66.195448 -128.843024) (xy 66.195448 -131.027424)
			)
		)
	)
	(zone
		(layer "Cmts.User")
		(hatch none 0.5)
		(connect_pads
			(clearance 0)
		)
		(min_thickness 0.25)
		(keepout
			(tracks allowed)
			(vias allowed)
			(pads allowed)
			(copperpour allowed)
			(footprints allowed)
		)
		(placement
			(enabled no)
			(sheetname "")
		)
		(fill
			(thermal_gap 0.5)
			(thermal_bridge_width 0.5)
			(island_removal_mode 0)
		)
		(polygon
			(pts
				(xy 324.462648 -132.907278) (xy 322.278248 -132.907278) (xy 322.278248 -131.840478) (xy 324.462648 -131.840478)
			)
		)
	)
	(zone
		(layer "Cmts.User")
		(hatch none 0.5)
		(connect_pads
			(clearance 0)
		)
		(min_thickness 0.25)
		(keepout
			(tracks allowed)
			(vias allowed)
			(pads allowed)
			(copperpour allowed)
			(footprints allowed)
		)
		(placement
			(enabled no)
			(sheetname "")
		)
		(fill
			(thermal_gap 0.5)
			(thermal_bridge_width 0.5)
			(island_removal_mode 0)
		)
		(polygon
			(pts
				(xy 383.968498 -129.097278) (xy 381.784098 -129.097278) (xy 381.784098 -128.030478) (xy 383.968498 -128.030478)
			)
		)
	)
	(zone
		(layer "Cmts.User")
		(hatch none 0.5)
		(connect_pads
			(clearance 0)
		)
		(min_thickness 0.25)
		(keepout
			(tracks allowed)
			(vias allowed)
			(pads allowed)
			(copperpour allowed)
			(footprints allowed)
		)
		(placement
			(enabled no)
			(sheetname "")
		)
		(fill
			(thermal_gap 0.5)
			(thermal_bridge_width 0.5)
			(island_removal_mode 0)
		)
		(polygon
			(pts
				(xy 288.24682 -175.30826) (xy 288.24682 -239.04448) (xy 276.93874 -239.04448) (xy 276.93874 -175.30826)
			)
		)
	)
	(zone
		(layer "Cmts.User")
		(hatch none 0.5)
		(connect_pads
			(clearance 0)
		)
		(min_thickness 0.25)
		(keepout
			(tracks allowed)
			(vias allowed)
			(pads allowed)
			(copperpour allowed)
			(footprints allowed)
		)
		(placement
			(enabled no)
			(sheetname "")
		)
		(fill
			(thermal_gap 0.5)
			(thermal_bridge_width 0.5)
			(island_removal_mode 0)
		)
		(polygon
			(pts
				(xy 126.688596 -19.896074) (xy 126.688596 -17.711674) (xy 127.755396 -17.711674) (xy 127.755396 -19.896074)
			)
		)
	)
	(zone
		(layer "Cmts.User")
		(hatch none 0.5)
		(connect_pads
			(clearance 0)
		)
		(min_thickness 0.25)
		(keepout
			(tracks allowed)
			(vias allowed)
			(pads allowed)
			(copperpour allowed)
			(footprints allowed)
		)
		(placement
			(enabled no)
			(sheetname "")
		)
		(fill
			(thermal_gap 0.5)
			(thermal_bridge_width 0.5)
			(island_removal_mode 0)
		)
		(polygon
			(pts
				(xy 356.01275 -132.907278) (xy 353.82835 -132.907278) (xy 353.82835 -131.840478) (xy 356.01275 -131.840478)
			)
		)
	)
	(zone
		(layer "Cmts.User")
		(hatch none 0.5)
		(connect_pads
			(clearance 0)
		)
		(min_thickness 0.25)
		(keepout
			(tracks allowed)
			(vias allowed)
			(pads allowed)
			(copperpour allowed)
			(footprints allowed)
		)
		(placement
			(enabled no)
			(sheetname "")
		)
		(fill
			(thermal_gap 0.5)
			(thermal_bridge_width 0.5)
			(island_removal_mode 0)
		)
		(polygon
			(pts
				(xy 419.1127 -17.907254) (xy 416.9283 -17.907254) (xy 416.9283 -16.840454) (xy 419.1127 -16.840454)
			)
		)
	)
	(zone
		(layer "Cmts.User")
		(hatch none 0.5)
		(connect_pads
			(clearance 0)
		)
		(min_thickness 0.25)
		(keepout
			(tracks allowed)
			(vias allowed)
			(pads allowed)
			(copperpour allowed)
			(footprints allowed)
		)
		(placement
			(enabled no)
			(sheetname "")
		)
		(fill
			(thermal_gap 0.5)
			(thermal_bridge_width 0.5)
			(island_removal_mode 0)
		)
		(polygon
			(pts
				(xy 450.662548 -132.907278) (xy 448.478148 -132.907278) (xy 448.478148 -131.840478) (xy 450.662548 -131.840478)
			)
		)
	)
	(zone
		(layer "Cmts.User")
		(hatch none 0.5)
		(connect_pads
			(clearance 0)
		)
		(min_thickness 0.25)
		(keepout
			(tracks allowed)
			(vias allowed)
			(pads allowed)
			(copperpour allowed)
			(footprints allowed)
		)
		(placement
			(enabled no)
			(sheetname "")
		)
		(fill
			(thermal_gap 0.5)
			(thermal_bridge_width 0.5)
			(island_removal_mode 0)
		)
		(polygon
			(pts
				(xy 320.868548 -129.097278) (xy 318.684148 -129.097278) (xy 318.684148 -128.030478) (xy 320.868548 -128.030478)
			)
		)
	)
	(zone
		(layer "Cmts.User")
		(hatch none 0.5)
		(connect_pads
			(clearance 0)
		)
		(min_thickness 0.25)
		(keepout
			(tracks allowed)
			(vias allowed)
			(pads allowed)
			(copperpour allowed)
			(footprints allowed)
		)
		(placement
			(enabled no)
			(sheetname "")
		)
		(fill
			(thermal_gap 0.5)
			(thermal_bridge_width 0.5)
			(island_removal_mode 0)
		)
		(polygon
			(pts
				(xy 96.67875 -131.027424) (xy 96.67875 -128.843024) (xy 97.74555 -128.843024) (xy 97.74555 -131.027424)
			)
		)
	)
	(zone
		(layer "Cmts.User")
		(hatch none 0.5)
		(connect_pads
			(clearance 0)
		)
		(min_thickness 0.25)
		(keepout
			(tracks allowed)
			(vias allowed)
			(pads allowed)
			(copperpour allowed)
			(footprints allowed)
		)
		(placement
			(enabled no)
			(sheetname "")
		)
		(fill
			(thermal_gap 0.5)
			(thermal_bridge_width 0.5)
			(island_removal_mode 0)
		)
		(polygon
			(pts
				(xy 415.5186 -14.097254) (xy 413.3342 -14.097254) (xy 413.3342 -13.030454) (xy 415.5186 -13.030454)
			)
		)
	)
	(zone
		(layer "Cmts.User")
		(hatch none 0.5)
		(connect_pads
			(clearance 0)
		)
		(min_thickness 0.25)
		(keepout
			(tracks allowed)
			(vias allowed)
			(pads allowed)
			(copperpour allowed)
			(footprints allowed)
		)
		(placement
			(enabled no)
			(sheetname "")
		)
		(fill
			(thermal_gap 0.5)
			(thermal_bridge_width 0.5)
			(island_removal_mode 0)
		)
		(polygon
			(pts
				(xy 158.238698 -19.896074) (xy 158.238698 -17.711674) (xy 159.305498 -17.711674) (xy 159.305498 -19.896074)
			)
		)
	)
	(zone
		(layer "Cmts.User")
		(hatch none 0.5)
		(connect_pads
			(clearance 0)
		)
		(min_thickness 0.25)
		(keepout
			(tracks allowed)
			(vias allowed)
			(pads allowed)
			(copperpour allowed)
			(footprints allowed)
		)
		(placement
			(enabled no)
			(sheetname "")
		)
		(fill
			(thermal_gap 0.5)
			(thermal_bridge_width 0.5)
			(island_removal_mode 0)
		)
		(polygon
			(pts
				(xy 478.61855 -14.097254) (xy 476.43415 -14.097254) (xy 476.43415 -13.030454) (xy 478.61855 -13.030454)
			)
		)
	)
	(zone
		(layer "Cmts.User")
		(hatch none 0.5)
		(connect_pads
			(clearance 0)
		)
		(min_thickness 0.25)
		(keepout
			(tracks allowed)
			(vias allowed)
			(pads allowed)
			(copperpour allowed)
			(footprints allowed)
		)
		(placement
			(enabled no)
			(sheetname "")
		)
		(fill
			(thermal_gap 0.5)
			(thermal_bridge_width 0.5)
			(island_removal_mode 0)
		)
		(polygon
			(pts
				(xy 383.968498 -14.097254) (xy 381.784098 -14.097254) (xy 381.784098 -13.030454) (xy 383.968498 -13.030454)
			)
		)
	)
	(zone
		(layer "Cmts.User")
		(hatch none 0.5)
		(connect_pads
			(clearance 0)
		)
		(min_thickness 0.25)
		(keepout
			(tracks allowed)
			(vias allowed)
			(pads allowed)
			(copperpour allowed)
			(footprints allowed)
		)
		(placement
			(enabled no)
			(sheetname "")
		)
		(fill
			(thermal_gap 0.5)
			(thermal_bridge_width 0.5)
			(island_removal_mode 0)
		)
		(polygon
			(pts
				(xy 96.67875 -16.0274) (xy 96.67875 -13.843) (xy 97.74555 -13.843) (xy 97.74555 -16.0274)
			)
		)
	)
	(zone
		(layer "Cmts.User")
		(hatch none 0.5)
		(connect_pads
			(clearance 0)
		)
		(min_thickness 0.25)
		(keepout
			(tracks allowed)
			(vias allowed)
			(pads allowed)
			(copperpour allowed)
			(footprints allowed)
		)
		(placement
			(enabled no)
			(sheetname "")
		)
		(fill
			(thermal_gap 0.5)
			(thermal_bridge_width 0.5)
			(island_removal_mode 0)
		)
		(polygon
			(pts
				(xy 415.5186 -129.097278) (xy 413.3342 -129.097278) (xy 413.3342 -128.030478) (xy 415.5186 -128.030478)
			)
		)
	)
	(zone
		(layer "Cmts.User")
		(hatch none 0.5)
		(connect_pads
			(clearance 0)
		)
		(min_thickness 0.25)
		(keepout
			(tracks allowed)
			(vias allowed)
			(pads allowed)
			(copperpour allowed)
			(footprints allowed)
		)
		(placement
			(enabled no)
			(sheetname "")
		)
		(fill
			(thermal_gap 0.5)
			(thermal_bridge_width 0.5)
			(island_removal_mode 0)
		)
		(polygon
			(pts
				(xy 231.88168 -79.7941) (xy 231.88168 -64.07912) (xy 226.10318 -64.07912) (xy 226.10318 -79.7941)
			)
		)
	)
)
